BODY ORDERED NET LIST - 1  
BT1              CONN2_AAABAT029P15-CONN2_AAA-BA 1        P3V_BAT                 
                                  2        GND                     
C1               Q_CAP_C0402-10UF,6.3V,20%,X6S,A 1        P3V3_AUX                
                                  2        GND                     
C2               Q_CAP_C0402-2.2UF,6.3V,20%,X6SA 1        P3V3_AUX                
                                  2        GND                     
C3               Q_CAP_C0805-10UF,16V,10%,X7R,CA 1        P12V_S3_AUX_CPU0_NVDIMM 
                                  2        GND                     
C4               Q_CAP_C0805-10UF,16V,10%,X7R,CA 1        P12V_S3_AUX_CPU0_NVDIMM 
                                  2        GND                     
C5               Q_CAP_C0402-2.2UF,6.3V,20%,X6SA 1        P3V3_AUX                
                                  2        GND                     
C6               Q_CAP_C0805-10UF,16V,10%,X7R,CA 1        P12V_S3_AUX_CPU0_NVDIMM 
                                  2        GND                     
C7               Q_CAP_C0805-10UF,16V,10%,X7R,CA 1        P12V_S3_AUX_CPU0_NVDIMM 
                                  2        GND                     
C8               Q_CAP_C0402-2.2UF,6.3V,20%,X6SA 1        P3V3_AUX                
                                  2        GND                     
C9               Q_CAP_C0805-10UF,16V,10%,X7R,CA 1        P12V_S3_AUX_CPU0_NVDIMM 
                                  2        GND                     
C10              Q_CAP_C0805-10UF,16V,10%,X7R,CA 1        P12V_S3_AUX_CPU0_NVDIMM 
                                  2        GND                     
C11              Q_CAP_C0402-2.2UF,6.3V,20%,X6SA 1        P3V3_AUX                
                                  2        GND                     
C12              Q_CAP_C0805-10UF,16V,10%,X7R,CA 1        P12V_S3_AUX_CPU0_NVDIMM 
                                  2        GND                     
C13              Q_CAP_C0805-10UF,16V,10%,X7R,CA 1        P12V_S3_AUX_CPU0_NVDIMM 
                                  2        GND                     
C14              Q_CAP_C0402-2.2UF,6.3V,20%,X6SA 1        P3V3_AUX                
                                  2        GND                     
C15              Q_CAP_C0805-10UF,16V,10%,X7R,CA 1        P12V_S3_AUX_CPU0_NVDIMM 
                                  2        GND                     
C16              Q_CAP_C0805-10UF,16V,10%,X7R,CA 1        P12V_S3_AUX_CPU0_NVDIMM 
                                  2        GND                     
C17              Q_CAP_C0402-2.2UF,6.3V,20%,X6SA 1        P3V3_AUX                
                                  2        GND                     
C18              Q_CAP_C0805-10UF,16V,10%,X7R,CA 1        P12V_S3_AUX_CPU0_NVDIMM 
                                  2        GND                     
C19              Q_CAP_C0805-10UF,16V,10%,X7R,CA 1        P12V_S3_AUX_CPU0_NVDIMM 
                                  2        GND                     
C20              Q_CAP_C0402-2.2UF,6.3V,20%,X6SA 1        P3V3_AUX                
                                  2        GND                     
C21              Q_CAP_C0805-10UF,16V,10%,X7R,CA 1        P12V_S3_AUX_CPU0_NVDIMM 
                                  2        GND                     
C22              Q_CAP_C0805-10UF,16V,10%,X7R,CA 1        P12V_S3_AUX_CPU0_NVDIMM 
                                  2        GND                     
C23              Q_CAP_C0402-2.2UF,6.3V,20%,X6SA 1        P3V3_AUX                
                                  2        GND                     
C24              Q_CAP_C0805-10UF,16V,10%,X7R,CA 1        P12V_S3_AUX_CPU0_NVDIMM 
                                  2        GND                     
C25              Q_CAP_C0805-22UF,16V,20%,X6S,CA 1        P12V_S3_AUX_CPU0_NVDIMM 
                                  2        GND                     
C26              Q_CAP_C0402-2.2UF,6.3V,20%,X6SA 1        P3V3_AUX                
                                  2        GND                     
C27              Q_CAP_C0805-10UF,16V,10%,X7R,CA 1        P12V_S3_AUX_CPU0_NVDIMM 
                                  2        GND                     
C28              Q_CAP_C0805-10UF,16V,10%,X7R,CA 1        P12V_S3_AUX_CPU0_NVDIMM 
                                  2        GND                     
C29              Q_CAP_C0402-2.2UF,6.3V,20%,X6SA 1        P3V3_AUX                
                                  2        GND                     
C30              Q_CAP_C0805-10UF,16V,10%,X7R,CA 1        P12V_S3_AUX_CPU0_NVDIMM 
                                  2        GND                     
C31              Q_CAP_C0805-10UF,16V,10%,X7R,CA 1        P12V_S3_AUX_CPU0_NVDIMM 
                                  2        GND                     
C32              Q_CAP_C0402-2.2UF,6.3V,20%,X6SA 1        P3V3_AUX                
                                  2        GND                     
C33              Q_CAP_C0805-10UF,16V,10%,X7R,CA 1        P12V_S3_AUX_CPU0_NVDIMM 
                                  2        GND                     
C34              Q_CAP_C0805-10UF,16V,10%,X7R,CA 1        P12V_S3_AUX_CPU0_NVDIMM 
                                  2        GND                     
C35              Q_CAP_C0402-2.2UF,6.3V,20%,X6SA 1        P3V3_AUX                
                                  2        GND                     
C36              Q_CAP_C0805-10UF,16V,10%,X7R,CA 1        P12V_S3_AUX_CPU0_NVDIMM 
                                  2        GND                     
C37              Q_CAP_C0805-10UF,16V,10%,X7R,CA 1        P12V_S3_AUX_CPU0_NVDIMM 
                                  2        GND                     
C38              Q_CAP_C0402-2.2UF,6.3V,20%,X6SA 1        P3V3_AUX                
                                  2        GND                     
C39              Q_CAP_C0805-10UF,16V,10%,X7R,CA 1        P12V_S3_AUX_CPU0_NVDIMM 
                                  2        GND                     
C40              Q_CAP_C0805-10UF,16V,10%,X7R,CA 1        P12V_S3_AUX_CPU0_NVDIMM 
                                  2        GND                     
C41              Q_CAP_C0402-2.2UF,6.3V,20%,X6SA 1        P3V3_AUX                
                                  2        GND                     
C42              Q_CAP_C0805-10UF,16V,10%,X7R,CA 1        P12V_S3_AUX_CPU0_NVDIMM 
                                  2        GND                     
C43              Q_CAP_C0805-10UF,16V,10%,X7R,CA 1        P12V_S3_AUX_CPU0_NVDIMM 
                                  2        GND                     
C44              Q_CAP_C0402-2.2UF,6.3V,20%,X6SA 1        P3V3_AUX                
                                  2        GND                     
C45              Q_CAP_C0805-10UF,16V,10%,X7R,CA 1        P12V_S3_AUX_CPU0_NVDIMM 
                                  2        GND                     
C46              Q_CAP_C0805-10UF,16V,10%,X7R,CA 1        P12V_S3_AUX_CPU0_NVDIMM 
                                  2        GND                     
C47              Q_CAP_C0402-2.2UF,6.3V,20%,X6SA 1        P3V3_AUX                
                                  2        GND                     
C48              Q_CAP_C0805-10UF,16V,10%,X7R,CA 1        P12V_S3_AUX_CPU0_NVDIMM 
                                  2        GND                     
C49              Q_CAP_C0805-10UF,16V,10%,X7R,CA 1        P12V_S3_AUX_CPU0_NVDIMM 
                                  2        GND                     
C50              Q_CAP_C0402-2.2UF,6.3V,20%,X6SA 1        P3V3_AUX                
                                  2        GND                     
C51              Q_CAP_C0805-10UF,16V,10%,X7R,CA 1        P12V_S3_AUX_CPU1_NVDIMM 
                                  2        GND                     
C52              Q_CAP_C0805-10UF,16V,10%,X7R,CA 1        P12V_S3_AUX_CPU1_NVDIMM 
                                  2        GND                     
C53              Q_CAP_C0402-2.2UF,6.3V,20%,X6SA 1        P3V3_AUX                
                                  2        GND                     
C54              Q_CAP_C0805-10UF,16V,10%,X7R,CA 1        P12V_S3_AUX_CPU1_NVDIMM 
                                  2        GND                     
C55              Q_CAP_C0805-10UF,16V,10%,X7R,CA 1        P12V_S3_AUX_CPU1_NVDIMM 
                                  2        GND                     
C56              Q_CAP_C0402-2.2UF,6.3V,20%,X6SA 1        P3V3_AUX                
                                  2        GND                     
C57              Q_CAP_C0805-10UF,16V,10%,X7R,CA 1        P12V_S3_AUX_CPU1_NVDIMM 
                                  2        GND                     
C58              Q_CAP_C0805-10UF,16V,10%,X7R,CA 1        P12V_S3_AUX_CPU1_NVDIMM 
                                  2        GND                     
C59              Q_CAP_C0402-2.2UF,6.3V,20%,X6SA 1        P3V3_AUX                
                                  2        GND                     
C60              Q_CAP_C0805-10UF,16V,10%,X7R,CA 1        P12V_S3_AUX_CPU1_NVDIMM 
                                  2        GND                     
C61              Q_CAP_C0805-10UF,16V,10%,X7R,CA 1        P12V_S3_AUX_CPU1_NVDIMM 
                                  2        GND                     
C62              Q_CAP_C0402-2.2UF,6.3V,20%,X6SA 1        P3V3_AUX                
                                  2        GND                     
C63              Q_CAP_C0805-10UF,16V,10%,X7R,CA 1        P12V_S3_AUX_CPU1_NVDIMM 
                                  2        GND                     
C64              Q_CAP_C0805-10UF,16V,10%,X7R,CA 1        P12V_S3_AUX_CPU1_NVDIMM 
                                  2        GND                     
C65              Q_CAP_C0402-2.2UF,6.3V,20%,X6SA 1        P3V3_AUX                
                                  2        GND                     
C66              Q_CAP_C0805-10UF,16V,10%,X7R,CA 1        P12V_S3_AUX_CPU1_NVDIMM 
                                  2        GND                     
C67              Q_CAP_C0805-10UF,16V,10%,X7R,CA 1        P12V_S3_AUX_CPU1_NVDIMM 
                                  2        GND                     
C68              Q_CAP_C0402-2.2UF,6.3V,20%,X6SA 1        P3V3_AUX                
                                  2        GND                     
C69              Q_CAP_C0805-10UF,16V,10%,X7R,CA 1        P12V_S3_AUX_CPU1_NVDIMM 
                                  2        GND                     
C70              Q_CAP_C0805-10UF,16V,10%,X7R,CA 1        P12V_S3_AUX_CPU1_NVDIMM 
                                  2        GND                     
C71              Q_CAP_C0402-10UF,6.3V,20%,X6S,A 1        P3V3_AUX                
                                  2        GND                     
C72              Q_CAP_C0402-2.2UF,6.3V,20%,X6SA 1        P3V3_AUX                
                                  2        GND                     
C73              Q_CAP_C0805-10UF,16V,10%,X7R,CA 1        P12V_S3_AUX_CPU1_NVDIMM 
                                  2        GND                     
C74              Q_CAP_C0805-10UF,16V,10%,X7R,CA 1        P12V_S3_AUX_CPU1_NVDIMM 
                                  2        GND                     
C75              Q_CAP_C0402-2.2UF,6.3V,20%,X6SA 1        P3V3_AUX                
                                  2        GND                     
C76              Q_CAP_C0805-10UF,16V,10%,X7R,CA 1        P12V_S3_AUX_CPU1_NVDIMM 
                                  2        GND                     
C77              Q_CAP_C0805-10UF,16V,10%,X7R,CA 1        P12V_S3_AUX_CPU1_NVDIMM 
                                  2        GND                     
C78              Q_CAP_C0402-2.2UF,6.3V,20%,X6SA 1        P3V3_AUX                
                                  2        GND                     
C79              Q_CAP_C0805-10UF,16V,10%,X7R,CA 1        P12V_S3_AUX_CPU1_NVDIMM 
                                  2        GND                     
C80              Q_CAP_C0805-10UF,16V,10%,X7R,CA 1        P12V_S3_AUX_CPU1_NVDIMM 
                                  2        GND                     
C81              Q_CAP_C0402-2.2UF,6.3V,20%,X6SA 1        P3V3_AUX                
                                  2        GND                     
C82              Q_CAP_C0805-10UF,16V,10%,X7R,CA 1        P12V_S3_AUX_CPU1_NVDIMM 
                                  2        GND                     
C83              Q_CAP_C0805-10UF,16V,10%,X7R,CA 1        P12V_S3_AUX_CPU1_NVDIMM 
                                  2        GND                     
C84              Q_CAP_C0402-2.2UF,6.3V,20%,X6SA 1        P3V3_AUX                
                                  2        GND                     
C85              Q_CAP_C0805-10UF,16V,10%,X7R,CA 1        P12V_S3_AUX_CPU1_NVDIMM 
                                  2        GND                     
C86              Q_CAP_C0805-10UF,16V,10%,X7R,CA 1        P12V_S3_AUX_CPU1_NVDIMM 
                                  2        GND                     
C87              Q_CAP_C0402-2.2UF,6.3V,20%,X6SA 1        P3V3_AUX                
                                  2        GND                     
C88              Q_CAP_C0805-10UF,16V,10%,X7R,CA 1        P12V_S3_AUX_CPU1_NVDIMM 
                                  2        GND                     
C89              Q_CAP_C0805-10UF,16V,10%,X7R,CA 1        P12V_S3_AUX_CPU1_NVDIMM 
                                  2        GND                     
C90              Q_CAP_C0402-2.2UF,6.3V,20%,X6SA 1        P3V3_AUX                
                                  2        GND                     
C91              Q_CAP_C0805-10UF,16V,10%,X7R,CA 1        P12V_S3_AUX_CPU1_NVDIMM 
                                  2        GND                     
C92              Q_CAP_C0805-10UF,16V,10%,X7R,CA 1        P12V_S3_AUX_CPU1_NVDIMM 
                                  2        GND                     
C93              Q_CAP_C0402-2.2UF,6.3V,20%,X6SA 1        P3V3_AUX                
                                  2        GND                     
C94              Q_CAP_C0805-10UF,16V,10%,X7R,CA 1        P12V_S3_AUX_CPU1_NVDIMM 
                                  2        GND                     
C95              Q_CAP_C0805-10UF,16V,10%,X7R,CA 1        P12V_S3_AUX_CPU1_NVDIMM 
                                  2        GND                     
C96              Q_CAP_C0402-2.2UF,6.3V,20%,X6SA 1        P3V3_AUX                
                                  2        GND                     
C97              Q_CAP_C0805-10UF,16V,10%,X7R,CA 1        P12V_S3_AUX_CPU1_NVDIMM 
                                  2        GND                     
C98              Q_CAP_C0805-10UF,16V,10%,X7R,CA 1        P12V_S3_AUX_CPU1_NVDIMM 
                                  2        GND                     
C101             Q_CAP_0805-47UF,4V,20%,X6S,CH6A 1        PVCCIN_CPU0             
                                  2        GND                     
C103             Q_CAP_0402-27PF  ,50V ,5% ,EMPA 1        XTAL_PCH_25M_IN_R       
                                  2        GND                     
C104             Q_CAP_0402-27PF  ,50V ,5% ,EMPA 1        XTAL_PCH_25M_OUT        
                                  2        GND                     
C108             Q_CAP_C0603-10UF,6.3V,20%,X6S,A 1        P3V3_AUX_CLK_GEN_VDD_CK440
                                  2        GND                     
C109             Q_CAP_C0402-1UF,25V,10%,X6S,CHA 1        P3V3_AUX_CLK_GEN_VDD_CK440
                                  2        GND                     
C110             Q_CAP_0402-0.1UF,25V,10%,X7R,CA 1        P3V3_AUX_CLK_GEN_VDD_CK440
                                  2        GND                     
C111             Q_CAP_0402-0.1UF,25V,10%,X7R,CA 1        P3V3_AUX_CLK_GEN_VDDXTAL_CK440
                                  2        GND                     
C112             Q_CAP_0402-0.1UF,25V,10%,X7R,CA 1        P3V3_AUX_CLK_GEN_VDDXTAL_CK440
                                  2        GND                     
C113             Q_CAP_0402-15PF,50V,5%,C0G,CH0A 1        XTAL_CLK_GEN1_25M_X1_R  
                                  2        GND                     
C114             Q_CAP_0402-0.1UF,25V,10%,X7R,CA 1        P3V3_AUX_CLK_GEN_VDDA25M_CK440
                                  2        GND                     
C115             Q_CAP_0402-0.1UF,25V,10%,X7R,CA 1        P3V3_AUX_CLK_GEN_VDDMXCK_CK440
                                  2        GND                     
C116             Q_CAP_0402-0.1UF,25V,10%,X7R,CA 1        P3V3_AUX_CLK_GEN_VDDMXCK_CK440
                                  2        GND                     
C117             Q_CAP_0402-0.1UF,25V,10%,X7R,CA 1        P3V3_AUX_CLK_GEN_VDDMXCK_CK440
                                  2        GND                     
C118             Q_CAP_0402-15PF,50V,5%,C0G,CH0A 1        XTAL_CLK_GEN1_25M_X2    
                                  2        GND                     
C119             Q_CAP_0402-0.1UF,25V,10%,X7R,CA 1        P3V3_AUX_CLK_GEN_VDDMXCK_CK440
                                  2        GND                     
C120             Q_CAP_0402-0.1UF,25V,10%,X7R,CA 1        P3V3_AUX_CLK_GEN_VDDPT_CK440
                                  2        GND                     
C127             Q_CAPP_RDLLF-270UF,16V,20%,OSCA 1        P12V_FRONT_CPU0         
                                  2        GND                     
C128             Q_CAP_0402-0.1UF,25V,10%,X7R,CA 1        P12V_FRONT_CPU0         
                                  2        GND                     
C129             Q_CAPP_SMLF-100UF,16V,20%,POSCA 1        P3V3                    
                                  2        GND                     
C130             Q_CAP_0402-0.1UF,25V,10%,X7R,CA 1        P3V3                    
                                  2        GND                     
C131             Q_CAP_C0402-1UF,25V,10%,X6S,CHA 1        P3V3_AUX                
                                  2        GND                     
C132             Q_CAP_0402-0.1UF,25V,10%,X7R,CA 1        P3V3_AUX                
                                  2        GND                     
C133             Q_CAPP_SMLF-100UF,16V,20%,POSCA 1        P12V_FRONT_CPU          
                                  2        GND                     
C134             Q_CAP_0402-0.1UF,25V,10%,X7R,CA 1        P12V_FRONT_CPU          
                                  2        GND                     
C135             Q_CAPP_SMLF-100UF,16V,20%,POSCA 1        P3V3                    
                                  2        GND                     
C136             Q_CAP_0402-0.1UF,25V,10%,X7R,CA 1        P3V3                    
                                  2        GND                     
C137             Q_CAP_C0402-1UF,25V,10%,X6S,CHA 1        P3V3_AUX                
                                  2        GND                     
C138             Q_CAP_0402-0.1UF,25V,10%,X7R,CA 1        P3V3_AUX                
                                  2        GND                     
C139             Q_CAP_DIFFBUS_C0201-DIFF BUS_0A 1        DMI_CPU0_PCH_TX_C_DN<7> 
                                  2        DMI_CPU0_PCH_TX_DN<7>   
C140             Q_CAP_DIFFBUS_C0201-DIFF BUS_0A 1        DMI_CPU0_PCH_TX_C_DP<7> 
                                  2        DMI_CPU0_PCH_TX_DP<7>   
C141             Q_CAP_DIFFBUS_C0201-DIFF BUS_0A 1        DMI_CPU0_PCH_TX_C_DN<6> 
                                  2        DMI_CPU0_PCH_TX_DN<6>   
C142             Q_CAP_DIFFBUS_C0201-DIFF BUS_0A 1        DMI_CPU0_PCH_TX_C_DP<6> 
                                  2        DMI_CPU0_PCH_TX_DP<6>   
C143             Q_CAP_DIFFBUS_C0201-DIFF BUS_0A 1        DMI_CPU0_PCH_TX_C_DN<5> 
                                  2        DMI_CPU0_PCH_TX_DN<5>   
C144             Q_CAP_DIFFBUS_C0201-DIFF BUS_0A 1        DMI_CPU0_PCH_TX_C_DP<5> 
                                  2        DMI_CPU0_PCH_TX_DP<5>   
C145             Q_CAP_DIFFBUS_C0201-DIFF BUS_0A 1        DMI_CPU0_PCH_TX_C_DN<4> 
                                  2        DMI_CPU0_PCH_TX_DN<4>   
C146             Q_CAP_DIFFBUS_C0201-DIFF BUS_0A 1        DMI_CPU0_PCH_TX_C_DP<4> 
                                  2        DMI_CPU0_PCH_TX_DP<4>   
C147             Q_CAP_DIFFBUS_C0201-DIFF BUS_0A 1        DMI_CPU0_PCH_TX_C_DN<3> 
                                  2        DMI_CPU0_PCH_TX_DN<3>   
C148             Q_CAP_DIFFBUS_C0201-DIFF BUS_0A 1        DMI_CPU0_PCH_TX_C_DP<3> 
                                  2        DMI_CPU0_PCH_TX_DP<3>   
C149             Q_CAP_DIFFBUS_C0201-DIFF BUS_0A 1        DMI_CPU0_PCH_TX_C_DN<2> 
                                  2        DMI_CPU0_PCH_TX_DN<2>   
C150             Q_CAP_DIFFBUS_C0201-DIFF BUS_0A 1        DMI_CPU0_PCH_TX_C_DP<2> 
                                  2        DMI_CPU0_PCH_TX_DP<2>   
C151             Q_CAP_DIFFBUS_C0201-DIFF BUS_0A 1        DMI_CPU0_PCH_TX_C_DN<1> 
                                  2        DMI_CPU0_PCH_TX_DN<1>   
C152             Q_CAP_DIFFBUS_C0201-DIFF BUS_0A 1        DMI_CPU0_PCH_TX_C_DP<1> 
                                  2        DMI_CPU0_PCH_TX_DP<1>   
C153             Q_CAP_DIFFBUS_C0201-DIFF BUS_0A 1        DMI_CPU0_PCH_TX_C_DN<0> 
                                  2        DMI_CPU0_PCH_TX_DN<0>   
C154             Q_CAP_DIFFBUS_C0201-DIFF BUS_0A 1        DMI_CPU0_PCH_TX_C_DP<0> 
                                  2        DMI_CPU0_PCH_TX_DP<0>   
C155             Q_CAP_DIFFBUS_C0201-DIFF BUS_0A 1        DMI_CPU0_PCH_RX_C_DN<7> 
                                  2        DMI_CPU0_PCH_RX_DN<7>   
C156             Q_CAP_DIFFBUS_C0201-DIFF BUS_0A 1        DMI_CPU0_PCH_RX_C_DP<7> 
                                  2        DMI_CPU0_PCH_RX_DP<7>   
C157             Q_CAP_DIFFBUS_C0201-DIFF BUS_0A 1        DMI_CPU0_PCH_RX_C_DN<6> 
                                  2        DMI_CPU0_PCH_RX_DN<6>   
C158             Q_CAP_DIFFBUS_C0201-DIFF BUS_0A 1        DMI_CPU0_PCH_RX_C_DP<6> 
                                  2        DMI_CPU0_PCH_RX_DP<6>   
C159             Q_CAP_DIFFBUS_C0201-DIFF BUS_0A 1        DMI_CPU0_PCH_RX_C_DN<5> 
                                  2        DMI_CPU0_PCH_RX_DN<5>   
C160             Q_CAP_DIFFBUS_C0201-DIFF BUS_0A 1        DMI_CPU0_PCH_RX_C_DP<5> 
                                  2        DMI_CPU0_PCH_RX_DP<5>   
C161             Q_CAP_DIFFBUS_C0201-DIFF BUS_0A 1        DMI_CPU0_PCH_RX_C_DN<4> 
                                  2        DMI_CPU0_PCH_RX_DN<4>   
C162             Q_CAP_DIFFBUS_C0201-DIFF BUS_0A 1        DMI_CPU0_PCH_RX_C_DP<4> 
                                  2        DMI_CPU0_PCH_RX_DP<4>   
C163             Q_CAP_DIFFBUS_C0201-DIFF BUS_0A 1        DMI_CPU0_PCH_RX_C_DN<3> 
                                  2        DMI_CPU0_PCH_RX_DN<3>   
C164             Q_CAP_DIFFBUS_C0201-DIFF BUS_0A 1        DMI_CPU0_PCH_RX_C_DP<3> 
                                  2        DMI_CPU0_PCH_RX_DP<3>   
C165             Q_CAP_DIFFBUS_C0201-DIFF BUS_0A 1        DMI_CPU0_PCH_RX_C_DN<2> 
                                  2        DMI_CPU0_PCH_RX_DN<2>   
C166             Q_CAP_DIFFBUS_C0201-DIFF BUS_0A 1        DMI_CPU0_PCH_RX_C_DP<2> 
                                  2        DMI_CPU0_PCH_RX_DP<2>   
C167             Q_CAP_DIFFBUS_C0201-DIFF BUS_0A 1        DMI_CPU0_PCH_RX_C_DN<1> 
                                  2        DMI_CPU0_PCH_RX_DN<1>   
C168             Q_CAP_DIFFBUS_C0201-DIFF BUS_0A 1        DMI_CPU0_PCH_RX_C_DP<1> 
                                  2        DMI_CPU0_PCH_RX_DP<1>   
C169             Q_CAP_DIFFBUS_C0201-DIFF BUS_0A 1        DMI_CPU0_PCH_RX_C_DN<0> 
                                  2        DMI_CPU0_PCH_RX_DN<0>   
C170             Q_CAP_DIFFBUS_C0201-DIFF BUS_0A 1        DMI_CPU0_PCH_RX_C_DP<0> 
                                  2        DMI_CPU0_PCH_RX_DP<0>   
C171             Q_CAP_0402-0.1UF,25V,10%,X7R,CA 1        P3V3_AUX_CLK_GEN_VDD_CK440
                                  2        GND                     
C172             Q_CAP_C0603-10UF,6.3V,20%,X6S,A 1        P3V3_AUX_CLK_GEN_VDDA100M_CK440
                                  2        GND                     
C173             Q_CAP_0402-0.1UF,25V,10%,X7R,CA 1        P3V3_AUX_CLK_GEN_VDDA100M_CK440
                                  2        GND                     
C174             Q_CAP_0402-0.1UF,25V,10%,X7R,CA 1        P3V3_AUX                
                                  2        GND                     
C179             Q_CAP_C0402-100NF,50V,10%,X7R,A 1        P3V3_E1S_0_DVDT         
                                  2        GND                     
C180             Q_CAP_0402-0.1UF,25V,10%,X7R,CA 1        P12V_FRONT_CPU          
                                  2        GND                     
C184             Q_CAP_C0805-10UF,25V,10%,X6S,CA 1        P3V3_E1S_0              
                                  2        GND                     
C188             Q_CAP_0402-0.1UF,25V,10%,X7R,CA 1        P3V3_AUX                
                                  2        GND                     
C204             Q_CAP_0402-0.1UF,25V,10%,X7R,CA 1        P3V3_DB2000_VDD         
                                  2        GND                     
C205             Q_CAP_0402-0.1UF,25V,10%,X7R,CA 1        P3V3_DB2000_VDD         
                                  2        GND                     
C206             Q_CAP_0402-0.1UF,25V,10%,X7R,CA 1        P3V3_DB2000_VDD         
                                  2        GND                     
C207             Q_CAP_0402-0.1UF,25V,10%,X7R,CA 1        P3V3_DB2000_VDD         
                                  2        GND                     
C208             Q_CAP_C0603-10UF,6.3V,20%,X6S,A 1        P3V3_DB2000_VDDR        
                                  2        GND                     
C209             Q_CAP_C0603-10UF,6.3V,20%,X6S,A 1        P3V3_DB2000_VDDA        
                                  2        GND                     
C210             Q_CAP_0402-0.1UF,25V,10%,X7R,CA 1        P3V3_DB2000_VDDR        
                                  2        GND                     
C211             Q_CAP_0402-0.1UF,25V,10%,X7R,CA 1        P3V3_DB2000_VDDA        
                                  2        GND                     
C212             Q_CAP_0805-47UF,4V,20%,X6S,CH6A 1        PVCCIN_CPU0             
                                  2        GND                     
C213             Q_CAP_0805-47UF,4V,20%,X6S,CH6A 1        PVCCIN_CPU0             
                                  2        GND                     
C214             Q_CAP_0805-47UF,4V,20%,X6S,CH6A 1        PVCCIN_CPU0             
                                  2        GND                     
C215             Q_CAP_0805-47UF,4V,20%,X6S,CH6A 1        PVCCIN_CPU0             
                                  2        GND                     
C216             Q_CAP_0805-47UF,4V,20%,X6S,CH6A 1        PVCCIN_CPU0             
                                  2        GND                     
C217             Q_CAP_0805-47UF,4V,20%,X6S,CH6A 1        PVCCIN_CPU0             
                                  2        GND                     
C218             Q_CAP_0805-47UF,4V,20%,X6S,CH6A 1        PVCCIN_CPU0             
                                  2        GND                     
C219             Q_CAP_0805-47UF,4V,20%,X6S,CH6A 1        PVCCIN_CPU0             
                                  2        GND                     
C220             Q_CAP_0805-47UF,4V,20%,X6S,CH6A 1        PVCCIN_CPU0             
                                  2        GND                     
C221             Q_CAP_C0402-22UF,4V,20%,X6S,CHA 1        PVCCIN_CPU1             
                                  2        GND                     
C222             Q_CAP_C0402-22UF,4V,20%,X6S,CHA 1        PVCCIN_CPU1             
                                  2        GND                     
C223             Q_CAP_C0402-22UF,4V,20%,X6S,CHA 1        PVCCIN_CPU1             
                                  2        GND                     
C224             Q_CAP_C0402-22UF,4V,20%,X6S,CHA 1        PVCCIN_CPU1             
                                  2        GND                     
C225             Q_CAP_0805-47UF,4V,20%,X6S,CH6A 1        PVCCIN_CPU1             
                                  2        GND                     
C226             Q_CAP_C0402-22UF,4V,20%,X6S,CHA 1        PVCCIN_CPU1             
                                  2        GND                     
C227             Q_CAP_C0402-22UF,4V,20%,X6S,CHA 1        PVCCIN_CPU1             
                                  2        GND                     
C228             Q_CAP_C0402-22UF,4V,20%,X6S,CHA 1        PVCCIN_CPU1             
                                  2        GND                     
C229             Q_CAP_C0402-22UF,4V,20%,X6S,CHA 1        PVCCIN_CPU1             
                                  2        GND                     
C230             Q_CAP_0805-47UF,4V,20%,X6S,CH6A 1        PVCCIN_CPU1             
                                  2        GND                     
C231             Q_CAP_C0402-22UF,4V,20%,X6S,CHA 1        PVCCIN_CPU1             
                                  2        GND                     
C232             Q_CAP_C0402-22UF,4V,20%,X6S,CHA 1        PVCCIN_CPU1             
                                  2        GND                     
C233             Q_CAP_C0402-22UF,4V,20%,X6S,CHA 1        PVCCIN_CPU1             
                                  2        GND                     
C234             Q_CAP_C0402-22UF,4V,20%,X6S,CHA 1        PVCCIN_CPU1             
                                  2        GND                     
C235             Q_CAP_0805-47UF,4V,20%,X6S,CH6A 1        PVCCIN_CPU1             
                                  2        GND                     
C236             Q_CAP_C0402-22UF,4V,20%,X6S,CHA 1        PVCCIN_CPU1             
                                  2        GND                     
C237             Q_CAP_C0402-22UF,4V,20%,X6S,CHA 1        PVCCIN_CPU1             
                                  2        GND                     
C238             Q_CAP_C0402-22UF,4V,20%,X6S,CHA 1        PVCCIN_CPU1             
                                  2        GND                     
C239             Q_CAP_C0402-22UF,4V,20%,X6S,CHA 1        PVCCIN_CPU1             
                                  2        GND                     
C240             Q_CAP_0805-47UF,4V,20%,X6S,CH6A 1        PVCCIN_CPU1             
                                  2        GND                     
C241             Q_CAP_C0402-22UF,4V,20%,X6S,CHA 1        PVCCIN_CPU1             
                                  2        GND                     
C242             Q_CAP_C0402-22UF,4V,20%,X6S,CHA 1        PVCCIN_CPU1             
                                  2        GND                     
C243             Q_CAP_C0402-22UF,4V,20%,X6S,CHA 1        PVCCIN_CPU1             
                                  2        GND                     
C244             Q_CAP_C0402-22UF,4V,20%,X6S,CHA 1        PVCCIN_CPU1             
                                  2        GND                     
C245             Q_CAP_0805-47UF,4V,20%,X6S,CH6A 1        PVCCIN_CPU1             
                                  2        GND                     
C246             Q_CAP_C0402-22UF,4V,20%,X6S,CHA 1        PVCCIN_CPU1             
                                  2        GND                     
C247             Q_CAP_C0402-22UF,4V,20%,X6S,CHA 1        PVCCIN_CPU1             
                                  2        GND                     
C248             Q_CAP_C0402-22UF,4V,20%,X6S,CHA 1        PVCCIN_CPU1             
                                  2        GND                     
C249             Q_CAP_C0402-22UF,4V,20%,X6S,CHA 1        PVCCIN_CPU1             
                                  2        GND                     
C250             Q_CAP_0805-47UF,4V,20%,X6S,CH6A 1        PVCCIN_CPU1             
                                  2        GND                     
C251             Q_CAP_C0402-22UF,4V,20%,X6S,CHA 1        PVCCIN_CPU1             
                                  2        GND                     
C252             Q_CAP_C0402-22UF,4V,20%,X6S,CHA 1        PVCCIN_CPU1             
                                  2        GND                     
C253             Q_CAP_C0402-22UF,4V,20%,X6S,CHA 1        PVCCIN_CPU1             
                                  2        GND                     
C254             Q_CAP_C0402-22UF,4V,20%,X6S,CHA 1        PVCCIN_CPU1             
                                  2        GND                     
C255             Q_CAP_0805-47UF,4V,20%,X6S,CH6A 1        PVCCIN_CPU1             
                                  2        GND                     
C256             Q_CAP_C0402-22UF,4V,20%,X6S,CHA 1        PVCCIN_CPU1             
                                  2        GND                     
C257             Q_CAP_C0402-22UF,4V,20%,X6S,CHA 1        PVCCIN_CPU1             
                                  2        GND                     
C258             Q_CAP_C0402-22UF,4V,20%,X6S,CHA 1        PVCCIN_CPU1             
                                  2        GND                     
C259             Q_CAP_C0402-22UF,4V,20%,X6S,CHA 1        PVCCIN_CPU1             
                                  2        GND                     
C260             Q_CAP_0805-47UF,4V,20%,X6S,CH6A 1        PVCCIN_CPU1             
                                  2        GND                     
C261             Q_CAP_C0402-22UF,4V,20%,X6S,CHA 1        PVCCIN_CPU1             
                                  2        GND                     
C262             Q_CAP_C0402-22UF,4V,20%,X6S,CHA 1        PVCCIN_CPU1             
                                  2        GND                     
C263             Q_CAP_C0402-22UF,4V,20%,X6S,CHA 1        PVCCIN_CPU1             
                                  2        GND                     
C264             Q_CAP_C0402-22UF,4V,20%,X6S,CHA 1        PVCCIN_CPU1             
                                  2        GND                     
C265             Q_CAP_0805-47UF,4V,20%,X6S,CH6A 1        PVCCIN_CPU1             
                                  2        GND                     
C266             Q_CAP_C0402-22UF,4V,20%,X6S,CHA 1        PVCCIN_CPU1             
                                  2        GND                     
C267             Q_CAP_C0402-22UF,4V,20%,X6S,CHA 1        PVCCIN_CPU1             
                                  2        GND                     
C268             Q_CAP_C0402-22UF,4V,20%,X6S,CHA 1        PVCCIN_CPU1             
                                  2        GND                     
C269             Q_CAP_C0402-22UF,4V,20%,X6S,CHA 1        PVCCIN_CPU1             
                                  2        GND                     
C270             Q_CAP_0805-47UF,4V,20%,X6S,CH6A 1        PVCCIN_CPU1             
                                  2        GND                     
C271             Q_CAP_C0402-22UF,4V,20%,X6S,CHA 1        PVCCIN_CPU1             
                                  2        GND                     
C272             Q_CAP_C0402-22UF,4V,20%,X6S,CHA 1        PVCCIN_CPU1             
                                  2        GND                     
C273             Q_CAP_C0402-22UF,4V,20%,X6S,CHA 1        PVCCIN_CPU1             
                                  2        GND                     
C274             Q_CAP_C0402-22UF,4V,20%,X6S,CHA 1        PVCCIN_CPU1             
                                  2        GND                     
C275             Q_CAP_C0402-22UF,4V,20%,X6S,CHA 1        PVCCIN_CPU1             
                                  2        GND                     
C276             Q_CAP_C0402-22UF,4V,20%,X6S,CHA 1        PVCCIN_CPU1             
                                  2        GND                     
C277             Q_CAP_C0402-22UF,4V,20%,X6S,CHA 1        PVCCIN_CPU1             
                                  2        GND                     
C278             Q_CAP_C0402-22UF,4V,20%,X6S,CHA 1        PVCCIN_CPU1             
                                  2        GND                     
C279             Q_CAP_C0402-22UF,4V,20%,X6S,CHA 1        PVCCIN_CPU1             
                                  2        GND                     
C280             Q_CAP_C0402-22UF,4V,20%,X6S,CHA 1        PVCCIN_CPU1             
                                  2        GND                     
C281             Q_CAP_C0402-22UF,4V,20%,X6S,CHA 1        PVCCIN_CPU1             
                                  2        GND                     
C282             Q_CAP_C0402-22UF,4V,20%,X6S,CHA 1        PVCCIN_CPU1             
                                  2        GND                     
C283             Q_CAP_C0402-22UF,4V,20%,X6S,CHA 1        PVCCIN_CPU1             
                                  2        GND                     
C284             Q_CAP_C0402-22UF,4V,20%,X6S,CHA 1        PVCCIN_CPU1             
                                  2        GND                     
C285             Q_CAP_C0402-22UF,4V,20%,X6S,CHA 1        PVCCIN_CPU1             
                                  2        GND                     
C286             Q_CAP_C0402-22UF,4V,20%,X6S,CHA 1        PVCCIN_CPU1             
                                  2        GND                     
C287             Q_CAP_C0402-22UF,4V,20%,X6S,CHA 1        PVCCIN_CPU1             
                                  2        GND                     
C288             Q_CAP_C0402-22UF,4V,20%,X6S,CHA 1        PVCCIN_CPU1             
                                  2        GND                     
C289             Q_CAP_C0402-22UF,4V,20%,X6S,CHA 1        PVCCIN_CPU1             
                                  2        GND                     
C290             Q_CAP_C0402-22UF,4V,20%,X6S,CHA 1        PVCCIN_CPU1             
                                  2        GND                     
C291             Q_CAP_C0402-22UF,4V,20%,X6S,CHA 1        PVCCIN_CPU1             
                                  2        GND                     
C292             Q_CAP_C0402-22UF,4V,20%,X6S,CHA 1        PVCCIN_CPU1             
                                  2        GND                     
C293             Q_CAP_C0402-22UF,4V,20%,X6S,CHA 1        PVCCIN_CPU1             
                                  2        GND                     
C294             Q_CAP_C0402-22UF,4V,20%,X6S,CHA 1        PVCCIN_CPU1             
                                  2        GND                     
C295             Q_CAP_C0402-22UF,4V,20%,X6S,CHA 1        PVCCIN_CPU1             
                                  2        GND                     
C296             Q_CAP_C0402-22UF,4V,20%,X6S,CHA 1        PVCCIN_CPU1             
                                  2        GND                     
C297             Q_CAP_C0402-22UF,4V,20%,X6S,CHA 1        PVCCIN_CPU1             
                                  2        GND                     
C298             Q_CAP_C0402-22UF,4V,20%,X6S,CHA 1        PVCCIN_CPU1             
                                  2        GND                     
C299             Q_CAP_C0402-22UF,4V,20%,X6S,CHA 1        PVCCIN_CPU1             
                                  2        GND                     
C300             Q_CAP_C0402-22UF,4V,20%,X6S,CHA 1        PVCCIN_CPU1             
                                  2        GND                     
C301             Q_CAP_C0402-22UF,4V,20%,X6S,CHA 1        PVCCIN_CPU1             
                                  2        GND                     
C302             Q_CAP_C0402-22UF,4V,20%,X6S,CHA 1        PVCCIN_CPU1             
                                  2        GND                     
C303             Q_CAP_C0402-22UF,4V,20%,X6S,CHA 1        PVCCIN_CPU1             
                                  2        GND                     
C304             Q_CAP_C0402-22UF,4V,20%,X6S,CHA 1        PVCCIN_CPU1             
                                  2        GND                     
C305             Q_CAP_C0402-22UF,4V,20%,X6S,CHA 1        PVCCIN_CPU1             
                                  2        GND                     
C306             Q_CAP_C0402-22UF,4V,20%,X6S,CHA 1        PVCCIN_CPU1             
                                  2        GND                     
C307             Q_CAP_C0402-22UF,4V,20%,X6S,CHA 1        PVCCIN_CPU1             
                                  2        GND                     
C308             Q_CAP_C0402-22UF,4V,20%,X6S,CHA 1        PVCCIN_CPU1             
                                  2        GND                     
C309             Q_CAP_C0402-22UF,4V,20%,X6S,CHA 1        PVCCIN_CPU1             
                                  2        GND                     
C310             Q_CAP_C0402-22UF,4V,20%,X6S,CHA 1        PVNN_MAIN_CPU1          
                                  2        GND                     
C311             Q_CAP_C0805-100UF,4V,20%,X6S,CA 1        PVCCIN_CPU1             
                                  2        GND                     
C312             Q_CAP_C0805-100UF,4V,20%,X6S,CA 1        PVCCIN_CPU1             
                                  2        GND                     
C313             Q_CAP_C0805-100UF,4V,20%,X6S,CA 1        PVCCIN_CPU1             
                                  2        GND                     
C314             Q_CAP_C0805-100UF,4V,20%,X6S,CA 1        PVCCIN_CPU1             
                                  2        GND                     
C315             Q_CAP_C0805-100UF,4V,20%,X6S,CA 1        PVCCIN_CPU1             
                                  2        GND                     
C316             Q_CAP_C0805-100UF,4V,20%,X6S,CA 1        PVCCIN_CPU1             
                                  2        GND                     
C317             Q_CAP_C0805-100UF,4V,20%,X6S,CA 1        PVCCIN_CPU1             
                                  2        GND                     
C318             Q_CAP_C0805-100UF,4V,20%,X6S,CA 1        PVCCIN_CPU1             
                                  2        GND                     
C319             Q_CAP_C0805-22UF,16V,20%,X6S,CA 1        P12V_OCP_SFF            
                                  2        GND                     
C320             Q_CAP_C0805-100UF,4V,20%,X6S,CA 1        PVCCIN_CPU1             
                                  2        GND                     
C321             Q_CAP_C0805-100UF,4V,20%,X6S,CA 1        PVCCIN_CPU1             
                                  2        GND                     
C322             Q_CAP_C0805-100UF,4V,20%,X6S,CA 1        PVCCIN_CPU1             
                                  2        GND                     
C323             Q_CAP_C0805-100UF,4V,20%,X6S,CA 1        PVCCIN_CPU1             
                                  2        GND                     
C324             Q_CAP_C0805-100UF,4V,20%,X6S,CA 1        PVCCIN_CPU1             
                                  2        GND                     
C325             Q_CAP_C0805-100UF,4V,20%,X6S,CA 1        PVCCIN_CPU1             
                                  2        GND                     
C326             Q_CAP_C0805-100UF,4V,20%,X6S,CA 1        PVCCIN_CPU1             
                                  2        GND                     
C327             Q_CAP_C0805-100UF,4V,20%,X6S,CA 1        PVCCIN_CPU1             
                                  2        GND                     
C328             Q_CAP_C0805-100UF,4V,20%,X6S,CA 1        PVCCIN_CPU1             
                                  2        GND                     
C329             Q_CAP_C0805-100UF,4V,20%,X6S,CA 1        PVCCIN_CPU1             
                                  2        GND                     
C330             Q_CAP_C0805-100UF,4V,20%,X6S,CA 1        PVCCIN_CPU1             
                                  2        GND                     
C331             Q_CAP_C0805-22UF,16V,20%,X6S,CA 1        P12V_OCP_SFF            
                                  2        GND                     
C332             Q_CAP_C0805-100UF,4V,20%,X6S,CA 1        PVCCIN_CPU1             
                                  2        GND                     
C333             Q_CAP_C0805-100UF,4V,20%,X6S,CA 1        PVCCIN_CPU1             
                                  2        GND                     
C335             Q_CAP_C0805-100UF,4V,20%,X6S,CA 1        PVCCIN_CPU1             
                                  2        GND                     
C336             Q_CAP_C0805-100UF,4V,20%,X6S,CA 1        PVCCIN_CPU1             
                                  2        GND                     
C337             Q_CAP_C0603-47UF,2.5V,20%,X6S,A 1        PVCCIN_CPU1             
                                  2        GND                     
C338             Q_CAP_C0805-100UF,4V,20%,X6S,CA 1        PVCCIN_CPU1             
                                  2        GND                     
C339             Q_CAP_C0805-100UF,4V,20%,X6S,CA 1        PVCCIN_CPU1             
                                  2        GND                     
C340             Q_CAP_C0603-47UF,2.5V,20%,X6S,A 1        PVCCIN_CPU1             
                                  2        GND                     
C341             Q_CAP_C0805-100UF,4V,20%,X6S,CA 1        PVCCIN_CPU1             
                                  2        GND                     
C342             Q_CAP_C0805-100UF,4V,20%,X6S,CA 1        PVCCIN_CPU1             
                                  2        GND                     
C343             Q_CAP_C0805-100UF,4V,20%,X6S,CA 1        PVCCIN_CPU1             
                                  2        GND                     
C344             Q_CAP_C0805-100UF,4V,20%,X6S,CA 1        PVCCIN_CPU1             
                                  2        GND                     
C345             Q_CAP_C0805-100UF,4V,20%,X6S,CA 1        PVCCIN_CPU1             
                                  2        GND                     
C346             Q_CAP_C0805-100UF,4V,20%,X6S,CA 1        PVCCIN_CPU1             
                                  2        GND                     
C347             Q_CAP_C0805-100UF,4V,20%,X6S,CA 1        PVCCIN_CPU1             
                                  2        GND                     
C348             Q_CAP_C0805-100UF,4V,20%,X6S,CA 1        PVCCIN_CPU1             
                                  2        GND                     
C349             Q_CAP_C0805-100UF,4V,20%,X6S,CA 1        PVCCIN_CPU1             
                                  2        GND                     
C350             Q_CAP_C0805-100UF,4V,20%,X6S,CA 1        PVCCIN_CPU1             
                                  2        GND                     
C351             Q_CAP_C0805-100UF,4V,20%,X6S,CA 1        PVCCIN_CPU1             
                                  2        GND                     
C352             Q_CAP_C0805-100UF,4V,20%,X6S,CA 1        PVCCIN_CPU1             
                                  2        GND                     
C353             Q_CAP_C0805-100UF,4V,20%,X6S,CA 1        PVCCIN_CPU1             
                                  2        GND                     
C354             Q_CAP_C0805-100UF,4V,20%,X6S,CA 1        PVCCIN_CPU1             
                                  2        GND                     
C355             Q_CAP_C0805-100UF,4V,20%,X6S,CA 1        PVCCIN_CPU0             
                                  2        GND                     
C356             Q_CAP_C0805-100UF,4V,20%,X6S,CA 1        PVCCIN_CPU0             
                                  2        GND                     
C357             Q_CAP_C0805-100UF,4V,20%,X6S,CA 1        PVCCIN_CPU0             
                                  2        GND                     
C358             Q_CAP_C0805-100UF,4V,20%,X6S,CA 1        PVCCIN_CPU0             
                                  2        GND                     
C359             Q_CAP_C0805-100UF,4V,20%,X6S,CA 1        PVCCIN_CPU0             
                                  2        GND                     
C360             Q_CAP_C0805-100UF,4V,20%,X6S,CA 1        PVCCIN_CPU0             
                                  2        GND                     
C361             Q_CAP_C0805-100UF,4V,20%,X6S,CA 1        PVCCIN_CPU0             
                                  2        GND                     
C362             Q_CAP_C0805-100UF,4V,20%,X6S,CA 1        PVCCIN_CPU0             
                                  2        GND                     
C363             Q_CAP_C0805-100UF,4V,20%,X6S,CA 1        PVCCIN_CPU0             
                                  2        GND                     
C364             Q_CAP_C0805-100UF,4V,20%,X6S,CA 1        PVCCIN_CPU0             
                                  2        GND                     
C365             Q_CAP_C0805-100UF,4V,20%,X6S,CA 1        PVCCIN_CPU0             
                                  2        GND                     
C366             Q_CAP_C0805-100UF,4V,20%,X6S,CA 1        PVCCIN_CPU0             
                                  2        GND                     
C367             Q_CAP_C0805-100UF,4V,20%,X6S,CA 1        PVCCIN_CPU0             
                                  2        GND                     
C368             Q_CAP_C0805-100UF,4V,20%,X6S,CA 1        PVCCIN_CPU0             
                                  2        GND                     
C369             Q_CAP_C0805-100UF,4V,20%,X6S,CA 1        PVCCIN_CPU0             
                                  2        GND                     
C370             Q_CAP_C0805-100UF,4V,20%,X6S,CA 1        PVCCIN_CPU0             
                                  2        GND                     
C371             Q_CAP_C0805-100UF,4V,20%,X6S,CA 1        PVCCIN_CPU0             
                                  2        GND                     
C372             Q_CAP_C0805-100UF,4V,20%,X6S,CA 1        PVCCIN_CPU0             
                                  2        GND                     
C373             Q_CAP_C0805-100UF,4V,20%,X6S,CA 1        PVCCIN_CPU0             
                                  2        GND                     
C374             Q_CAP_C0805-100UF,4V,20%,X6S,CA 1        PVCCIN_CPU0             
                                  2        GND                     
C376             Q_CAP_C0805-100UF,4V,20%,X6S,CA 1        PVCCIN_CPU0             
                                  2        GND                     
C377             Q_CAP_C0805-100UF,4V,20%,X6S,CA 1        PVCCIN_CPU0             
                                  2        GND                     
C379             Q_CAP_C0805-100UF,4V,20%,X6S,CA 1        PVCCIN_CPU0             
                                  2        GND                     
C380             Q_CAP_C0805-100UF,4V,20%,X6S,CA 1        PVCCIN_CPU0             
                                  2        GND                     
C381             Q_CAP_C0603-47UF,2.5V,20%,X6S,A 1        PVCCIN_CPU0             
                                  2        GND                     
C382             Q_CAP_C0805-100UF,4V,20%,X6S,CA 1        PVCCIN_CPU0             
                                  2        GND                     
C383             Q_CAP_C0805-100UF,4V,20%,X6S,CA 1        PVCCIN_CPU0             
                                  2        GND                     
C384             Q_CAP_C0603-47UF,2.5V,20%,X6S,A 1        PVCCIN_CPU0             
                                  2        GND                     
C385             Q_CAP_C0805-100UF,4V,20%,X6S,CA 1        PVCCIN_CPU0             
                                  2        GND                     
C386             Q_CAP_C0805-100UF,4V,20%,X6S,CA 1        PVCCIN_CPU0             
                                  2        GND                     
C387             Q_CAP_C0805-100UF,4V,20%,X6S,CA 1        PVCCIN_CPU0             
                                  2        GND                     
C388             Q_CAP_C0805-100UF,4V,20%,X6S,CA 1        PVCCIN_CPU0             
                                  2        GND                     
C389             Q_CAP_C0805-100UF,4V,20%,X6S,CA 1        PVCCIN_CPU0             
                                  2        GND                     
C390             Q_CAP_C0805-100UF,4V,20%,X6S,CA 1        PVCCIN_CPU0             
                                  2        GND                     
C391             Q_CAP_C0805-100UF,4V,20%,X6S,CA 1        PVCCIN_CPU0             
                                  2        GND                     
C392             Q_CAP_C0805-100UF,4V,20%,X6S,CA 1        PVCCIN_CPU0             
                                  2        GND                     
C393             Q_CAP_C0805-100UF,4V,20%,X6S,CA 1        PVCCIN_CPU0             
                                  2        GND                     
C394             Q_CAP_C0805-100UF,4V,20%,X6S,CA 1        PVCCIN_CPU0             
                                  2        GND                     
C395             Q_CAP_C0805-100UF,4V,20%,X6S,CA 1        PVNN_MAIN_CPU0          
                                  2        GND                     
C396             Q_CAP_C0805-100UF,4V,20%,X6S,CA 1        PVCCIN_CPU0             
                                  2        GND                     
C397             Q_CAP_C0805-100UF,4V,20%,X6S,CA 1        PVCCIN_CPU0             
                                  2        GND                     
C398             Q_CAP_C0805-100UF,4V,20%,X6S,CA 1        PVCCIN_CPU0             
                                  2        GND                     
C399             Q_CAP_C0402-22UF,4V,20%,X6S,CHA 1        PVCCD_HV_CPU0           
                                  2        GND                     
C400             Q_CAP_C0402-22UF,4V,20%,X6S,CHA 1        PVCCFA_EHV_FIVRA_CPU0   
                                  2        GND                     
C401             Q_CAP_C0402-22UF,4V,20%,X6S,CHA 1        PVCCD_HV_CPU0           
                                  2        GND                     
C402             Q_CAP_C0402-22UF,4V,20%,X6S,CHA 1        PVCCFA_EHV_FIVRA_CPU0   
                                  2        GND                     
C403             Q_CAP_C0402-22UF,4V,20%,X6S,CHA 1        PVCCD_HV_CPU0           
                                  2        GND                     
C404             Q_CAP_C0402-22UF,4V,20%,X6S,CHA 1        PVCCFA_EHV_FIVRA_CPU0   
                                  2        GND                     
C405             Q_CAP_C0402-22UF,4V,20%,X6S,CHA 1        PVCCD_HV_CPU0           
                                  2        GND                     
C406             Q_CAP_C0402-22UF,4V,20%,X6S,CHA 1        PVCCFA_EHV_FIVRA_CPU0   
                                  2        GND                     
C407             Q_CAP_C0402-22UF,4V,20%,X6S,CHA 1        PVCCFA_EHV_FIVRA_CPU0   
                                  2        GND                     
C408             Q_CAP_C0402-22UF,4V,20%,X6S,CHA 1        PVCCINFAON_CPU0         
                                  2        GND                     
C409             Q_CAP_C0402-22UF,4V,20%,X6S,CHA 1        PVCCFA_EHV_FIVRA_CPU0   
                                  2        GND                     
C410             Q_CAP_C0402-22UF,4V,20%,X6S,CHA 1        PVCCINFAON_CPU0         
                                  2        GND                     
C411             Q_CAP_C0402-22UF,4V,20%,X6S,CHA 1        PVCCFA_EHV_FIVRA_CPU0   
                                  2        GND                     
C412             Q_CAP_C0402-22UF,4V,20%,X6S,CHA 1        PVCCINFAON_CPU0         
                                  2        GND                     
C413             Q_CAP_C0402-22UF,4V,20%,X6S,CHA 1        PVCCFA_EHV_FIVRA_CPU0   
                                  2        GND                     
C414             Q_CAP_C0402-22UF,4V,20%,X6S,CHA 1        PVCCINFAON_CPU0         
                                  2        GND                     
C415             Q_CAP_C0402-22UF,4V,20%,X6S,CHA 1        PVCCFA_EHV_FIVRA_CPU0   
                                  2        GND                     
C416             Q_CAP_C0402-22UF,4V,20%,X6S,CHA 1        PVCCINFAON_CPU0         
                                  2        GND                     
C417             Q_CAP_C0402-22UF,4V,20%,X6S,CHA 1        PVCCFA_EHV_FIVRA_CPU0   
                                  2        GND                     
C418             Q_CAP_C0402-22UF,4V,20%,X6S,CHA 1        PVCCFA_EHV_FIVRA_CPU0   
                                  2        GND                     
C419             Q_CAP_C0402-22UF,4V,20%,X6S,CHA 1        PVCCFA_EHV_CPU0         
                                  2        GND                     
C420             Q_CAP_C0402-22UF,4V,20%,X6S,CHA 1        PVCCFA_EHV_CPU0         
                                  2        GND                     
C421             Q_CAP_C0402-22UF,4V,20%,X6S,CHA 1        PVCCFA_EHV_CPU0         
                                  2        GND                     
C422             Q_CAP_C0402-22UF,4V,20%,X6S,CHA 1        PVCCFA_EHV_CPU0         
                                  2        GND                     
C423             Q_CAP_C0402-22UF,4V,20%,X6S,CHA 1        PVCCD_HV_CPU1           
                                  2        GND                     
C424             Q_CAP_C0402-22UF,4V,20%,X6S,CHA 1        PVCCFA_EHV_FIVRA_CPU1   
                                  2        GND                     
C425             Q_CAP_C0402-22UF,4V,20%,X6S,CHA 1        PVCCD_HV_CPU1           
                                  2        GND                     
C426             Q_CAP_C0402-22UF,4V,20%,X6S,CHA 1        PVCCFA_EHV_FIVRA_CPU1   
                                  2        GND                     
C427             Q_CAP_C0402-22UF,4V,20%,X6S,CHA 1        PVCCD_HV_CPU1           
                                  2        GND                     
C428             Q_CAP_C0402-22UF,4V,20%,X6S,CHA 1        PVCCFA_EHV_FIVRA_CPU1   
                                  2        GND                     
C429             Q_CAP_C0402-22UF,4V,20%,X6S,CHA 1        PVCCD_HV_CPU1           
                                  2        GND                     
C430             Q_CAP_C0402-22UF,4V,20%,X6S,CHA 1        PVCCFA_EHV_FIVRA_CPU1   
                                  2        GND                     
C431             Q_CAP_C0402-22UF,4V,20%,X6S,CHA 1        PVCCFA_EHV_FIVRA_CPU1   
                                  2        GND                     
C432             Q_CAP_C0402-22UF,4V,20%,X6S,CHA 1        PVCCINFAON_CPU1         
                                  2        GND                     
C433             Q_CAP_C0402-22UF,4V,20%,X6S,CHA 1        PVCCFA_EHV_FIVRA_CPU1   
                                  2        GND                     
C434             Q_CAP_C0402-22UF,4V,20%,X6S,CHA 1        PVCCINFAON_CPU1         
                                  2        GND                     
C435             Q_CAP_C0402-22UF,4V,20%,X6S,CHA 1        PVCCFA_EHV_FIVRA_CPU1   
                                  2        GND                     
C436             Q_CAP_C0402-22UF,4V,20%,X6S,CHA 1        PVCCINFAON_CPU1         
                                  2        GND                     
C437             Q_CAP_C0402-22UF,4V,20%,X6S,CHA 1        PVCCFA_EHV_FIVRA_CPU1   
                                  2        GND                     
C438             Q_CAP_C0402-22UF,4V,20%,X6S,CHA 1        PVCCINFAON_CPU1         
                                  2        GND                     
C439             Q_CAP_C0402-22UF,4V,20%,X6S,CHA 1        PVCCFA_EHV_FIVRA_CPU1   
                                  2        GND                     
C440             Q_CAP_C0402-22UF,4V,20%,X6S,CHA 1        PVCCINFAON_CPU1         
                                  2        GND                     
C441             Q_CAP_C0402-22UF,4V,20%,X6S,CHA 1        PVCCFA_EHV_FIVRA_CPU1   
                                  2        GND                     
C442             Q_CAP_C0402-22UF,4V,20%,X6S,CHA 1        PVCCFA_EHV_FIVRA_CPU1   
                                  2        GND                     
C443             Q_CAP_C0402-22UF,4V,20%,X6S,CHA 1        PVCCFA_EHV_CPU1         
                                  2        GND                     
C444             Q_CAP_C0402-22UF,4V,20%,X6S,CHA 1        PVCCFA_EHV_CPU1         
                                  2        GND                     
C445             Q_CAP_C0402-22UF,4V,20%,X6S,CHA 1        PVCCFA_EHV_CPU1         
                                  2        GND                     
C446             Q_CAP_C0402-22UF,4V,20%,X6S,CHA 1        PVCCFA_EHV_CPU1         
                                  2        GND                     
C447             Q_CAP_C0805-100UF,4V,20%,X6S,CA 1        PVCCD_HV_CPU1           
                                  2        GND                     
C448             Q_CAP_C0805-100UF,4V,20%,X6S,CA 1        PVCCFA_EHV_CPU1         
                                  2        GND                     
C449             Q_CAP_C0805-100UF,4V,20%,X6S,CA 1        PVCCFA_EHV_FIVRA_CPU1   
                                  2        GND                     
C450             Q_CAP_C0805-100UF,4V,20%,X6S,CA 1        PVCCFA_EHV_FIVRA_CPU1   
                                  2        GND                     
C451             Q_CAP_C0805-100UF,4V,20%,X6S,CA 1        PVCCD_HV_CPU1           
                                  2        GND                     
C452             Q_CAP_C0805-100UF,4V,20%,X6S,CA 1        PVCCFA_EHV_CPU1         
                                  2        GND                     
C453             Q_CAP_C0805-100UF,4V,20%,X6S,CA 1        PVCCFA_EHV_FIVRA_CPU1   
                                  2        GND                     
C454             Q_CAP_C0805-100UF,4V,20%,X6S,CA 1        PVCCFA_EHV_FIVRA_CPU1   
                                  2        GND                     
C455             Q_CAP_C0805-100UF,4V,20%,X6S,CA 1        PVCCD_HV_CPU1           
                                  2        GND                     
C456             Q_CAP_C0805-100UF,4V,20%,X6S,CA 1        PVCCFA_EHV_CPU1         
                                  2        GND                     
C457             Q_CAP_C0805-100UF,4V,20%,X6S,CA 1        PVCCFA_EHV_FIVRA_CPU1   
                                  2        GND                     
C458             Q_CAP_C0805-100UF,4V,20%,X6S,CA 1        PVCCFA_EHV_FIVRA_CPU1   
                                  2        GND                     
C459             Q_CAP_C0805-100UF,4V,20%,X6S,CA 1        PVCCD_HV_CPU1           
                                  2        GND                     
C460             Q_CAP_C0805-100UF,4V,20%,X6S,CA 1        PVCCFA_EHV_CPU1         
                                  2        GND                     
C461             Q_CAP_C0805-100UF,4V,20%,X6S,CA 1        PVCCFA_EHV_FIVRA_CPU1   
                                  2        GND                     
C462             Q_CAP_C0805-100UF,4V,20%,X6S,CA 1        PVCCFA_EHV_FIVRA_CPU1   
                                  2        GND                     
C463             Q_CAP_C0805-100UF,4V,20%,X6S,CA 1        PVCCD_HV_CPU1           
                                  2        GND                     
C464             Q_CAP_C0805-100UF,4V,20%,X6S,CA 1        PVCCFA_EHV_CPU1         
                                  2        GND                     
C465             Q_CAP_C0603-47UF,2.5V,20%,X6S,A 1        PVCCFA_EHV_FIVRA_CPU1   
                                  2        GND                     
C466             Q_CAP_C0805-100UF,4V,20%,X6S,CA 1        PVCCFA_EHV_FIVRA_CPU1   
                                  2        GND                     
C467             Q_CAP_C0805-100UF,4V,20%,X6S,CA 1        PVCCD_HV_CPU1           
                                  2        GND                     
C468             Q_CAP_C0805-100UF,4V,20%,X6S,CA 1        PVCCFA_EHV_CPU1         
                                  2        GND                     
C470             Q_CAP_C0805-100UF,4V,20%,X6S,CA 1        PVCCFA_EHV_FIVRA_CPU1   
                                  2        GND                     
C471             Q_CAP_C0603-47UF,2.5V,20%,X6S,A 1        PVCCD_HV_CPU1           
                                  2        GND                     
C472             Q_CAP_C0603-47UF,2.5V,20%,X6S,A 1        PVCCFA_EHV_CPU1         
                                  2        GND                     
C473             Q_CAP_C0805-100UF,4V,20%,X6S,CA 1        PVCCFA_EHV_FIVRA_CPU1   
                                  2        GND                     
C474             Q_CAP_C0603-47UF,2.5V,20%,X6S,A 1        PVCCD_HV_CPU1           
                                  2        GND                     
C475             Q_CAP_C0603-47UF,2.5V,20%,X6S,A 1        PVCCFA_EHV_CPU1         
                                  2        GND                     
C476             Q_CAP_C0805-100UF,4V,20%,X6S,CA 1        PVCCFA_EHV_FIVRA_CPU1   
                                  2        GND                     
C477             Q_CAP_C0805-100UF,4V,20%,X6S,CA 1        PVCCFA_EHV_FIVRA_CPU1   
                                  2        GND                     
C478             Q_CAP_C0805-100UF,4V,20%,X6S,CA 1        PVCCINFAON_CPU1         
                                  2        GND                     
C479             Q_CAP_C0805-100UF,4V,20%,X6S,CA 1        PVCCFA_EHV_FIVRA_CPU1   
                                  2        GND                     
C480             Q_CAP_C0603-47UF,2.5V,20%,X6S,A 1        PVCCIN_CPU1             
                                  2        GND                     
C481             Q_CAP_C0805-100UF,4V,20%,X6S,CA 1        PVCCINFAON_CPU1         
                                  2        GND                     
C482             Q_CAP_C0805-100UF,4V,20%,X6S,CA 1        PVCCFA_EHV_FIVRA_CPU1   
                                  2        GND                     
C483             Q_CAP_C0603-47UF,2.5V,20%,X6S,A 1        PVCCIN_CPU1             
                                  2        GND                     
C484             Q_CAP_C0805-100UF,4V,20%,X6S,CA 1        PVCCINFAON_CPU1         
                                  2        GND                     
C485             Q_CAP_C0805-100UF,4V,20%,X6S,CA 1        PVCCFA_EHV_FIVRA_CPU1   
                                  2        GND                     
C486             Q_CAP_C0805-100UF,4V,20%,X6S,CA 1        PVCCINFAON_CPU1         
                                  2        GND                     
C487             Q_CAP_C0805-100UF,4V,20%,X6S,CA 1        PVCCINFAON_CPU1         
                                  2        GND                     
C488             Q_CAP_C0603-47UF,2.5V,20%,X6S,A 1        PVCCINFAON_CPU1         
                                  2        GND                     
C489             Q_CAP_C0603-47UF,2.5V,20%,X6S,A 1        PVCCINFAON_CPU1         
                                  2        GND                     
C490             Q_CAP_C0402-22UF,4V,20%,X6S,CHA 1        PVCCINFAON_CPU1         
                                  2        GND                     
C491             Q_CAP_C0805-100UF,4V,20%,X6S,CA 1        PVCCD_HV_CPU0           
                                  2        GND                     
C492             Q_CAP_C0805-100UF,4V,20%,X6S,CA 1        PVCCFA_EHV_CPU0         
                                  2        GND                     
C493             Q_CAP_C0805-100UF,4V,20%,X6S,CA 1        PVCCFA_EHV_FIVRA_CPU0   
                                  2        GND                     
C494             Q_CAP_C0805-100UF,4V,20%,X6S,CA 1        PVCCFA_EHV_FIVRA_CPU0   
                                  2        GND                     
C495             Q_CAP_C0805-100UF,4V,20%,X6S,CA 1        PVCCD_HV_CPU0           
                                  2        GND                     
C496             Q_CAP_C0805-100UF,4V,20%,X6S,CA 1        PVCCFA_EHV_CPU0         
                                  2        GND                     
C497             Q_CAP_C0805-100UF,4V,20%,X6S,CA 1        PVCCFA_EHV_FIVRA_CPU0   
                                  2        GND                     
C498             Q_CAP_C0805-100UF,4V,20%,X6S,CA 1        PVCCFA_EHV_FIVRA_CPU0   
                                  2        GND                     
C499             Q_CAP_C0805-100UF,4V,20%,X6S,CA 1        PVCCD_HV_CPU0           
                                  2        GND                     
C500             Q_CAP_C0805-100UF,4V,20%,X6S,CA 1        PVCCFA_EHV_CPU0         
                                  2        GND                     
C501             Q_CAP_C0805-100UF,4V,20%,X6S,CA 1        PVCCFA_EHV_FIVRA_CPU0   
                                  2        GND                     
C502             Q_CAP_C0805-100UF,4V,20%,X6S,CA 1        PVCCFA_EHV_FIVRA_CPU0   
                                  2        GND                     
C503             Q_CAP_C0805-100UF,4V,20%,X6S,CA 1        PVCCD_HV_CPU0           
                                  2        GND                     
C504             Q_CAP_C0805-100UF,4V,20%,X6S,CA 1        PVCCFA_EHV_CPU0         
                                  2        GND                     
C505             Q_CAP_C0805-100UF,4V,20%,X6S,CA 1        PVCCFA_EHV_FIVRA_CPU0   
                                  2        GND                     
C506             Q_CAP_C0805-100UF,4V,20%,X6S,CA 1        PVCCFA_EHV_FIVRA_CPU0   
                                  2        GND                     
C507             Q_CAP_C0805-100UF,4V,20%,X6S,CA 1        PVCCD_HV_CPU0           
                                  2        GND                     
C508             Q_CAP_C0805-100UF,4V,20%,X6S,CA 1        PVCCFA_EHV_CPU0         
                                  2        GND                     
C509             Q_CAP_C0603-47UF,2.5V,20%,X6S,A 1        PVCCFA_EHV_FIVRA_CPU0   
                                  2        GND                     
C510             Q_CAP_C0805-100UF,4V,20%,X6S,CA 1        PVCCFA_EHV_FIVRA_CPU0   
                                  2        GND                     
C511             Q_CAP_C0805-100UF,4V,20%,X6S,CA 1        PVCCD_HV_CPU0           
                                  2        GND                     
C512             Q_CAP_C0805-100UF,4V,20%,X6S,CA 1        PVCCFA_EHV_CPU0         
                                  2        GND                     
C513             Q_CAP_C0805-22UF,16V,20%,X6S,CA 1        PGPPA_AUX               
                                  2        GND                     
C514             Q_CAP_C0805-100UF,4V,20%,X6S,CA 1        PVCCFA_EHV_FIVRA_CPU0   
                                  2        GND                     
C515             Q_CAP_C0603-47UF,2.5V,20%,X6S,A 1        PVCCD_HV_CPU0           
                                  2        GND                     
C516             Q_CAP_C0603-47UF,2.5V,20%,X6S,A 1        PVCCFA_EHV_CPU0         
                                  2        GND                     
C517             Q_CAP_C0805-100UF,4V,20%,X6S,CA 1        PVCCFA_EHV_FIVRA_CPU0   
                                  2        GND                     
C518             Q_CAP_C0603-47UF,2.5V,20%,X6S,A 1        PVCCD_HV_CPU0           
                                  2        GND                     
C519             Q_CAP_C0603-47UF,2.5V,20%,X6S,A 1        PVCCFA_EHV_CPU0         
                                  2        GND                     
C520             Q_CAP_C0805-100UF,4V,20%,X6S,CA 1        PVCCFA_EHV_FIVRA_CPU0   
                                  2        GND                     
C521             Q_CAP_C0805-100UF,4V,20%,X6S,CA 1        PVCCFA_EHV_FIVRA_CPU0   
                                  2        GND                     
C522             Q_CAP_C0805-100UF,4V,20%,X6S,CA 1        PVCCINFAON_CPU0         
                                  2        GND                     
C523             Q_CAP_C0805-100UF,4V,20%,X6S,CA 1        PVCCFA_EHV_FIVRA_CPU0   
                                  2        GND                     
C524             Q_CAP_C0603-47UF,2.5V,20%,X6S,A 1        PVCCIN_CPU0             
                                  2        GND                     
C525             Q_CAP_C0805-100UF,4V,20%,X6S,CA 1        PVCCINFAON_CPU0         
                                  2        GND                     
C526             Q_CAP_C0805-100UF,4V,20%,X6S,CA 1        PVCCFA_EHV_FIVRA_CPU0   
                                  2        GND                     
C527             Q_CAP_C0603-47UF,2.5V,20%,X6S,A 1        PVCCIN_CPU0             
                                  2        GND                     
C528             Q_CAP_C0805-100UF,4V,20%,X6S,CA 1        PVCCINFAON_CPU0         
                                  2        GND                     
C529             Q_CAP_C0805-100UF,4V,20%,X6S,CA 1        PVCCFA_EHV_FIVRA_CPU0   
                                  2        GND                     
C530             Q_CAP_C0805-100UF,4V,20%,X6S,CA 1        PVCCINFAON_CPU0         
                                  2        GND                     
C531             Q_CAP_C0805-100UF,4V,20%,X6S,CA 1        PVCCINFAON_CPU0         
                                  2        GND                     
C532             Q_CAP_C0603-47UF,2.5V,20%,X6S,A 1        PVCCINFAON_CPU0         
                                  2        GND                     
C533             Q_CAP_C0603-47UF,2.5V,20%,X6S,A 1        PVCCINFAON_CPU0         
                                  2        GND                     
C534             Q_CAP_C0402-22UF,4V,20%,X6S,CHA 1        PVCCINFAON_CPU0         
                                  2        GND                     
C535             Q_CAP_C0805-22UF,16V,20%,X6S,CA 1        PGPPA_AUX               
                                  2        GND                     
C536             Q_CAP_0402-0.1UF,25V,10%,X7R,CA 1        P3V3_AUX                
                                  2        GND                     
C537             Q_CAP_0402-0.1UF,25V,10%,X7R,CA 1        P3V3_AUX                
                                  2        GND                     
C538             Q_CAP_0402-0.1UF,25V,10%,X7R,CA 1        P3V3_AUX                
                                  2        GND                     
C539             Q_CAP_0402-0.1UF,25V,10%,X7R,CA 1        P3V3_AUX                
                                  2        GND                     
C540             Q_CAP_0402-0.1UF,25V,10%,X7R,CA 1        P3V3_AUX                
                                  2        GND                     
C541             Q_CAP_C0402-1UF,25V,10%,X6S,CHA 1        P3V3_AUX                
                                  2        GND                     
C542             Q_CAP_C0402-1UF,25V,10%,X6S,CHA 1        P3V3_AUX                
                                  2        GND                     
C543             Q_CAP_0402-0.1UF,25V,10%,X7R,CA 1        P3V3_AUX                
                                  2        GND                     
C544             Q_CAP_0402-0.1UF,25V,10%,X7R,CA 1        P3V3_AUX                
                                  2        GND                     
C545             Q_CAP_C0402-1UF,25V,10%,X6S,CHA 1        P3V3_AUX                
                                  2        GND                     
C546             Q_CAP_C0402-1UF,25V,10%,X6S,CHA 1        P3V3_AUX                
                                  2        GND                     
C547             Q_CAP_C0402-1UF,25V,10%,X6S,CHA 1        P1V05_PCH_AUX           
                                  2        GND                     
C548             Q_CAP_0402-0.1UF,25V,10%,X7R,CA 1        JTAG_DBP_POWER_BTN_N    
                                  2        GND                     
C549             Q_CAP_0402-0.1UF,25V,10%,X7R,CA 1        JTAG_RST_DBP_RST_CO_N   
                                  2        GND                     
C550             Q_CAP_C0402-1UF,25V,10%,X6S,CHA 1        P1V8_PCH_AUX            
                                  2        GND                     
C551             Q_CAP_C0402-1UF,25V,10%,X6S,CHA 1        P3V3_AUX                
                                  2        GND                     
C552             Q_CAP_0402-0.1UF,25V,10%,X7R,CA 1        FM_CPU_FBRK_DEBUG_N     
                                  2        GND                     
C553             Q_CAP_0402-0.1UF,25V,10%,X7R,CA 1        P3V3_AUX                
                                  2        GND                     
C554             Q_CAP_0402-0.1UF,25V,10%,X7R,CA 1        P3V3_AUX                
                                  2        GND                     
C559             Q_CAP_0402-0.1UF,25V,10%,X7R,CA 1        PVNN_TERM_CPU0          
                                  2        GND                     
C560             Q_CAP_0402-0.1UF,25V,10%,X7R,CA 1        PVNN_TERM_CPU1          
                                  2        GND                     
C561             Q_CAP_0402-0.1UF,25V,10%,X7R,CA 1        P3V3_AUX                
                                  2        GND                     
C562             Q_CAP_0402-0.1UF,25V,10%,X7R,CA 1        P3V3_AUX                
                                  2        GND                     
C563             Q_CAP_C0805-10UF,25V,10%,X6S,CA 1        P3V3_AUX                
                                  2        GND                     
C564             Q_CAP_0402-0.1UF,25V,10%,X7R,CA 1        PU_USB_INT_P5V_EN_N     
                                  2        GND                     
C565             Q_CAP_0402-0.1UF,25V,10%,X7R,CA 1        USB3_9_TX_DN            
                                  2        USB3_9_TX_DN_C          
C566             Q_CAP_0402-0.1UF,25V,10%,X7R,CA 1        USB3_9_TX_DP            
                                  2        USB3_9_TX_DP_C          
C567             Q_CAP_0402-0.1UF,25V,10%,X7R,CA 1        PVNN_TERM_CPU0          
                                  2        GND                     
C568             Q_CAP_0402-0.1UF,25V,10%,X7R,CA 1        PVNN_TERM_CPU1          
                                  2        GND                     
C569             Q_CAP_0402-0.1UF,25V,10%,X7R,CA 1        P3V3_AUX                
                                  2        GND                     
C570             Q_CAP_0402-0.1UF,25V,10%,X7R,CA 1        P3V3_AUX                
                                  2        GND                     
C575             Q_CAP_C0402-100NF,50V,10%,X7R,A 1        P3V3_E1S_3_DVDT         
                                  2        GND                     
C578             Q_CAP_0402-0.1UF,25V,10%,X7R,CA 1        P3V3_AUX                
                                  2        GND                     
C579             Q_CAP_0402-0.1UF,25V,10%,X7R,CA 1        P3V3_AUX                
                                  2        GND                     
C580             Q_CAP_0402-0.1UF,25V,10%,X7R,CA 1        P3V3_AUX                
                                  2        GND                     
C581             Q_CAP_0402-0.1UF,25V,10%,X7R,CA 1        P3V3_AUX                
                                  2        GND                     
C582             Q_CAP_C0402-100NF,50V,10%,X7R,A 1        P3V3_OCP_DVDT_1         
                                  2        GND                     
C583             Q_CAP_C0402-1UF,16V,10%,X6S,CHA 1        P12V_AUX                
                                  2        GND                     
C586             Q_CAP_0402-0.1UF,25V,10%,X7R,CA 1        P12V_AUX                
                                  2        GND                     
C587             Q_CAP_C0805-10UF,25V,10%,X6S,CA 1        P3V3_OCP_SFF            
                                  2        GND                     
C588             Q_CAP_C0402-3900PF,50V,10%,X7RA 1        P12V_OCP_ITIMER_1       
                                  2        GND                     
C589             Q_CAP_C0402-1UF,16V,10%,X6S,CHA 1        P12V_OCP_SFF            
                                  2        GND                     
C590             Q_CAP_C0402-22UF,4V,20%,X6S,CHA 1        PVNN_MAIN_CPU0          
                                  2        GND                     
C591             Q_CAP_0402-3300PF,50V,10%,X7R,A 1        P12V_OCP_DVDT_1         
                                  2        GND                     
C592             Q_CAP_0402-0.1UF,25V,10%,X7R,CA 1        P3V3_AUX                
                                  2        GND                     
C593             Q_CAP_0402-0.1UF,25V,10%,X7R,CA 1        P3V3_AUX                
                                  2        GND                     
C605             Q_CAP_C0402-1UF,25V,10%,X6S,CHA 1        PGPPA_AUX               
                                  2        GND                     
C606             Q_CAP_C0402-1UF,25V,10%,X6S,CHA 1        PGPPA_AUX               
                                  2        GND                     
C607             Q_CAP_0402-0.1UF,25V,10%,X7R,CA 1        PGPPA_AUX               
                                  2        GND                     
C608             Q_CAP_0402-0.1UF,25V,10%,X7R,CA 1        PGPPA_AUX               
                                  2        GND                     
C609             Q_CAP_0402-0.1UF,25V,10%,X7R,CA 1        RTC_EXT_CAP             
                                  2        GND                     
C610             Q_CAP_C0402-1UF,25V,10%,X6S,CHA 1        RST_SRTCRST_N           
                                  2        GND                     
C611             Q_CAP_C0402-1UF,25V,10%,X6S,CHA 1        P3V3_RTC_AUX            
                                  2        GND                     
C613             Q_CAP_C0402-1UF,25V,10%,EMPTY,A 1        RST_PLD_CPU1_DRAM_GH_N  
                                  2        GND                     
C614             Q_CAP_C0402-1UF,25V,10%,EMPTY,A 1        RST_PLD_CPU1_DRAM_AB_N  
                                  2        GND                     
C615             Q_CAP_C0402-1UF,25V,10%,EMPTY,A 1        RST_PLD_CPU1_DRAM_CD_N  
                                  2        GND                     
C616             Q_CAP_C0402-1UF,25V,10%,EMPTY,A 1        RST_PLD_CPU1_DRAM_EF_N  
                                  2        GND                     
C621             Q_CAP_C0402-1UF,25V,10%,EMPTY,A 1        RST_PLD_CPU0_DRAM_GH_N  
                                  2        GND                     
C622             Q_CAP_C0402-1UF,25V,10%,EMPTY,A 1        RST_PLD_CPU0_DRAM_AB_N  
                                  2        GND                     
C623             Q_CAP_C0402-1UF,25V,10%,EMPTY,A 1        RST_PLD_CPU0_DRAM_CD_N  
                                  2        GND                     
C624             Q_CAP_C0402-1UF,25V,10%,EMPTY,A 1        RST_PLD_CPU0_DRAM_EF_N  
                                  2        GND                     
C629             Q_CAP_0402-0.1UF,25V,10%,X7R,CA 1        P3V3_AUX                
                                  2        GND                     
C630             Q_CAP_0402-0.1UF,25V,10%,X7R,CA 1        P3V3_AUX                
                                  2        GND                     
C631             Q_CAP_0402-0.1UF,25V,10%,X7R,CA 1        P3V3_AUX                
                                  2        GND                     
C632             Q_CAP_C0805-10UF,25V,10%,X6S,CA 1        P12V_FRONT_CPU          
                                  2        GND                     
C633             Q_CAP_C0805-22UF,25V,20%,X5R,CA 1        P5V                     
                                  2        GND                     
C634             Q_CAP_SATA6G_C0402-SATA6G_0.01A 1        SATA_P11_TX_C_DP        
                                  2        SATA_P11_TX_DP          
C635             Q_CAP_SATA6G_C0402-SATA6G_0.01A 1        SATA_P11_TX_C_DN        
                                  2        SATA_P11_TX_DN          
C636             Q_CAP_SATA6G_C0402-SATA6G_0.01A 1        SATA_P11_RX_C_DN        
                                  2        SATA_P11_RX_DN          
C637             Q_CAP_SATA6G_C0402-SATA6G_0.01A 1        SATA_P11_RX_C_DP        
                                  2        SATA_P11_RX_DP          
C638             Q_CAP_0402-0.1UF,25V,10%,X7R,CA 1        P5V                     
                                  2        GND                     
C639             Q_CAP_0402-0.1UF,25V,10%,X7R,CA 1        P3V3_AUX                
                                  2        GND                     
C640             Q_CAP_0402-0.1UF,25V,10%,X7R,CA 1        P3V3_AUX                
                                  2        GND                     
C641             Q_CAP_0402-0.1UF,25V,10%,X7R,CA 1        P3V3_AUX                
                                  2        GND                     
C643             Q_CAP_DIFFBUS_C0402-DIFF BUS_0A 1        P3E_PCH_BMC_TX_DP       
                                  2        P3E_PCH_BMC_TX_C_DP     
C644             Q_CAP_DIFFBUS_C0402-DIFF BUS_0A 1        P3E_PCH_BMC_TX_DN       
                                  2        P3E_PCH_BMC_TX_C_DN     
C678             Q_CAP_DIFFBUS_C0201-DIFF BUS_0A 1        P5E_CPU1_PE4_TX_C_DN<15>
                                  2        P5E_CPU1_PE4_TX_DN<15>  
C679             Q_CAP_DIFFBUS_C0201-DIFF BUS_0A 1        P5E_CPU1_PE4_TX_C_DP<15>
                                  2        P5E_CPU1_PE4_TX_DP<15>  
C680             Q_CAP_DIFFBUS_C0201-DIFF BUS_0A 1        P5E_CPU1_PE4_TX_C_DN<14>
                                  2        P5E_CPU1_PE4_TX_DN<14>  
C681             Q_CAP_DIFFBUS_C0201-DIFF BUS_0A 1        P5E_CPU1_PE4_TX_C_DP<14>
                                  2        P5E_CPU1_PE4_TX_DP<14>  
C682             Q_CAP_DIFFBUS_C0201-DIFF BUS_0A 1        P5E_CPU1_PE4_TX_C_DN<13>
                                  2        P5E_CPU1_PE4_TX_DN<13>  
C683             Q_CAP_DIFFBUS_C0201-DIFF BUS_0A 1        P5E_CPU1_PE4_TX_C_DP<13>
                                  2        P5E_CPU1_PE4_TX_DP<13>  
C684             Q_CAP_DIFFBUS_C0201-DIFF BUS_0A 1        P5E_CPU1_PE4_TX_C_DN<12>
                                  2        P5E_CPU1_PE4_TX_DN<12>  
C685             Q_CAP_DIFFBUS_C0201-DIFF BUS_0A 1        P5E_CPU1_PE4_TX_C_DP<12>
                                  2        P5E_CPU1_PE4_TX_DP<12>  
C686             Q_CAP_DIFFBUS_C0201-DIFF BUS_0A 1        P5E_CPU1_PE4_TX_C_DN<11>
                                  2        P5E_CPU1_PE4_TX_DN<11>  
C687             Q_CAP_DIFFBUS_C0201-DIFF BUS_0A 1        P5E_CPU1_PE4_TX_C_DP<11>
                                  2        P5E_CPU1_PE4_TX_DP<11>  
C688             Q_CAP_DIFFBUS_C0201-DIFF BUS_0A 1        P5E_CPU1_PE4_TX_C_DN<10>
                                  2        P5E_CPU1_PE4_TX_DN<10>  
C689             Q_CAP_DIFFBUS_C0201-DIFF BUS_0A 1        P5E_CPU1_PE4_TX_C_DP<10>
                                  2        P5E_CPU1_PE4_TX_DP<10>  
C690             Q_CAP_DIFFBUS_C0201-DIFF BUS_0A 1        P5E_CPU1_PE4_TX_C_DN<9> 
                                  2        P5E_CPU1_PE4_TX_DN<9>   
C691             Q_CAP_DIFFBUS_C0201-DIFF BUS_0A 1        P5E_CPU1_PE4_TX_C_DP<9> 
                                  2        P5E_CPU1_PE4_TX_DP<9>   
C692             Q_CAP_DIFFBUS_C0201-DIFF BUS_0A 1        P5E_CPU1_PE4_TX_C_DN<8> 
                                  2        P5E_CPU1_PE4_TX_DN<8>   
C693             Q_CAP_DIFFBUS_C0201-DIFF BUS_0A 1        P5E_CPU1_PE4_TX_C_DP<8> 
                                  2        P5E_CPU1_PE4_TX_DP<8>   
C694             Q_CAP_DIFFBUS_C0201-DIFF BUS_0A 1        P5E_CPU1_PE4_TX_C_DN<7> 
                                  2        P5E_CPU1_PE4_TX_DN<7>   
C695             Q_CAP_DIFFBUS_C0201-DIFF BUS_0A 1        P5E_CPU1_PE4_TX_C_DP<7> 
                                  2        P5E_CPU1_PE4_TX_DP<7>   
C696             Q_CAP_DIFFBUS_C0201-DIFF BUS_0A 1        P5E_CPU1_PE4_TX_C_DN<6> 
                                  2        P5E_CPU1_PE4_TX_DN<6>   
C697             Q_CAP_DIFFBUS_C0201-DIFF BUS_0A 1        P5E_CPU1_PE4_TX_C_DP<6> 
                                  2        P5E_CPU1_PE4_TX_DP<6>   
C698             Q_CAP_DIFFBUS_C0201-DIFF BUS_0A 1        P5E_CPU1_PE4_TX_C_DN<5> 
                                  2        P5E_CPU1_PE4_TX_DN<5>   
C699             Q_CAP_DIFFBUS_C0201-DIFF BUS_0A 1        P5E_CPU1_PE4_TX_C_DP<5> 
                                  2        P5E_CPU1_PE4_TX_DP<5>   
C700             Q_CAP_DIFFBUS_C0201-DIFF BUS_0A 1        P5E_CPU1_PE4_TX_C_DN<4> 
                                  2        P5E_CPU1_PE4_TX_DN<4>   
C701             Q_CAP_DIFFBUS_C0201-DIFF BUS_0A 1        P5E_CPU1_PE4_TX_C_DP<4> 
                                  2        P5E_CPU1_PE4_TX_DP<4>   
C702             Q_CAP_DIFFBUS_C0201-DIFF BUS_0A 1        P5E_CPU1_PE4_TX_C_DN<3> 
                                  2        P5E_CPU1_PE4_TX_DN<3>   
C703             Q_CAP_DIFFBUS_C0201-DIFF BUS_0A 1        P5E_CPU1_PE4_TX_C_DP<3> 
                                  2        P5E_CPU1_PE4_TX_DP<3>   
C704             Q_CAP_DIFFBUS_C0201-DIFF BUS_0A 1        P5E_CPU1_PE4_TX_C_DN<2> 
                                  2        P5E_CPU1_PE4_TX_DN<2>   
C705             Q_CAP_DIFFBUS_C0201-DIFF BUS_0A 1        P5E_CPU1_PE4_TX_C_DP<2> 
                                  2        P5E_CPU1_PE4_TX_DP<2>   
C706             Q_CAP_DIFFBUS_C0201-DIFF BUS_0A 1        P5E_CPU1_PE4_TX_C_DN<1> 
                                  2        P5E_CPU1_PE4_TX_DN<1>   
C707             Q_CAP_DIFFBUS_C0201-DIFF BUS_0A 1        P5E_CPU1_PE4_TX_C_DP<1> 
                                  2        P5E_CPU1_PE4_TX_DP<1>   
C708             Q_CAP_DIFFBUS_C0201-DIFF BUS_0A 1        P5E_CPU1_PE4_TX_C_DN<0> 
                                  2        P5E_CPU1_PE4_TX_DN<0>   
C709             Q_CAP_DIFFBUS_C0201-DIFF BUS_0A 1        P5E_CPU1_PE4_TX_C_DP<0> 
                                  2        P5E_CPU1_PE4_TX_DP<0>   
C710             Q_CAP_DIFFBUS_C0201-DIFF BUS_0A 1        P5E_CPU1_PE1_TX_C_DN<15>
                                  2        P5E_CPU1_PE1_TX_DN<15>  
C711             Q_CAP_DIFFBUS_C0201-DIFF BUS_0A 1        P5E_CPU1_PE1_TX_C_DP<15>
                                  2        P5E_CPU1_PE1_TX_DP<15>  
C712             Q_CAP_DIFFBUS_C0201-DIFF BUS_0A 1        P5E_CPU1_PE1_TX_C_DN<14>
                                  2        P5E_CPU1_PE1_TX_DN<14>  
C713             Q_CAP_DIFFBUS_C0201-DIFF BUS_0A 1        P5E_CPU1_PE1_TX_C_DP<14>
                                  2        P5E_CPU1_PE1_TX_DP<14>  
C714             Q_CAP_DIFFBUS_C0201-DIFF BUS_0A 1        P5E_CPU1_PE1_TX_C_DN<13>
                                  2        P5E_CPU1_PE1_TX_DN<13>  
C715             Q_CAP_DIFFBUS_C0201-DIFF BUS_0A 1        P5E_CPU1_PE1_TX_C_DP<13>
                                  2        P5E_CPU1_PE1_TX_DP<13>  
C716             Q_CAP_DIFFBUS_C0201-DIFF BUS_0A 1        P5E_CPU1_PE1_TX_C_DN<12>
                                  2        P5E_CPU1_PE1_TX_DN<12>  
C717             Q_CAP_DIFFBUS_C0201-DIFF BUS_0A 1        P5E_CPU1_PE1_TX_C_DP<12>
                                  2        P5E_CPU1_PE1_TX_DP<12>  
C718             Q_CAP_DIFFBUS_C0201-DIFF BUS_0A 1        P5E_CPU1_PE1_TX_C_DN<11>
                                  2        P5E_CPU1_PE1_TX_DN<11>  
C719             Q_CAP_DIFFBUS_C0201-DIFF BUS_0A 1        P5E_CPU1_PE1_TX_C_DP<11>
                                  2        P5E_CPU1_PE1_TX_DP<11>  
C720             Q_CAP_DIFFBUS_C0201-DIFF BUS_0A 1        P5E_CPU1_PE1_TX_C_DN<10>
                                  2        P5E_CPU1_PE1_TX_DN<10>  
C721             Q_CAP_DIFFBUS_C0201-DIFF BUS_0A 1        P5E_CPU1_PE1_TX_C_DP<10>
                                  2        P5E_CPU1_PE1_TX_DP<10>  
C722             Q_CAP_DIFFBUS_C0201-DIFF BUS_0A 1        P5E_CPU1_PE1_TX_C_DN<9> 
                                  2        P5E_CPU1_PE1_TX_DN<9>   
C723             Q_CAP_DIFFBUS_C0201-DIFF BUS_0A 1        P5E_CPU1_PE1_TX_C_DP<9> 
                                  2        P5E_CPU1_PE1_TX_DP<9>   
C724             Q_CAP_DIFFBUS_C0201-DIFF BUS_0A 1        P5E_CPU1_PE1_TX_C_DN<8> 
                                  2        P5E_CPU1_PE1_TX_DN<8>   
C725             Q_CAP_DIFFBUS_C0201-DIFF BUS_0A 1        P5E_CPU1_PE1_TX_C_DP<8> 
                                  2        P5E_CPU1_PE1_TX_DP<8>   
C726             Q_CAP_DIFFBUS_C0201-DIFF BUS_0A 1        P5E_CPU1_PE1_TX_C_DN<7> 
                                  2        P5E_CPU1_PE1_TX_DN<7>   
C727             Q_CAP_DIFFBUS_C0201-DIFF BUS_0A 1        P5E_CPU1_PE1_TX_C_DP<7> 
                                  2        P5E_CPU1_PE1_TX_DP<7>   
C728             Q_CAP_DIFFBUS_C0201-DIFF BUS_0A 1        P5E_CPU1_PE1_TX_C_DN<6> 
                                  2        P5E_CPU1_PE1_TX_DN<6>   
C729             Q_CAP_DIFFBUS_C0201-DIFF BUS_0A 1        P5E_CPU1_PE1_TX_C_DP<6> 
                                  2        P5E_CPU1_PE1_TX_DP<6>   
C730             Q_CAP_DIFFBUS_C0201-DIFF BUS_0A 1        P5E_CPU1_PE1_TX_C_DN<5> 
                                  2        P5E_CPU1_PE1_TX_DN<5>   
C731             Q_CAP_DIFFBUS_C0201-DIFF BUS_0A 1        P5E_CPU1_PE1_TX_C_DP<5> 
                                  2        P5E_CPU1_PE1_TX_DP<5>   
C732             Q_CAP_DIFFBUS_C0201-DIFF BUS_0A 1        P5E_CPU1_PE1_TX_C_DN<4> 
                                  2        P5E_CPU1_PE1_TX_DN<4>   
C733             Q_CAP_DIFFBUS_C0201-DIFF BUS_0A 1        P5E_CPU1_PE1_TX_C_DP<4> 
                                  2        P5E_CPU1_PE1_TX_DP<4>   
C734             Q_CAP_DIFFBUS_C0201-DIFF BUS_0A 1        P5E_CPU1_PE1_TX_C_DN<3> 
                                  2        P5E_CPU1_PE1_TX_DN<3>   
C735             Q_CAP_DIFFBUS_C0201-DIFF BUS_0A 1        P5E_CPU1_PE1_TX_C_DP<3> 
                                  2        P5E_CPU1_PE1_TX_DP<3>   
C736             Q_CAP_DIFFBUS_C0201-DIFF BUS_0A 1        P5E_CPU1_PE1_TX_C_DN<2> 
                                  2        P5E_CPU1_PE1_TX_DN<2>   
C737             Q_CAP_DIFFBUS_C0201-DIFF BUS_0A 1        P5E_CPU1_PE1_TX_C_DP<2> 
                                  2        P5E_CPU1_PE1_TX_DP<2>   
C738             Q_CAP_DIFFBUS_C0201-DIFF BUS_0A 1        P5E_CPU1_PE1_TX_C_DN<1> 
                                  2        P5E_CPU1_PE1_TX_DN<1>   
C739             Q_CAP_DIFFBUS_C0201-DIFF BUS_0A 1        P5E_CPU1_PE1_TX_C_DP<1> 
                                  2        P5E_CPU1_PE1_TX_DP<1>   
C740             Q_CAP_DIFFBUS_C0201-DIFF BUS_0A 1        P5E_CPU1_PE1_TX_C_DN<0> 
                                  2        P5E_CPU1_PE1_TX_DN<0>   
C741             Q_CAP_DIFFBUS_C0201-DIFF BUS_0A 1        P5E_CPU1_PE1_TX_C_DP<0> 
                                  2        P5E_CPU1_PE1_TX_DP<0>   
C742             Q_CAP_DIFFBUS_C0201-DIFF BUS_0A 1        P5E_CPU1_PE2_TX_C_DN<15>
                                  2        P5E_CPU1_PE2_TX_DN<15>  
C743             Q_CAP_DIFFBUS_C0201-DIFF BUS_0A 1        P5E_CPU1_PE2_TX_C_DP<15>
                                  2        P5E_CPU1_PE2_TX_DP<15>  
C744             Q_CAP_DIFFBUS_C0201-DIFF BUS_0A 1        P5E_CPU1_PE2_TX_C_DN<14>
                                  2        P5E_CPU1_PE2_TX_DN<14>  
C745             Q_CAP_DIFFBUS_C0201-DIFF BUS_0A 1        P5E_CPU1_PE2_TX_C_DP<14>
                                  2        P5E_CPU1_PE2_TX_DP<14>  
C746             Q_CAP_DIFFBUS_C0201-DIFF BUS_0A 1        P5E_CPU1_PE2_TX_C_DN<13>
                                  2        P5E_CPU1_PE2_TX_DN<13>  
C747             Q_CAP_DIFFBUS_C0201-DIFF BUS_0A 1        P5E_CPU1_PE2_TX_C_DP<13>
                                  2        P5E_CPU1_PE2_TX_DP<13>  
C748             Q_CAP_DIFFBUS_C0201-DIFF BUS_0A 1        P5E_CPU1_PE2_TX_C_DN<12>
                                  2        P5E_CPU1_PE2_TX_DN<12>  
C749             Q_CAP_DIFFBUS_C0201-DIFF BUS_0A 1        P5E_CPU1_PE2_TX_C_DP<12>
                                  2        P5E_CPU1_PE2_TX_DP<12>  
C750             Q_CAP_DIFFBUS_C0201-DIFF BUS_0A 1        P5E_CPU1_PE2_TX_C_DN<11>
                                  2        P5E_CPU1_PE2_TX_DN<11>  
C751             Q_CAP_DIFFBUS_C0201-DIFF BUS_0A 1        P5E_CPU1_PE2_TX_C_DP<11>
                                  2        P5E_CPU1_PE2_TX_DP<11>  
C752             Q_CAP_DIFFBUS_C0201-DIFF BUS_0A 1        P5E_CPU1_PE2_TX_C_DN<10>
                                  2        P5E_CPU1_PE2_TX_DN<10>  
C753             Q_CAP_DIFFBUS_C0201-DIFF BUS_0A 1        P5E_CPU1_PE2_TX_C_DP<10>
                                  2        P5E_CPU1_PE2_TX_DP<10>  
C754             Q_CAP_DIFFBUS_C0201-DIFF BUS_0A 1        P5E_CPU1_PE2_TX_C_DN<9> 
                                  2        P5E_CPU1_PE2_TX_DN<9>   
C755             Q_CAP_DIFFBUS_C0201-DIFF BUS_0A 1        P5E_CPU1_PE2_TX_C_DP<9> 
                                  2        P5E_CPU1_PE2_TX_DP<9>   
C756             Q_CAP_DIFFBUS_C0201-DIFF BUS_0A 1        P5E_CPU1_PE2_TX_C_DN<8> 
                                  2        P5E_CPU1_PE2_TX_DN<8>   
C757             Q_CAP_DIFFBUS_C0201-DIFF BUS_0A 1        P5E_CPU1_PE2_TX_C_DP<8> 
                                  2        P5E_CPU1_PE2_TX_DP<8>   
C758             Q_CAP_DIFFBUS_C0201-DIFF BUS_0A 1        P5E_CPU1_PE2_TX_C_DN<7> 
                                  2        P5E_CPU1_PE2_TX_DN<7>   
C759             Q_CAP_DIFFBUS_C0201-DIFF BUS_0A 1        P5E_CPU1_PE2_TX_C_DP<7> 
                                  2        P5E_CPU1_PE2_TX_DP<7>   
C760             Q_CAP_DIFFBUS_C0201-DIFF BUS_0A 1        P5E_CPU1_PE2_TX_C_DN<6> 
                                  2        P5E_CPU1_PE2_TX_DN<6>   
C761             Q_CAP_DIFFBUS_C0201-DIFF BUS_0A 1        P5E_CPU1_PE2_TX_C_DP<6> 
                                  2        P5E_CPU1_PE2_TX_DP<6>   
C762             Q_CAP_DIFFBUS_C0201-DIFF BUS_0A 1        P5E_CPU1_PE2_TX_C_DN<5> 
                                  2        P5E_CPU1_PE2_TX_DN<5>   
C763             Q_CAP_DIFFBUS_C0201-DIFF BUS_0A 1        P5E_CPU1_PE2_TX_C_DP<5> 
                                  2        P5E_CPU1_PE2_TX_DP<5>   
C764             Q_CAP_DIFFBUS_C0201-DIFF BUS_0A 1        P5E_CPU1_PE2_TX_C_DN<4> 
                                  2        P5E_CPU1_PE2_TX_DN<4>   
C765             Q_CAP_DIFFBUS_C0201-DIFF BUS_0A 1        P5E_CPU1_PE2_TX_C_DP<4> 
                                  2        P5E_CPU1_PE2_TX_DP<4>   
C766             Q_CAP_DIFFBUS_C0201-DIFF BUS_0A 1        P5E_CPU1_PE2_TX_C_DN<3> 
                                  2        P5E_CPU1_PE2_TX_DN<3>   
C767             Q_CAP_DIFFBUS_C0201-DIFF BUS_0A 1        P5E_CPU1_PE2_TX_C_DP<3> 
                                  2        P5E_CPU1_PE2_TX_DP<3>   
C768             Q_CAP_DIFFBUS_C0201-DIFF BUS_0A 1        P5E_CPU1_PE2_TX_C_DN<2> 
                                  2        P5E_CPU1_PE2_TX_DN<2>   
C769             Q_CAP_DIFFBUS_C0201-DIFF BUS_0A 1        P5E_CPU1_PE2_TX_C_DP<2> 
                                  2        P5E_CPU1_PE2_TX_DP<2>   
C770             Q_CAP_DIFFBUS_C0201-DIFF BUS_0A 1        P5E_CPU1_PE2_TX_C_DN<1> 
                                  2        P5E_CPU1_PE2_TX_DN<1>   
C771             Q_CAP_DIFFBUS_C0201-DIFF BUS_0A 1        P5E_CPU1_PE2_TX_C_DP<1> 
                                  2        P5E_CPU1_PE2_TX_DP<1>   
C772             Q_CAP_DIFFBUS_C0201-DIFF BUS_0A 1        P5E_CPU1_PE2_TX_C_DN<0> 
                                  2        P5E_CPU1_PE2_TX_DN<0>   
C773             Q_CAP_DIFFBUS_C0201-DIFF BUS_0A 1        P5E_CPU1_PE2_TX_C_DP<0> 
                                  2        P5E_CPU1_PE2_TX_DP<0>   
C806             Q_CAP_DIFFBUS_C0201-DIFF BUS_0A 1        P5E_CPU1_PE0_TX_C_DN<15>
                                  2        P5E_CPU1_PE0_TX_DN<15>  
C807             Q_CAP_DIFFBUS_C0201-DIFF BUS_0A 1        P5E_CPU1_PE0_TX_C_DP<15>
                                  2        P5E_CPU1_PE0_TX_DP<15>  
C808             Q_CAP_DIFFBUS_C0201-DIFF BUS_0A 1        P5E_CPU1_PE0_TX_C_DN<14>
                                  2        P5E_CPU1_PE0_TX_DN<14>  
C809             Q_CAP_DIFFBUS_C0201-DIFF BUS_0A 1        P5E_CPU1_PE0_TX_C_DP<14>
                                  2        P5E_CPU1_PE0_TX_DP<14>  
C810             Q_CAP_DIFFBUS_C0201-DIFF BUS_0A 1        P5E_CPU1_PE0_TX_C_DN<13>
                                  2        P5E_CPU1_PE0_TX_DN<13>  
C811             Q_CAP_DIFFBUS_C0201-DIFF BUS_0A 1        P5E_CPU1_PE0_TX_C_DP<13>
                                  2        P5E_CPU1_PE0_TX_DP<13>  
C812             Q_CAP_DIFFBUS_C0201-DIFF BUS_0A 1        P5E_CPU1_PE0_TX_C_DN<12>
                                  2        P5E_CPU1_PE0_TX_DN<12>  
C813             Q_CAP_DIFFBUS_C0201-DIFF BUS_0A 1        P5E_CPU1_PE0_TX_C_DP<12>
                                  2        P5E_CPU1_PE0_TX_DP<12>  
C814             Q_CAP_DIFFBUS_C0201-DIFF BUS_0A 1        P5E_CPU1_PE0_TX_C_DN<11>
                                  2        P5E_CPU1_PE0_TX_DN<11>  
C815             Q_CAP_DIFFBUS_C0201-DIFF BUS_0A 1        P5E_CPU1_PE0_TX_C_DP<11>
                                  2        P5E_CPU1_PE0_TX_DP<11>  
C816             Q_CAP_DIFFBUS_C0201-DIFF BUS_0A 1        P5E_CPU1_PE0_TX_C_DN<10>
                                  2        P5E_CPU1_PE0_TX_DN<10>  
C817             Q_CAP_DIFFBUS_C0201-DIFF BUS_0A 1        P5E_CPU1_PE0_TX_C_DP<10>
                                  2        P5E_CPU1_PE0_TX_DP<10>  
C818             Q_CAP_DIFFBUS_C0201-DIFF BUS_0A 1        P5E_CPU1_PE0_TX_C_DN<9> 
                                  2        P5E_CPU1_PE0_TX_DN<9>   
C819             Q_CAP_DIFFBUS_C0201-DIFF BUS_0A 1        P5E_CPU1_PE0_TX_C_DP<9> 
                                  2        P5E_CPU1_PE0_TX_DP<9>   
C820             Q_CAP_DIFFBUS_C0201-DIFF BUS_0A 1        P5E_CPU1_PE0_TX_C_DN<8> 
                                  2        P5E_CPU1_PE0_TX_DN<8>   
C821             Q_CAP_DIFFBUS_C0201-DIFF BUS_0A 1        P5E_CPU1_PE0_TX_C_DP<8> 
                                  2        P5E_CPU1_PE0_TX_DP<8>   
C822             Q_CAP_DIFFBUS_C0201-DIFF BUS_0A 1        P5E_CPU1_PE0_TX_C_DN<7> 
                                  2        P5E_CPU1_PE0_TX_DN<7>   
C823             Q_CAP_DIFFBUS_C0201-DIFF BUS_0A 1        P5E_CPU1_PE0_TX_C_DP<7> 
                                  2        P5E_CPU1_PE0_TX_DP<7>   
C824             Q_CAP_DIFFBUS_C0201-DIFF BUS_0A 1        P5E_CPU1_PE0_TX_C_DN<6> 
                                  2        P5E_CPU1_PE0_TX_DN<6>   
C825             Q_CAP_DIFFBUS_C0201-DIFF BUS_0A 1        P5E_CPU1_PE0_TX_C_DP<6> 
                                  2        P5E_CPU1_PE0_TX_DP<6>   
C826             Q_CAP_DIFFBUS_C0201-DIFF BUS_0A 1        P5E_CPU1_PE0_TX_C_DN<5> 
                                  2        P5E_CPU1_PE0_TX_DN<5>   
C827             Q_CAP_DIFFBUS_C0201-DIFF BUS_0A 1        P5E_CPU1_PE0_TX_C_DP<5> 
                                  2        P5E_CPU1_PE0_TX_DP<5>   
C828             Q_CAP_DIFFBUS_C0201-DIFF BUS_0A 1        P5E_CPU1_PE0_TX_C_DN<4> 
                                  2        P5E_CPU1_PE0_TX_DN<4>   
C829             Q_CAP_DIFFBUS_C0201-DIFF BUS_0A 1        P5E_CPU1_PE0_TX_C_DP<4> 
                                  2        P5E_CPU1_PE0_TX_DP<4>   
C830             Q_CAP_DIFFBUS_C0201-DIFF BUS_0A 1        P5E_CPU1_PE0_TX_C_DN<3> 
                                  2        P5E_CPU1_PE0_TX_DN<3>   
C831             Q_CAP_DIFFBUS_C0201-DIFF BUS_0A 1        P5E_CPU1_PE0_TX_C_DP<3> 
                                  2        P5E_CPU1_PE0_TX_DP<3>   
C832             Q_CAP_DIFFBUS_C0201-DIFF BUS_0A 1        P5E_CPU1_PE0_TX_C_DN<2> 
                                  2        P5E_CPU1_PE0_TX_DN<2>   
C833             Q_CAP_DIFFBUS_C0201-DIFF BUS_0A 1        P5E_CPU1_PE0_TX_C_DP<2> 
                                  2        P5E_CPU1_PE0_TX_DP<2>   
C834             Q_CAP_DIFFBUS_C0201-DIFF BUS_0A 1        P5E_CPU1_PE0_TX_C_DN<1> 
                                  2        P5E_CPU1_PE0_TX_DN<1>   
C835             Q_CAP_DIFFBUS_C0201-DIFF BUS_0A 1        P5E_CPU1_PE0_TX_C_DP<1> 
                                  2        P5E_CPU1_PE0_TX_DP<1>   
C836             Q_CAP_DIFFBUS_C0201-DIFF BUS_0A 1        P5E_CPU1_PE0_TX_C_DN<0> 
                                  2        P5E_CPU1_PE0_TX_DN<0>   
C837             Q_CAP_DIFFBUS_C0201-DIFF BUS_0A 1        P5E_CPU1_PE0_TX_C_DP<0> 
                                  2        P5E_CPU1_PE0_TX_DP<0>   
C838             Q_CAP_DIFFBUS_C0201-DIFF BUS_0A 1        P5E_CPU0_PE2_TX_C_DN<15>
                                  2        P5E_CPU0_PE2_TX_DN<15>  
C839             Q_CAP_DIFFBUS_C0201-DIFF BUS_0A 1        P5E_CPU0_PE2_TX_C_DP<15>
                                  2        P5E_CPU0_PE2_TX_DP<15>  
C840             Q_CAP_DIFFBUS_C0201-DIFF BUS_0A 1        P5E_CPU0_PE2_TX_C_DN<14>
                                  2        P5E_CPU0_PE2_TX_DN<14>  
C841             Q_CAP_DIFFBUS_C0201-DIFF BUS_0A 1        P5E_CPU0_PE2_TX_C_DP<14>
                                  2        P5E_CPU0_PE2_TX_DP<14>  
C842             Q_CAP_DIFFBUS_C0201-DIFF BUS_0A 1        P5E_CPU0_PE2_TX_C_DN<13>
                                  2        P5E_CPU0_PE2_TX_DN<13>  
C843             Q_CAP_DIFFBUS_C0201-DIFF BUS_0A 1        P5E_CPU0_PE2_TX_C_DP<13>
                                  2        P5E_CPU0_PE2_TX_DP<13>  
C844             Q_CAP_DIFFBUS_C0201-DIFF BUS_0A 1        P5E_CPU0_PE2_TX_C_DN<12>
                                  2        P5E_CPU0_PE2_TX_DN<12>  
C845             Q_CAP_DIFFBUS_C0201-DIFF BUS_0A 1        P5E_CPU0_PE2_TX_C_DP<12>
                                  2        P5E_CPU0_PE2_TX_DP<12>  
C846             Q_CAP_DIFFBUS_C0201-DIFF BUS_0A 1        P5E_CPU0_PE2_TX_C_DN<11>
                                  2        P5E_CPU0_PE2_TX_DN<11>  
C847             Q_CAP_DIFFBUS_C0201-DIFF BUS_0A 1        P5E_CPU0_PE2_TX_C_DP<11>
                                  2        P5E_CPU0_PE2_TX_DP<11>  
C848             Q_CAP_DIFFBUS_C0201-DIFF BUS_0A 1        P5E_CPU0_PE2_TX_C_DN<10>
                                  2        P5E_CPU0_PE2_TX_DN<10>  
C849             Q_CAP_DIFFBUS_C0201-DIFF BUS_0A 1        P5E_CPU0_PE2_TX_C_DP<10>
                                  2        P5E_CPU0_PE2_TX_DP<10>  
C850             Q_CAP_DIFFBUS_C0201-DIFF BUS_0A 1        P5E_CPU0_PE2_TX_C_DN<9> 
                                  2        P5E_CPU0_PE2_TX_DN<9>   
C851             Q_CAP_DIFFBUS_C0201-DIFF BUS_0A 1        P5E_CPU0_PE2_TX_C_DP<9> 
                                  2        P5E_CPU0_PE2_TX_DP<9>   
C852             Q_CAP_DIFFBUS_C0201-DIFF BUS_0A 1        P5E_CPU0_PE2_TX_C_DN<8> 
                                  2        P5E_CPU0_PE2_TX_DN<8>   
C853             Q_CAP_DIFFBUS_C0201-DIFF BUS_0A 1        P5E_CPU0_PE2_TX_C_DP<8> 
                                  2        P5E_CPU0_PE2_TX_DP<8>   
C854             Q_CAP_DIFFBUS_C0201-DIFF BUS_0A 1        P5E_CPU0_PE2_TX_C_DN<7> 
                                  2        P5E_CPU0_PE2_TX_DN<7>   
C855             Q_CAP_DIFFBUS_C0201-DIFF BUS_0A 1        P5E_CPU0_PE2_TX_C_DP<7> 
                                  2        P5E_CPU0_PE2_TX_DP<7>   
C856             Q_CAP_DIFFBUS_C0201-DIFF BUS_0A 1        P5E_CPU0_PE2_TX_C_DN<6> 
                                  2        P5E_CPU0_PE2_TX_DN<6>   
C857             Q_CAP_DIFFBUS_C0201-DIFF BUS_0A 1        P5E_CPU0_PE2_TX_C_DP<6> 
                                  2        P5E_CPU0_PE2_TX_DP<6>   
C858             Q_CAP_DIFFBUS_C0201-DIFF BUS_0A 1        P5E_CPU0_PE2_TX_C_DN<5> 
                                  2        P5E_CPU0_PE2_TX_DN<5>   
C859             Q_CAP_DIFFBUS_C0201-DIFF BUS_0A 1        P5E_CPU0_PE2_TX_C_DP<5> 
                                  2        P5E_CPU0_PE2_TX_DP<5>   
C860             Q_CAP_DIFFBUS_C0201-DIFF BUS_0A 1        P5E_CPU0_PE2_TX_C_DN<4> 
                                  2        P5E_CPU0_PE2_TX_DN<4>   
C861             Q_CAP_DIFFBUS_C0201-DIFF BUS_0A 1        P5E_CPU0_PE2_TX_C_DP<4> 
                                  2        P5E_CPU0_PE2_TX_DP<4>   
C862             Q_CAP_DIFFBUS_C0201-DIFF BUS_0A 1        P5E_CPU0_PE2_TX_C_DN<3> 
                                  2        P5E_CPU0_PE2_TX_DN<3>   
C863             Q_CAP_DIFFBUS_C0201-DIFF BUS_0A 1        P5E_CPU0_PE2_TX_C_DP<3> 
                                  2        P5E_CPU0_PE2_TX_DP<3>   
C864             Q_CAP_DIFFBUS_C0201-DIFF BUS_0A 1        P5E_CPU0_PE2_TX_C_DN<2> 
                                  2        P5E_CPU0_PE2_TX_DN<2>   
C865             Q_CAP_DIFFBUS_C0201-DIFF BUS_0A 1        P5E_CPU0_PE2_TX_C_DP<2> 
                                  2        P5E_CPU0_PE2_TX_DP<2>   
C866             Q_CAP_DIFFBUS_C0201-DIFF BUS_0A 1        P5E_CPU0_PE2_TX_C_DN<1> 
                                  2        P5E_CPU0_PE2_TX_DN<1>   
C867             Q_CAP_DIFFBUS_C0201-DIFF BUS_0A 1        P5E_CPU0_PE2_TX_C_DP<1> 
                                  2        P5E_CPU0_PE2_TX_DP<1>   
C868             Q_CAP_DIFFBUS_C0201-DIFF BUS_0A 1        P5E_CPU0_PE2_TX_C_DN<0> 
                                  2        P5E_CPU0_PE2_TX_DN<0>   
C869             Q_CAP_DIFFBUS_C0201-DIFF BUS_0A 1        P5E_CPU0_PE2_TX_C_DP<0> 
                                  2        P5E_CPU0_PE2_TX_DP<0>   
C870             Q_CAP_DIFFBUS_C0201-DIFF BUS_0A 1        P5E_CPU0_PE3_TX_C_DN<15>
                                  2        P5E_CPU0_PE3_TX_DN<15>  
C871             Q_CAP_DIFFBUS_C0201-DIFF BUS_0A 1        P5E_CPU0_PE3_TX_C_DP<15>
                                  2        P5E_CPU0_PE3_TX_DP<15>  
C872             Q_CAP_DIFFBUS_C0201-DIFF BUS_0A 1        P5E_CPU0_PE3_TX_C_DN<14>
                                  2        P5E_CPU0_PE3_TX_DN<14>  
C873             Q_CAP_DIFFBUS_C0201-DIFF BUS_0A 1        P5E_CPU0_PE3_TX_C_DP<14>
                                  2        P5E_CPU0_PE3_TX_DP<14>  
C874             Q_CAP_DIFFBUS_C0201-DIFF BUS_0A 1        P5E_CPU0_PE3_TX_C_DN<13>
                                  2        P5E_CPU0_PE3_TX_DN<13>  
C875             Q_CAP_DIFFBUS_C0201-DIFF BUS_0A 1        P5E_CPU0_PE3_TX_C_DP<13>
                                  2        P5E_CPU0_PE3_TX_DP<13>  
C876             Q_CAP_DIFFBUS_C0201-DIFF BUS_0A 1        P5E_CPU0_PE3_TX_C_DN<12>
                                  2        P5E_CPU0_PE3_TX_DN<12>  
C877             Q_CAP_DIFFBUS_C0201-DIFF BUS_0A 1        P5E_CPU0_PE3_TX_C_DP<12>
                                  2        P5E_CPU0_PE3_TX_DP<12>  
C878             Q_CAP_DIFFBUS_C0201-DIFF BUS_0A 1        P5E_CPU0_PE3_TX_C_DN<11>
                                  2        P5E_CPU0_PE3_TX_DN<11>  
C879             Q_CAP_DIFFBUS_C0201-DIFF BUS_0A 1        P5E_CPU0_PE3_TX_C_DP<11>
                                  2        P5E_CPU0_PE3_TX_DP<11>  
C880             Q_CAP_DIFFBUS_C0201-DIFF BUS_0A 1        P5E_CPU0_PE3_TX_C_DN<10>
                                  2        P5E_CPU0_PE3_TX_DN<10>  
C881             Q_CAP_DIFFBUS_C0201-DIFF BUS_0A 1        P5E_CPU0_PE3_TX_C_DP<10>
                                  2        P5E_CPU0_PE3_TX_DP<10>  
C882             Q_CAP_DIFFBUS_C0201-DIFF BUS_0A 1        P5E_CPU0_PE3_TX_C_DN<9> 
                                  2        P5E_CPU0_PE3_TX_DN<9>   
C883             Q_CAP_DIFFBUS_C0201-DIFF BUS_0A 1        P5E_CPU0_PE3_TX_C_DP<9> 
                                  2        P5E_CPU0_PE3_TX_DP<9>   
C884             Q_CAP_DIFFBUS_C0201-DIFF BUS_0A 1        P5E_CPU0_PE3_TX_C_DN<8> 
                                  2        P5E_CPU0_PE3_TX_DN<8>   
C885             Q_CAP_DIFFBUS_C0201-DIFF BUS_0A 1        P5E_CPU0_PE3_TX_C_DP<8> 
                                  2        P5E_CPU0_PE3_TX_DP<8>   
C886             Q_CAP_DIFFBUS_C0201-DIFF BUS_0A 1        P5E_CPU0_PE3_TX_C_DN<7> 
                                  2        P5E_CPU0_PE3_TX_DN<7>   
C887             Q_CAP_DIFFBUS_C0201-DIFF BUS_0A 1        P5E_CPU0_PE3_TX_C_DP<7> 
                                  2        P5E_CPU0_PE3_TX_DP<7>   
C888             Q_CAP_DIFFBUS_C0201-DIFF BUS_0A 1        P5E_CPU0_PE3_TX_C_DN<6> 
                                  2        P5E_CPU0_PE3_TX_DN<6>   
C889             Q_CAP_DIFFBUS_C0201-DIFF BUS_0A 1        P5E_CPU0_PE3_TX_C_DP<6> 
                                  2        P5E_CPU0_PE3_TX_DP<6>   
C890             Q_CAP_DIFFBUS_C0201-DIFF BUS_0A 1        P5E_CPU0_PE3_TX_C_DN<5> 
                                  2        P5E_CPU0_PE3_TX_DN<5>   
C891             Q_CAP_DIFFBUS_C0201-DIFF BUS_0A 1        P5E_CPU0_PE3_TX_C_DP<5> 
                                  2        P5E_CPU0_PE3_TX_DP<5>   
C892             Q_CAP_DIFFBUS_C0201-DIFF BUS_0A 1        P5E_CPU0_PE3_TX_C_DN<4> 
                                  2        P5E_CPU0_PE3_TX_DN<4>   
C893             Q_CAP_DIFFBUS_C0201-DIFF BUS_0A 1        P5E_CPU0_PE3_TX_C_DP<4> 
                                  2        P5E_CPU0_PE3_TX_DP<4>   
C894             Q_CAP_DIFFBUS_C0201-DIFF BUS_0A 1        P5E_CPU0_PE3_TX_C_DN<3> 
                                  2        P5E_CPU0_PE3_TX_DN<3>   
C895             Q_CAP_DIFFBUS_C0201-DIFF BUS_0A 1        P5E_CPU0_PE3_TX_C_DP<3> 
                                  2        P5E_CPU0_PE3_TX_DP<3>   
C896             Q_CAP_DIFFBUS_C0201-DIFF BUS_0A 1        P5E_CPU0_PE3_TX_C_DN<2> 
                                  2        P5E_CPU0_PE3_TX_DN<2>   
C897             Q_CAP_DIFFBUS_C0201-DIFF BUS_0A 1        P5E_CPU0_PE3_TX_C_DP<2> 
                                  2        P5E_CPU0_PE3_TX_DP<2>   
C898             Q_CAP_DIFFBUS_C0201-DIFF BUS_0A 1        P5E_CPU0_PE3_TX_C_DN<1> 
                                  2        P5E_CPU0_PE3_TX_DN<1>   
C899             Q_CAP_DIFFBUS_C0201-DIFF BUS_0A 1        P5E_CPU0_PE3_TX_C_DP<1> 
                                  2        P5E_CPU0_PE3_TX_DP<1>   
C900             Q_CAP_DIFFBUS_C0201-DIFF BUS_0A 1        P5E_CPU0_PE3_TX_C_DN<0> 
                                  2        P5E_CPU0_PE3_TX_DN<0>   
C901             Q_CAP_DIFFBUS_C0201-DIFF BUS_0A 1        P5E_CPU0_PE3_TX_C_DP<0> 
                                  2        P5E_CPU0_PE3_TX_DP<0>   
C902             Q_CAP_DIFFBUS_C0201-DIFF BUS_0A 1        P5E_CPU0_PE0_TX_C_DN<15>
                                  2        P5E_CPU0_PE0_TX_DN<15>  
C903             Q_CAP_DIFFBUS_C0201-DIFF BUS_0A 1        P5E_CPU0_PE0_TX_C_DP<15>
                                  2        P5E_CPU0_PE0_TX_DP<15>  
C904             Q_CAP_DIFFBUS_C0201-DIFF BUS_0A 1        P5E_CPU0_PE0_TX_C_DN<14>
                                  2        P5E_CPU0_PE0_TX_DN<14>  
C905             Q_CAP_DIFFBUS_C0201-DIFF BUS_0A 1        P5E_CPU0_PE0_TX_C_DP<14>
                                  2        P5E_CPU0_PE0_TX_DP<14>  
C906             Q_CAP_DIFFBUS_C0201-DIFF BUS_0A 1        P5E_CPU0_PE0_TX_C_DN<13>
                                  2        P5E_CPU0_PE0_TX_DN<13>  
C907             Q_CAP_DIFFBUS_C0201-DIFF BUS_0A 1        P5E_CPU0_PE0_TX_C_DP<13>
                                  2        P5E_CPU0_PE0_TX_DP<13>  
C908             Q_CAP_DIFFBUS_C0201-DIFF BUS_0A 1        P5E_CPU0_PE0_TX_C_DN<12>
                                  2        P5E_CPU0_PE0_TX_DN<12>  
C909             Q_CAP_DIFFBUS_C0201-DIFF BUS_0A 1        P5E_CPU0_PE0_TX_C_DP<12>
                                  2        P5E_CPU0_PE0_TX_DP<12>  
C910             Q_CAP_DIFFBUS_C0201-DIFF BUS_0A 1        P5E_CPU0_PE0_TX_C_DN<11>
                                  2        P5E_CPU0_PE0_TX_DN<11>  
C911             Q_CAP_DIFFBUS_C0201-DIFF BUS_0A 1        P5E_CPU0_PE0_TX_C_DP<11>
                                  2        P5E_CPU0_PE0_TX_DP<11>  
C912             Q_CAP_DIFFBUS_C0201-DIFF BUS_0A 1        P5E_CPU0_PE0_TX_C_DN<10>
                                  2        P5E_CPU0_PE0_TX_DN<10>  
C913             Q_CAP_DIFFBUS_C0201-DIFF BUS_0A 1        P5E_CPU0_PE0_TX_C_DP<10>
                                  2        P5E_CPU0_PE0_TX_DP<10>  
C914             Q_CAP_DIFFBUS_C0201-DIFF BUS_0A 1        P5E_CPU0_PE0_TX_C_DN<9> 
                                  2        P5E_CPU0_PE0_TX_DN<9>   
C915             Q_CAP_DIFFBUS_C0201-DIFF BUS_0A 1        P5E_CPU0_PE0_TX_C_DP<9> 
                                  2        P5E_CPU0_PE0_TX_DP<9>   
C916             Q_CAP_DIFFBUS_C0201-DIFF BUS_0A 1        P5E_CPU0_PE0_TX_C_DN<8> 
                                  2        P5E_CPU0_PE0_TX_DN<8>   
C917             Q_CAP_DIFFBUS_C0201-DIFF BUS_0A 1        P5E_CPU0_PE0_TX_C_DP<8> 
                                  2        P5E_CPU0_PE0_TX_DP<8>   
C918             Q_CAP_DIFFBUS_C0201-DIFF BUS_0A 1        P5E_CPU0_PE0_TX_C_DN<7> 
                                  2        P5E_CPU0_PE0_TX_DN<7>   
C919             Q_CAP_DIFFBUS_C0201-DIFF BUS_0A 1        P5E_CPU0_PE0_TX_C_DP<7> 
                                  2        P5E_CPU0_PE0_TX_DP<7>   
C920             Q_CAP_DIFFBUS_C0201-DIFF BUS_0A 1        P5E_CPU0_PE0_TX_C_DN<6> 
                                  2        P5E_CPU0_PE0_TX_DN<6>   
C921             Q_CAP_DIFFBUS_C0201-DIFF BUS_0A 1        P5E_CPU0_PE0_TX_C_DP<6> 
                                  2        P5E_CPU0_PE0_TX_DP<6>   
C922             Q_CAP_DIFFBUS_C0201-DIFF BUS_0A 1        P5E_CPU0_PE0_TX_C_DN<5> 
                                  2        P5E_CPU0_PE0_TX_DN<5>   
C923             Q_CAP_DIFFBUS_C0201-DIFF BUS_0A 1        P5E_CPU0_PE0_TX_C_DP<5> 
                                  2        P5E_CPU0_PE0_TX_DP<5>   
C924             Q_CAP_DIFFBUS_C0201-DIFF BUS_0A 1        P5E_CPU0_PE0_TX_C_DN<4> 
                                  2        P5E_CPU0_PE0_TX_DN<4>   
C925             Q_CAP_DIFFBUS_C0201-DIFF BUS_0A 1        P5E_CPU0_PE0_TX_C_DP<4> 
                                  2        P5E_CPU0_PE0_TX_DP<4>   
C926             Q_CAP_DIFFBUS_C0201-DIFF BUS_0A 1        P5E_CPU0_PE0_TX_C_DN<3> 
                                  2        P5E_CPU0_PE0_TX_DN<3>   
C927             Q_CAP_DIFFBUS_C0201-DIFF BUS_0A 1        P5E_CPU0_PE0_TX_C_DP<3> 
                                  2        P5E_CPU0_PE0_TX_DP<3>   
C928             Q_CAP_DIFFBUS_C0201-DIFF BUS_0A 1        P5E_CPU0_PE0_TX_C_DN<2> 
                                  2        P5E_CPU0_PE0_TX_DN<2>   
C929             Q_CAP_DIFFBUS_C0201-DIFF BUS_0A 1        P5E_CPU0_PE0_TX_C_DP<2> 
                                  2        P5E_CPU0_PE0_TX_DP<2>   
C930             Q_CAP_DIFFBUS_C0201-DIFF BUS_0A 1        P5E_CPU0_PE0_TX_C_DN<1> 
                                  2        P5E_CPU0_PE0_TX_DN<1>   
C931             Q_CAP_DIFFBUS_C0201-DIFF BUS_0A 1        P5E_CPU0_PE0_TX_C_DP<1> 
                                  2        P5E_CPU0_PE0_TX_DP<1>   
C932             Q_CAP_DIFFBUS_C0201-DIFF BUS_0A 1        P5E_CPU0_PE0_TX_C_DN<0> 
                                  2        P5E_CPU0_PE0_TX_DN<0>   
C933             Q_CAP_DIFFBUS_C0201-DIFF BUS_0A 1        P5E_CPU0_PE0_TX_C_DP<0> 
                                  2        P5E_CPU0_PE0_TX_DP<0>   
C934             Q_CAP_DIFFBUS_C0201-DIFF BUS_0A 1        P5E_CPU0_PE1_TX_C_DN<15>
                                  2        P5E_CPU0_PE1_TX_DN<15>  
C935             Q_CAP_DIFFBUS_C0201-DIFF BUS_0A 1        P5E_CPU0_PE1_TX_C_DP<15>
                                  2        P5E_CPU0_PE1_TX_DP<15>  
C936             Q_CAP_DIFFBUS_C0201-DIFF BUS_0A 1        P5E_CPU0_PE1_TX_C_DN<14>
                                  2        P5E_CPU0_PE1_TX_DN<14>  
C937             Q_CAP_DIFFBUS_C0201-DIFF BUS_0A 1        P5E_CPU0_PE1_TX_C_DP<14>
                                  2        P5E_CPU0_PE1_TX_DP<14>  
C938             Q_CAP_DIFFBUS_C0201-DIFF BUS_0A 1        P5E_CPU0_PE1_TX_C_DN<13>
                                  2        P5E_CPU0_PE1_TX_DN<13>  
C939             Q_CAP_DIFFBUS_C0201-DIFF BUS_0A 1        P5E_CPU0_PE1_TX_C_DP<13>
                                  2        P5E_CPU0_PE1_TX_DP<13>  
C940             Q_CAP_DIFFBUS_C0201-DIFF BUS_0A 1        P5E_CPU0_PE1_TX_C_DN<12>
                                  2        P5E_CPU0_PE1_TX_DN<12>  
C941             Q_CAP_DIFFBUS_C0201-DIFF BUS_0A 1        P5E_CPU0_PE1_TX_C_DP<12>
                                  2        P5E_CPU0_PE1_TX_DP<12>  
C942             Q_CAP_DIFFBUS_C0201-DIFF BUS_0A 1        P5E_CPU0_PE1_TX_C_DN<11>
                                  2        P5E_CPU0_PE1_TX_DN<11>  
C943             Q_CAP_DIFFBUS_C0201-DIFF BUS_0A 1        P5E_CPU0_PE1_TX_C_DP<11>
                                  2        P5E_CPU0_PE1_TX_DP<11>  
C944             Q_CAP_DIFFBUS_C0201-DIFF BUS_0A 1        P5E_CPU0_PE1_TX_C_DN<10>
                                  2        P5E_CPU0_PE1_TX_DN<10>  
C945             Q_CAP_DIFFBUS_C0201-DIFF BUS_0A 1        P5E_CPU0_PE1_TX_C_DP<10>
                                  2        P5E_CPU0_PE1_TX_DP<10>  
C946             Q_CAP_DIFFBUS_C0201-DIFF BUS_0A 1        P5E_CPU0_PE1_TX_C_DN<9> 
                                  2        P5E_CPU0_PE1_TX_DN<9>   
C947             Q_CAP_DIFFBUS_C0201-DIFF BUS_0A 1        P5E_CPU0_PE1_TX_C_DP<9> 
                                  2        P5E_CPU0_PE1_TX_DP<9>   
C948             Q_CAP_DIFFBUS_C0201-DIFF BUS_0A 1        P5E_CPU0_PE1_TX_C_DN<8> 
                                  2        P5E_CPU0_PE1_TX_DN<8>   
C949             Q_CAP_DIFFBUS_C0201-DIFF BUS_0A 1        P5E_CPU0_PE1_TX_C_DP<8> 
                                  2        P5E_CPU0_PE1_TX_DP<8>   
C950             Q_CAP_DIFFBUS_C0201-DIFF BUS_0A 1        P5E_CPU0_PE1_TX_C_DN<7> 
                                  2        P5E_CPU0_PE1_TX_DN<7>   
C951             Q_CAP_DIFFBUS_C0201-DIFF BUS_0A 1        P5E_CPU0_PE1_TX_C_DP<7> 
                                  2        P5E_CPU0_PE1_TX_DP<7>   
C952             Q_CAP_DIFFBUS_C0201-DIFF BUS_0A 1        P5E_CPU0_PE1_TX_C_DN<6> 
                                  2        P5E_CPU0_PE1_TX_DN<6>   
C953             Q_CAP_DIFFBUS_C0201-DIFF BUS_0A 1        P5E_CPU0_PE1_TX_C_DP<6> 
                                  2        P5E_CPU0_PE1_TX_DP<6>   
C954             Q_CAP_DIFFBUS_C0201-DIFF BUS_0A 1        P5E_CPU0_PE1_TX_C_DN<5> 
                                  2        P5E_CPU0_PE1_TX_DN<5>   
C955             Q_CAP_DIFFBUS_C0201-DIFF BUS_0A 1        P5E_CPU0_PE1_TX_C_DP<5> 
                                  2        P5E_CPU0_PE1_TX_DP<5>   
C956             Q_CAP_DIFFBUS_C0201-DIFF BUS_0A 1        P5E_CPU0_PE1_TX_C_DN<4> 
                                  2        P5E_CPU0_PE1_TX_DN<4>   
C957             Q_CAP_DIFFBUS_C0201-DIFF BUS_0A 1        P5E_CPU0_PE1_TX_C_DP<4> 
                                  2        P5E_CPU0_PE1_TX_DP<4>   
C958             Q_CAP_DIFFBUS_C0201-DIFF BUS_0A 1        P5E_CPU0_PE1_TX_C_DN<3> 
                                  2        P5E_CPU0_PE1_TX_DN<3>   
C959             Q_CAP_DIFFBUS_C0201-DIFF BUS_0A 1        P5E_CPU0_PE1_TX_C_DP<3> 
                                  2        P5E_CPU0_PE1_TX_DP<3>   
C960             Q_CAP_DIFFBUS_C0201-DIFF BUS_0A 1        P5E_CPU0_PE1_TX_C_DN<2> 
                                  2        P5E_CPU0_PE1_TX_DN<2>   
C961             Q_CAP_DIFFBUS_C0201-DIFF BUS_0A 1        P5E_CPU0_PE1_TX_C_DP<2> 
                                  2        P5E_CPU0_PE1_TX_DP<2>   
C962             Q_CAP_DIFFBUS_C0201-DIFF BUS_0A 1        P5E_CPU0_PE1_TX_C_DN<1> 
                                  2        P5E_CPU0_PE1_TX_DN<1>   
C963             Q_CAP_DIFFBUS_C0201-DIFF BUS_0A 1        P5E_CPU0_PE1_TX_C_DP<1> 
                                  2        P5E_CPU0_PE1_TX_DP<1>   
C964             Q_CAP_DIFFBUS_C0201-DIFF BUS_0A 1        P5E_CPU0_PE1_TX_C_DN<0> 
                                  2        P5E_CPU0_PE1_TX_DN<0>   
C965             Q_CAP_DIFFBUS_C0201-DIFF BUS_0A 1        P5E_CPU0_PE1_TX_C_DP<0> 
                                  2        P5E_CPU0_PE1_TX_DP<0>   
C966             Q_CAP_C0402-22UF,4V,20%,X6S,CHA 1        PVCCIN_CPU0             
                                  2        GND                     
C967             Q_CAP_C0402-22UF,4V,20%,X6S,CHA 1        PVCCIN_CPU0             
                                  2        GND                     
C968             Q_CAP_C0402-22UF,4V,20%,X6S,CHA 1        PVCCIN_CPU0             
                                  2        GND                     
C969             Q_CAP_C0402-22UF,4V,20%,X6S,CHA 1        PVCCIN_CPU0             
                                  2        GND                     
C970             Q_CAP_C0402-22UF,4V,20%,X6S,CHA 1        PVCCIN_CPU0             
                                  2        GND                     
C971             Q_CAP_C0402-22UF,4V,20%,X6S,CHA 1        PVCCIN_CPU0             
                                  2        GND                     
C972             Q_CAP_C0402-22UF,4V,20%,X6S,CHA 1        PVCCIN_CPU0             
                                  2        GND                     
C973             Q_CAP_C0402-22UF,4V,20%,X6S,CHA 1        PVCCIN_CPU0             
                                  2        GND                     
C974             Q_CAP_C0402-22UF,4V,20%,X6S,CHA 1        PVCCIN_CPU0             
                                  2        GND                     
C975             Q_CAP_C0402-22UF,4V,20%,X6S,CHA 1        PVCCIN_CPU0             
                                  2        GND                     
C976             Q_CAP_C0402-22UF,4V,20%,X6S,CHA 1        PVCCIN_CPU0             
                                  2        GND                     
C977             Q_CAP_C0402-22UF,4V,20%,X6S,CHA 1        PVCCIN_CPU0             
                                  2        GND                     
C978             Q_CAP_C0402-22UF,4V,20%,X6S,CHA 1        PVCCIN_CPU0             
                                  2        GND                     
C979             Q_CAP_C0402-22UF,4V,20%,X6S,CHA 1        PVCCIN_CPU0             
                                  2        GND                     
C980             Q_CAP_C0402-22UF,4V,20%,X6S,CHA 1        PVCCIN_CPU0             
                                  2        GND                     
C981             Q_CAP_C0402-22UF,4V,20%,X6S,CHA 1        PVCCIN_CPU0             
                                  2        GND                     
C982             Q_CAP_C0402-22UF,4V,20%,X6S,CHA 1        PVCCIN_CPU0             
                                  2        GND                     
C983             Q_CAP_C0402-22UF,4V,20%,X6S,CHA 1        PVCCIN_CPU0             
                                  2        GND                     
C984             Q_CAP_C0402-22UF,4V,20%,X6S,CHA 1        PVCCIN_CPU0             
                                  2        GND                     
C985             Q_CAP_C0402-22UF,4V,20%,X6S,CHA 1        PVCCIN_CPU0             
                                  2        GND                     
C986             Q_CAP_C0402-22UF,4V,20%,X6S,CHA 1        PVCCIN_CPU0             
                                  2        GND                     
C987             Q_CAP_C0402-22UF,4V,20%,X6S,CHA 1        PVCCIN_CPU0             
                                  2        GND                     
C988             Q_CAP_C0402-22UF,4V,20%,X6S,CHA 1        PVCCIN_CPU0             
                                  2        GND                     
C989             Q_CAP_C0402-22UF,4V,20%,X6S,CHA 1        PVCCIN_CPU0             
                                  2        GND                     
C990             Q_CAP_C0402-22UF,4V,20%,X6S,CHA 1        PVCCIN_CPU0             
                                  2        GND                     
C991             Q_CAP_C0402-22UF,4V,20%,X6S,CHA 1        PVCCIN_CPU0             
                                  2        GND                     
C992             Q_CAP_C0402-22UF,4V,20%,X6S,CHA 1        PVCCIN_CPU0             
                                  2        GND                     
C993             Q_CAP_C0402-22UF,4V,20%,X6S,CHA 1        PVCCIN_CPU0             
                                  2        GND                     
C994             Q_CAP_C0402-22UF,4V,20%,X6S,CHA 1        PVCCIN_CPU0             
                                  2        GND                     
C995             Q_CAP_C0402-22UF,4V,20%,X6S,CHA 1        PVCCIN_CPU0             
                                  2        GND                     
C996             Q_CAP_C0402-22UF,4V,20%,X6S,CHA 1        PVCCIN_CPU0             
                                  2        GND                     
C997             Q_CAP_C0402-22UF,4V,20%,X6S,CHA 1        PVCCIN_CPU0             
                                  2        GND                     
C998             Q_CAP_C0402-22UF,4V,20%,X6S,CHA 1        PVCCIN_CPU0             
                                  2        GND                     
C999             Q_CAP_C0402-22UF,4V,20%,X6S,CHA 1        PVCCIN_CPU0             
                                  2        GND                     
C1000            Q_CAP_C0402-22UF,4V,20%,X6S,CHA 1        PVCCIN_CPU0             
                                  2        GND                     
C1001            Q_CAP_C0402-22UF,4V,20%,X6S,CHA 1        PVCCIN_CPU0             
                                  2        GND                     
C1002            Q_CAP_C0402-22UF,4V,20%,X6S,CHA 1        PVCCIN_CPU0             
                                  2        GND                     
C1003            Q_CAP_C0402-22UF,4V,20%,X6S,CHA 1        PVCCIN_CPU0             
                                  2        GND                     
C1004            Q_CAP_C0402-22UF,4V,20%,X6S,CHA 1        PVCCIN_CPU0             
                                  2        GND                     
C1005            Q_CAP_C0402-22UF,4V,20%,X6S,CHA 1        PVCCIN_CPU0             
                                  2        GND                     
C1006            Q_CAP_C0402-22UF,4V,20%,X6S,CHA 1        PVCCIN_CPU0             
                                  2        GND                     
C1007            Q_CAP_C0402-22UF,4V,20%,X6S,CHA 1        PVCCIN_CPU0             
                                  2        GND                     
C1008            Q_CAP_C0402-22UF,4V,20%,X6S,CHA 1        PVCCIN_CPU0             
                                  2        GND                     
C1009            Q_CAP_C0402-22UF,4V,20%,X6S,CHA 1        PVCCIN_CPU0             
                                  2        GND                     
C1010            Q_CAP_C0402-22UF,4V,20%,X6S,CHA 1        PVCCIN_CPU0             
                                  2        GND                     
C1011            Q_CAP_C0402-22UF,4V,20%,X6S,CHA 1        PVCCIN_CPU0             
                                  2        GND                     
C1012            Q_CAP_C0402-22UF,4V,20%,X6S,CHA 1        PVCCIN_CPU0             
                                  2        GND                     
C1013            Q_CAP_C0402-22UF,4V,20%,X6S,CHA 1        PVCCIN_CPU0             
                                  2        GND                     
C1014            Q_CAP_C0402-22UF,4V,20%,X6S,CHA 1        PVCCIN_CPU0             
                                  2        GND                     
C1015            Q_CAP_C0402-22UF,4V,20%,X6S,CHA 1        PVCCIN_CPU0             
                                  2        GND                     
C1016            Q_CAP_C0402-22UF,4V,20%,X6S,CHA 1        PVCCIN_CPU0             
                                  2        GND                     
C1017            Q_CAP_C0402-22UF,4V,20%,X6S,CHA 1        PVCCIN_CPU0             
                                  2        GND                     
C1018            Q_CAP_C0402-22UF,4V,20%,X6S,CHA 1        PVCCIN_CPU0             
                                  2        GND                     
C1019            Q_CAP_C0402-22UF,4V,20%,X6S,CHA 1        PVCCIN_CPU0             
                                  2        GND                     
C1020            Q_CAP_C0402-22UF,4V,20%,X6S,CHA 1        PVCCIN_CPU0             
                                  2        GND                     
C1021            Q_CAP_C0402-22UF,4V,20%,X6S,CHA 1        PVCCIN_CPU0             
                                  2        GND                     
C1022            Q_CAP_C0402-22UF,4V,20%,X6S,CHA 1        PVCCIN_CPU0             
                                  2        GND                     
C1023            Q_CAP_C0402-22UF,4V,20%,X6S,CHA 1        PVCCIN_CPU0             
                                  2        GND                     
C1024            Q_CAP_C0402-22UF,4V,20%,X6S,CHA 1        PVCCIN_CPU0             
                                  2        GND                     
C1025            Q_CAP_C0402-22UF,4V,20%,X6S,CHA 1        PVCCIN_CPU0             
                                  2        GND                     
C1026            Q_CAP_C0402-22UF,4V,20%,X6S,CHA 1        PVCCIN_CPU0             
                                  2        GND                     
C1027            Q_CAP_C0402-22UF,4V,20%,X6S,CHA 1        PVCCIN_CPU0             
                                  2        GND                     
C1028            Q_CAP_C0402-22UF,4V,20%,X6S,CHA 1        PVCCIN_CPU0             
                                  2        GND                     
C1029            Q_CAP_C0402-22UF,4V,20%,X6S,CHA 1        PVCCIN_CPU0             
                                  2        GND                     
C1030            Q_CAP_C0402-22UF,4V,20%,X6S,CHA 1        PVCCIN_CPU0             
                                  2        GND                     
C1031            Q_CAP_C0402-22UF,4V,20%,X6S,CHA 1        PVCCIN_CPU0             
                                  2        GND                     
C1032            Q_CAP_C0402-22UF,4V,20%,X6S,CHA 1        PVCCIN_CPU0             
                                  2        GND                     
C1033            Q_CAP_C0402-22UF,4V,20%,X6S,CHA 1        PVCCIN_CPU0             
                                  2        GND                     
C1034            Q_CAP_C0402-22UF,4V,20%,X6S,CHA 1        PVCCIN_CPU0             
                                  2        GND                     
C1035            Q_CAP_C0402-22UF,4V,20%,X6S,CHA 1        PVCCIN_CPU0             
                                  2        GND                     
C1036            Q_CAP_C0402-22UF,4V,20%,X6S,CHA 1        PVCCIN_CPU0             
                                  2        GND                     
C1037            Q_CAP_C0402-22UF,4V,20%,X6S,CHA 1        PVCCIN_CPU0             
                                  2        GND                     
C1038            Q_CAP_C0402-22UF,4V,20%,X6S,CHA 1        PVCCIN_CPU0             
                                  2        GND                     
C1039            Q_CAP_C0402-22UF,4V,20%,X6S,CHA 1        PVCCIN_CPU0             
                                  2        GND                     
C1040            Q_CAP_C0402-22UF,4V,20%,X6S,CHA 1        PVCCIN_CPU0             
                                  2        GND                     
C1041            Q_CAP_C0402-22UF,4V,20%,X6S,CHA 1        PVCCIN_CPU0             
                                  2        GND                     
C1042            Q_CAP_C0402-100NF,50V,10%,X7R,A 1        P5V_AUX                 
                                  2        GND                     
C1043            Q_CAP_C0402-22UF,4V,20%,X6S,CHA 1        PVCCIN_CPU0             
                                  2        GND                     
C1044            Q_CAP_C0402-22UF,4V,20%,X6S,CHA 1        PVCCIN_CPU0             
                                  2        GND                     
C1045            Q_CAP_C0402-22UF,4V,20%,X6S,CHA 1        PVCCIN_CPU0             
                                  2        GND                     
C1046            Q_CAP_C0805-22UF,16V,20%,X6S,CA 1        P3V3_AUX                
                                  2        GND                     
C1047            Q_CAP_C0805-22UF,16V,20%,X6S,CA 1        P12V_REAR_CPU           
                                  2        GND                     
C1048            Q_CAP_0402-0.1UF,25V,10%,X7R,CA 1        P12V_REAR_CPU           
                                  2        GND                     
C1049            Q_CAP_0402-0.1UF,25V,10%,X7R,CA 1        P12V_REAR_CPU           
                                  2        GND                     
C1050            Q_CAP_0402-0.1UF,25V,10%,X7R,CA 1        P12V_REAR_CPU           
                                  2        GND                     
C1051            Q_CAP_0402-0.1UF,25V,10%,X7R,CA 1        P12V_REAR_CPU           
                                  2        GND                     
C1052            Q_CAP_0402-0.1UF,25V,10%,X7R,CA 1        P12V_REAR_CPU           
                                  2        GND                     
C1053            Q_CAP_C0805-22UF,16V,20%,X6S,CA 1        P3V3_AUX                
                                  2        GND                     
C1054            Q_CAP_C0805-22UF,16V,20%,X6S,CA 1        P3V3_AUX                
                                  2        GND                     
C1055            Q_CAP_C0805-22UF,16V,20%,X6S,CA 1        P12V_REAR_CPU           
                                  2        GND                     
C1056            Q_CAP_0402-0.1UF,25V,10%,X7R,CA 1        P12V_REAR_CPU           
                                  2        GND                     
C1057            Q_CAP_0402-0.1UF,25V,10%,X7R,CA 1        P12V_REAR_CPU           
                                  2        GND                     
C1058            Q_CAP_0402-0.1UF,25V,10%,X7R,CA 1        P12V_REAR_CPU           
                                  2        GND                     
C1059            Q_CAP_0402-0.1UF,25V,10%,X7R,CA 1        P12V_REAR_CPU           
                                  2        GND                     
C1060            Q_CAP_0402-0.1UF,25V,10%,X7R,CA 1        P12V_REAR_CPU           
                                  2        GND                     
C1061            Q_CAP_C0805-22UF,16V,20%,X6S,CA 1        P3V3_AUX                
                                  2        GND                     
C1063            Q_CAP_C0805-22UF,16V,20%,X6S,CA 1        P12V_REAR_CPU           
                                  2        GND                     
C1064            Q_CAP_0402-0.1UF,25V,10%,X7R,CA 1        P12V_REAR_CPU           
                                  2        GND                     
C1065            Q_CAP_0402-0.1UF,25V,10%,X7R,CA 1        P12V_REAR_CPU           
                                  2        GND                     
C1066            Q_CAP_0402-0.1UF,25V,10%,X7R,CA 1        P12V_REAR_CPU           
                                  2        GND                     
C1067            Q_CAP_0402-0.1UF,25V,10%,X7R,CA 1        P12V_REAR_CPU           
                                  2        GND                     
C1068            Q_CAP_0402-0.1UF,25V,10%,X7R,CA 1        P12V_REAR_CPU           
                                  2        GND                     
C1069            Q_CAP_C0805-22UF,16V,20%,X6S,CA 1        P3V3_AUX                
                                  2        GND                     
C1078            Q_CAP_C0603-22UF,6.3V,20%,X6S,A 1        P3V3                    
                                  2        GND                     
C1080            Q_CAP_C0603-22UF,6.3V,20%,X6S,A 1        P3V3                    
                                  2        GND                     
C1082            Q_CAP_C0603-22UF,6.3V,20%,X6S,A 1        P3V3                    
                                  2        GND                     
C1084            Q_CAP_0402-0.1UF,25V,10%,X7R,CA 1        P3V3                    
                                  2        GND                     
C1086            Q_CAP_0402-0.1UF,25V,10%,X7R,CA 1        P3V3                    
                                  2        GND                     
C1088            Q_CAP_0402-0.1UF,25V,10%,X7R,CA 1        P3V3                    
                                  2        GND                     
C1096            Q_CAP_DIFFBUS_C0201-DIFF BUS_0A 1        P3E_PCH_M2_TX_DP<4>     
                                  2        P3E_PCH_M2_TX_C_DP<4>   
C1097            Q_CAP_DIFFBUS_C0201-DIFF BUS_0A 1        P3E_PCH_M2_TX_DN<4>     
                                  2        P3E_PCH_M2_TX_C_DN<4>   
C1098            Q_CAP_DIFFBUS_C0201-DIFF BUS_0A 1        P3E_PCH_M2_TX_DP<3>     
                                  2        P3E_PCH_M2_TX_C_DP<3>   
C1099            Q_CAP_DIFFBUS_C0201-DIFF BUS_0A 1        P3E_PCH_M2_TX_DN<3>     
                                  2        P3E_PCH_M2_TX_C_DN<3>   
C1100            Q_CAP_DIFFBUS_C0201-DIFF BUS_0A 1        P3E_PCH_M2_TX_DP<2>     
                                  2        P3E_PCH_M2_TX_C_DP<2>   
C1101            Q_CAP_DIFFBUS_C0201-DIFF BUS_0A 1        P3E_PCH_M2_TX_DN<2>     
                                  2        P3E_PCH_M2_TX_C_DN<2>   
C1102            Q_CAP_DIFFBUS_C0201-DIFF BUS_0A 1        P3E_PCH_M2_TX_DP<1>     
                                  2        P3E_PCH_M2_TX_C_DP<1>   
C1103            Q_CAP_DIFFBUS_C0201-DIFF BUS_0A 1        P3E_PCH_M2_TX_DN<1>     
                                  2        P3E_PCH_M2_TX_C_DN<1>   
C1104            Q_CAP_DIFFBUS_C0201-DIFF BUS_0A 1        P3E_PCH_M2_TX_DP<0>     
                                  2        P3E_PCH_M2_TX_C_DP<0>   
C1105            Q_CAP_DIFFBUS_C0201-DIFF BUS_0A 1        P3E_PCH_M2_TX_DN<0>     
                                  2        P3E_PCH_M2_TX_C_DN<0>   
C1107            Q_CAP_0402-0.1UF,25V,10%,X7R,CA 1        P3V3_AUX                
                                  2        GND                     
C1108            Q_CAP_0402-0.1UF,25V,10%,X7R,CA 1        P3V3_AUX                
                                  2        GND                     
C1110            Q_CAP_0402-0.1UF,25V,10%,X7R,CA 1        P3V3_AUX                
                                  2        GND                     
C1111            Q_CAP_0402-0.1UF,25V,10%,X7R,CA 1        P3V3_AUX                
                                  2        GND                     
C1113            Q_CAP_0402-0.1UF,25V,10%,X7R,CA 1        P3V3_AUX                
                                  2        GND                     
C1114            Q_CAP_0402-0.1UF,25V,10%,X7R,CA 1        P3V3_AUX                
                                  2        GND                     
C1115            Q_CAP_C0402-2.2UF,6.3V,20%,EMPA 1        PVCCA_AUX_PLD           
                                  2        GND                     
C1118            Q_CAP_0402-0.1UF,25V,10%,X7R,CA 1        P3V3_AUX                
                                  2        GND                     
C1119            Q_CAP_0402-0.1UF,25V,10%,X7R,CA 1        P3V3_AUX                
                                  2        GND                     
C1120            Q_CAP_0402-0.1UF,25V,10%,X7R,CA 1        PVCCIO_PLDIO2           
                                  2        GND                     
C1122            Q_CAP_0402-0.1UF,25V,10%,X7R,CA 1        P3V3_AUX                
                                  2        GND                     
C1123            Q_CAP_0402-0.1UF,25V,10%,X7R,CA 1        P3V3_AUX                
                                  2        GND                     
C1124            Q_CAP_0402-0.1UF,25V,10%,EMPTYA 1        PVCCA_AUX_PLD           
                                  2        GND                     
C1127            Q_CAP_0402-0.1UF,25V,10%,X7R,CA 1        P3V3_AUX                
                                  2        GND                     
C1128            Q_CAP_0402-0.1UF,25V,10%,X7R,CA 1        P3V3_AUX                
                                  2        GND                     
C1129            Q_CAP_0402-0.1UF,25V,10%,X7R,CA 1        PVCCIO_PLDIO2           
                                  2        GND                     
C1130            Q_CAP_0402-0.1UF,25V,10%,EMPTYA 1        PVCCA_AUX_PLD           
                                  2        GND                     
C1133            Q_CAP_0402-0.1UF,25V,10%,X7R,CA 1        P3V3_AUX                
                                  2        GND                     
C1134            Q_CAP_0402-0.1UF,25V,10%,X7R,CA 1        P3V3_AUX                
                                  2        GND                     
C1135            Q_CAP_0402-0.1UF,25V,10%,X7R,CA 1        PVCCIO_PLDIO2           
                                  2        GND                     
C1136            Q_CAP_0402-0.1UF,25V,10%,EMPTYA 1        PVCCA_AUX_PLD           
                                  2        GND                     
C1138            Q_CAP_0402-0.1UF,25V,10%,X7R,CA 1        P3V3_AUX                
                                  2        GND                     
C1139            Q_CAP_0402-0.1UF,25V,10%,X7R,CA 1        P3V3_AUX                
                                  2        GND                     
C1140            Q_CAP_0402-0.1UF,25V,10%,EMPTYA 1        PVCCA_AUX_PLD           
                                  2        GND                     
C1142            Q_CAP_0402-0.1UF,25V,10%,X7R,CA 1        P3V3_AUX                
                                  2        GND                     
C1143            Q_CAP_0402-0.1UF,25V,10%,X7R,CA 1        P3V3_AUX                
                                  2        GND                     
C1144            Q_CAP_0402-0.1UF,25V,10%,EMPTYA 1        PVCCA_AUX_PLD           
                                  2        GND                     
C1146            Q_CAP_0402-0.1UF,25V,10%,X7R,CA 1        P3V3_AUX                
                                  2        GND                     
C1147            Q_CAP_0402-0.1UF,25V,10%,X7R,CA 1        P3V3_AUX                
                                  2        GND                     
C1148            Q_CAP_0402-0.1UF,25V,10%,EMPTYA 1        PVCCA_AUX_PLD           
                                  2        GND                     
C1150            Q_CAP_0402-0.1UF,25V,10%,X7R,CA 1        P3V3_AUX                
                                  2        GND                     
C1151            Q_CAP_0402-0.1UF,25V,10%,X7R,CA 1        P3V3_AUX                
                                  2        GND                     
C1152            Q_CAP_0402-0.1UF,25V,10%,X7R,CA 1        P3V3_AUX                
                                  2        GND                     
C1153            Q_CAP_0402-0.1UF,25V,10%,X7R,CA 1        P3V3_AUX                
                                  2        GND                     
C1154            Q_CAP_0402-0.1UF,25V,10%,X7R,CA 1        P3V3_AUX                
                                  2        GND                     
C1155            Q_CAP_0402-0.1UF,25V,10%,X7R,CA 1        P3V3_AUX                
                                  2        GND                     
C1156            Q_CAP_0402-0.1UF,25V,10%,X7R,CA 1        P3V3_AUX                
                                  2        GND                     
C1157            Q_CAP_0402-0.1UF,25V,10%,X7R,CA 1        P3V3_AUX                
                                  2        GND                     
C1158            Q_CAP_0402-0.1UF,25V,10%,X7R,CA 1        P3V3_AUX                
                                  2        GND                     
C1159            Q_CAP_0402-0.1UF,25V,10%,X7R,CA 1        P3V3_AUX                
                                  2        GND                     
C1160            Q_CAP_0402-0.1UF,25V,10%,X7R,CA 1        PVCCIO_PLDIO5           
                                  2        GND                     
C1161            Q_CAP_0402-0.1UF,25V,10%,X7R,CA 1        P3V3_AUX                
                                  2        GND                     
C1162            Q_CAP_0402-0.1UF,25V,10%,X7R,CA 1        P3V3_AUX                
                                  2        GND                     
C1163            Q_CAP_0402-0.1UF,25V,10%,X7R,CA 1        P3V3_AUX                
                                  2        GND                     
C1164            Q_CAP_0402-0.1UF,25V,10%,X7R,CA 1        P3V3_AUX                
                                  2        GND                     
C1165            Q_CAP_0402-0.1UF,25V,10%,X7R,CA 1        P3V3_AUX                
                                  2        GND                     
C1166            Q_CAP_0402-0.1UF,25V,10%,X7R,CA 1        PVCCIO_PLDIO5           
                                  2        GND                     
C1167            Q_CAP_0402-0.1UF,25V,10%,X7R,CA 1        P3V3_AUX                
                                  2        GND                     
C1168            Q_CAP_0402-0.1UF,25V,10%,X7R,CA 1        P3V3_AUX                
                                  2        GND                     
C1169            Q_CAP_0402-0.1UF,25V,10%,X7R,CA 1        PVCCIO_PLDIO5           
                                  2        GND                     
C1170            Q_CAP_C0805-10UF,16V,10%,X6S,CA 1        P5V_AUX                 
                                  2        GND                     
C1171            Q_CAP_C0805-10UF,16V,10%,EMPTYA 1        P5V_AUX                 
                                  2        GND                     
C1172            Q_CAP_C0402-100NF,50V,10%,X7R,A 1        P5V                     
                                  2        GND                     
C1173            Q_CAP_0402-0.1UF,25V,10%,X7R,CA 1        P3V3_AUX                
                                  2        GND                     
C1175            Q_CAP_0402-0.1UF,25V,10%,X7R,CA 1        P3V3_AUX                
                                  2        GND                     
C1177            Q_CAP_C0402-1UF,25V,10%,X6S,CHA 1        RST_RTCRST_N            
                                  2        GND                     
C1178            Q_CAP_C0603-22UF,4V,20%,X6S,CHA 1        P1V05_PCH_AUX           
                                  2        GND                     
C1181            Q_CAP_C0603-22UF,4V,20%,X6S,CHA 1        P1V8_PCH_AUX            
                                  2        GND                     
C1182            Q_CAP_C0603-22UF,4V,20%,X6S,CHA 1        P1V05_PCH_AUX           
                                  2        GND                     
C1183            Q_CAP_C0402-2.2UF,10V,10%,X6S,A 1        P1V05_PCH_AUX           
                                  2        GND                     
C1184            Q_CAP_C0603-22UF,4V,20%,X6S,CHA 1        P3V3_AUX                
                                  2        GND                     
C1185            Q_CAP_C0603-22UF,4V,20%,X6S,CHA 1        P1V05_PCH_AUX           
                                  2        GND                     
C1186            Q_CAP_C0603-22UF,4V,20%,X6S,CHA 1        P1V8_PCH_AUX            
                                  2        GND                     
C1187            Q_CAP_C0603-22UF,4V,20%,X6S,CHA 1        P1V05_PCH_AUX           
                                  2        GND                     
C1189            Q_CAP_C0402-2.2UF,10V,10%,X6S,A 1        P1V05_PCH_AUX           
                                  2        GND                     
C1191            Q_CAP_C0603-22UF,4V,20%,X6S,CHA 1        P3V3_AUX                
                                  2        GND                     
C1192            Q_CAP_C0603-22UF,4V,20%,X6S,CHA 1        P1V05_PCH_AUX           
                                  2        GND                     
C1197            Q_CAP_C0603-22UF,4V,20%,X6S,CHA 1        P1V8_PCH_AUX            
                                  2        GND                     
C1198            Q_CAP_C0603-22UF,4V,20%,X6S,CHA 1        P1V05_PCH_AUX           
                                  2        GND                     
C1200            Q_CAP_C0402-2.2UF,10V,10%,X6S,A 1        P1V05_PCH_AUX           
                                  2        GND                     
C1201            Q_CAP_C0603-22UF,4V,20%,X6S,CHA 1        P3V3_AUX                
                                  2        GND                     
C1202            Q_CAP_C0603-22UF,4V,20%,X6S,CHA 1        P1V8_PCH_AUX            
                                  2        GND                     
C1203            Q_CAP_C0402-10UF,6.3V,20%,X6S,A 1        P1V05_PCH_AUX           
                                  2        GND                     
C1204            Q_CAP_C0402-2.2UF,10V,10%,X6S,A 1        P1V05_PCH_AUX           
                                  2        GND                     
C1205            Q_CAP_C0402-10UF,6.3V,20%,X6S,A 1        P1V05_PCH_AUX           
                                  2        GND                     
C1206            Q_CAP_C0402-10UF,6.3V,20%,X6S,A 1        P3V3_AUX                
                                  2        GND                     
C1207            Q_CAP_C0402-10UF,6.3V,20%,X6S,A 1        P1V8_PCH_AUX            
                                  2        GND                     
C1208            Q_CAP_0402-0.1UF,25V,10%,X7R,CA 1        P3V3                    
                                  2        GND                     
C1209            Q_CAP_0402-100PF,50V,5%,X7R,CHA 1        PWRGD_SYS_PWROK_R       
                                  2        GND                     
C1210            Q_CAP_C0402-10UF,6.3V,20%,X6S,A 1        P1V05_PCH_AUX           
                                  2        GND                     
C1211            Q_CAP_0402-100PF,50V,5%,X7R,CHA 1        PWRGD_PCH_PWROK_R       
                                  2        GND                     
C1213            Q_CAP_C0805-22UF,16V,20%,X6S,CA 1        P12V_OCP_SFF            
                                  2        GND                     
C1214            Q_CAP_C0402-2.2UF,10V,10%,X6S,A 1        P1V05_PCH_AUX           
                                  2        GND                     
C1215            Q_CAP_0402-0.1UF,25V,10%,X7R,CA 1        P3V3                    
                                  2        GND                     
C1216            Q_CAP_0402-0.1UF,25V,10%,X7R,CA 1        P3V3                    
                                  2        GND                     
C1217            Q_CAP_0402-0.1UF,25V,10%,X7R,CA 1        P3V3                    
                                  2        GND                     
C1218            Q_CAP_0402-0.1UF,25V,10%,X7R,CA 1        P3V3                    
                                  2        GND                     
C1219            Q_CAP_0402-0.1UF,25V,10%,X7R,CA 1        P3V3                    
                                  2        GND                     
C1226            Q_CAP_0402-0.22UF,16V,10%,X7R,A 1        VR_P5V_EN_D_R           
                                  2        GND                     
C1227            Q_CAP_C0402-100NF,50V,10%,X7R,A 1        P5V                     
                                  2        GND                     
C1228            Q_CAP_C0402-10UF,6.3V,20%,X6S,A 1        P1V05_PCH_AUX           
                                  2        GND                     
C1229            Q_CAP_0402-0.1UF,25V,10%,X7R,CA 1        PGPPA_AUX               
                                  2        GND                     
C1231            Q_CAP_C0402-10UF,6.3V,20%,X6S,A 1        P1V05_PCH_AUX           
                                  2        GND                     
C1232            Q_CAP_C0805-22UF,16V,20%,X6S,CA 1        P12V_OCP_SFF            
                                  2        GND                     
C1233            Q_CAP_0402-0.1UF,25V,10%,X7R,CA 1        P12V_OCP_SFF            
                                  2        GND                     
C1234            Q_CAP_0402-0.1UF,25V,10%,X7R,CA 1        P12V_OCP_SFF            
                                  2        GND                     
C1235            Q_CAP_0402-0.1UF,25V,10%,X7R,CA 1        P12V_OCP_SFF            
                                  2        GND                     
C1236            Q_CAP_0402-0.1UF,25V,10%,X7R,CA 1        P12V_OCP_SFF            
                                  2        GND                     
C1237            Q_CAP_0402-0.1UF,25V,10%,X7R,CA 1        P3V3_OCP_SFF            
                                  2        GND                     
C1238            Q_CAP_0402-0.1UF,25V,10%,X7R,CA 1        P3V3_OCP_SFF            
                                  2        GND                     
C1239            Q_CAP_0402-0.1UF,25V,10%,X7R,CA 1        P3V3_OCP_SFF            
                                  2        GND                     
C1240            Q_CAP_0402-0.1UF,25V,10%,X7R,CA 1        P3V3_OCP_SFF            
                                  2        GND                     
C1241            Q_CAP_0402-0.1UF,25V,10%,X7R,CA 1        P3V3_AUX                
                                  2        GND                     
C1242            Q_CAP_C0402-2.2UF,10V,10%,X6S,A 1        P1V05_PCH_AUX           
                                  2        GND                     
C1243            Q_CAP_0805-47UF,4V,20%,X6S,CH6A 1        P3V3_AUX                
                                  2        GND                     
C1244            Q_CAP_0805-47UF,4V,20%,X6S,CH6A 1        P1V05_PCH_AUX           
                                  2        GND                     
C1245            Q_CAP_0805-47UF,4V,20%,X6S,CH6A 1        P3V3_AUX                
                                  2        GND                     
C1246            Q_CAP_0805-47UF,4V,20%,X6S,CH6A 1        P1V05_PCH_AUX           
                                  2        GND                     
C1247            Q_CAP_0805-47UF,4V,20%,X6S,CH6A 1        P1V05_PCH_AUX           
                                  2        GND                     
C1248            Q_CAP_0805-47UF,4V,20%,X6S,CH6A 1        P1V05_PCH_AUX           
                                  2        GND                     
C1249            Q_CAP_0805-47UF,4V,20%,X6S,CH6A 1        P1V05_PCH_AUX           
                                  2        GND                     
C1250            Q_CAP_0402-1UF,6.3V,10%,EMPTY,A 1        P1V05_PCH_AUX           
                                  2        GND                     
C1251            Q_CAP_C0603-10UF,6.3V,20%,X6S,A 1        P1V05_PCH_PLL_AUX       
                                  2        GND                     
C1252            Q_CAP_C0603-10UF,6.3V,20%,X6S,A 1        P1V8_PCH_PLL_AUX        
                                  2        GND                     
C1253            Q_CAP_0402-1UF,6.3V,10%,EMPTY,A 1        P1V8_PCH_AUX            
                                  2        GND                     
C1254            Q_CAP_C0603-10UF,6.3V,20%,X6S,A 1        P1V05_PCH_PLL_AUX       
                                  2        GND                     
C1255            Q_CAP_C0603-10UF,6.3V,20%,X6S,A 1        P1V8_PCH_PLL_AUX        
                                  2        GND                     
C1256            Q_CAP_0402-1UF,6.3V,10%,EMPTY,A 1        P1V05_PCH_PLL_AUX       
                                  2        GND                     
C1257            Q_CAP_0402-1UF,6.3V,10%,EMPTY,A 1        P1V8_PCH_PLL_AUX        
                                  2        GND                     
C1258            Q_CAP_0805-47UF,4V,20%,X6S,CH6A 1        P1V05_PCH_PLL_AUX       
                                  2        GND                     
C1259            Q_CAP_0805-47UF,4V,20%,X6S,CH6A 1        P1V8_PCH_PLL_AUX        
                                  2        GND                     
C1260            Q_CAP_C0603-10UF,6.3V,20%,X6S,A 1        P1V05_PCH_PLL_AUX       
                                  2        GND                     
C1261            Q_CAP_C0603-10UF,6.3V,20%,X6S,A 1        P1V8_PCH_PLL_AUX        
                                  2        GND                     
C1262            Q_CAP_C0402-10UF,6.3V,20%,X6S,A 1        P1V05_PCH_PLL_AUX       
                                  2        GND                     
C1263            Q_CAP_C0402-10UF,6.3V,20%,X6S,A 1        P1V8_PCH_PLL_AUX        
                                  2        GND                     
C1264            Q_CAP_0402-1UF,6.3V,10%,EMPTY,A 1        P1V05_PCH_PLL_AUX       
                                  2        GND                     
C1265            Q_CAP_0402-1UF,6.3V,10%,EMPTY,A 1        P1V8_PCH_PLL_AUX        
                                  2        GND                     
C1266            Q_CAP_C0402-10UF,6.3V,20%,X6S,A 1        P1V8_PCH_PLL_AUX        
                                  2        GND                     
C1272            Q_CAP_0805-47UF,4V,20%,X6S,CH6A 1        P1V05_PCH_PLL_AUX       
                                  2        GND                     
C1273            Q_CAP_0805-47UF,4V,20%,X6S,CH6A 1        P1V8_PCH_PLL_AUX        
                                  2        GND                     
C1274            Q_CAP_0402-0.1UF,25V,10%,X7R,CA 1        P3V3_AUX                
                                  2        GND                     
C1275            Q_CAP_0402-0.1UF,25V,10%,X7R,CA 1        P3V3_AUX                
                                  2        GND                     
C1276            Q_CAP_C0805-22UF,16V,20%,X6S,CA 1        P12V_E1S_0              
                                  2        GND                     
C1277            Q_CAP_C0805-22UF,16V,20%,X6S,CA 1        P12V_E1S_0              
                                  2        GND                     
C1278            Q_CAP_0402-0.1UF,25V,10%,X7R,CA 1        P12V_E1S_0              
                                  2        GND                     
C1279            Q_CAP_0402-0.1UF,25V,10%,X7R,CA 1        P12V_E1S_0              
                                  2        GND                     
C1280            Q_CAP_0402-0.1UF,25V,10%,X7R,CA 1        P12V_E1S_1              
                                  2        GND                     
C1281            Q_CAP_0402-0.1UF,25V,10%,X7R,CA 1        P12V_E1S_1              
                                  2        GND                     
C1282            Q_CAP_0402-0.1UF,25V,10%,X7R,CA 1        P3V3_E1S_0              
                                  2        GND                     
C1283            Q_CAP_0402-0.1UF,25V,10%,X7R,CA 1        P3V3_E1S_0              
                                  2        GND                     
C1284            Q_CAP_0402-0.1UF,25V,10%,X7R,CA 1        P3V3_E1S_1              
                                  2        GND                     
C1285            Q_CAP_0402-0.1UF,25V,10%,X7R,CA 1        P3V3_E1S_1              
                                  2        GND                     
C1286            Q_CAP_0402-1000PF,50V,5%,EMPTYA 1        FM_P1V05_PCH_AUX_R_EN   
                                  2        GND                     
C1288            Q_CAP_0402-0.1UF,25V,10%,X7R,CA 1        P3V3_AUX                
                                  2        GND                     
C1289            Q_CAP_C0402-1UF,25V,10%,X6S,CHA 1        P3V3_AUX                
                                  2        GND                     
C1290            Q_CAP_C0402-1UF,25V,10%,X6S,CHA 1        P3V3_AUX                
                                  2        GND                     
C1291            Q_CAP_C0402-1UF,25V,10%,X6S,CHA 1        P3V3_AUX                
                                  2        GND                     
C1292            Q_CAP_0402-0.1UF,25V,10%,X7R,CA 1        P3V3_AUX                
                                  2        GND                     
C1293            Q_CAP_C0402-1UF,25V,10%,X6S,CHA 1        FM_BMC_EN_DET           
                                  2        GND                     
C1296            Q_CAP_0402-1000PF,50V,5%,X7R,TA 1        PWRGD_PVNN_MAIN_CPU0    
                                  2        GND                     
C1297            Q_CAP_0402-1000PF,50V,5%,X7R,TA 1        PWRGD_PVNN_MAIN_CPU1    
                                  2        GND                     
C1300            Q_CAP_0402-1000PF,50V,5%,EMPTYA 1        FM_PVPP_HBM_CPU0_EN     
                                  2        GND                     
C1301            Q_CAP_0402-1000PF,50V,5%,EMPTYA 1        PWRGD_PVPP_HBM_CPU0_R   
                                  2        GND                     
C1302            Q_CAP_C0402-22UF,4V,20%,X6S,CHA 1        PVNN_TERM_CPU0          
                                  2        GND                     
C1305            Q_CAP_0402-0.1UF,25V,10%,X7R,CA 1        P3V3_AUX                
                                  2        GND                     
C1307            Q_CAP_0402-1000PF,50V,5%,EMPTYA 1        FM_PVNN_MAIN_CPU0_EN    
                                  2        GND                     
C1308            Q_CAP_0402-1000PF,50V,5%,EMPTYA 1        FM_PVNN_MAIN_CPU1_EN    
                                  2        GND                     
C1309            Q_CAP_C0603-10UF,6.3V,20%,X6S,A 1        P3V3_AUX_CLK_GEN_VDDXTAL_CK440
                                  2        GND                     
C1310            Q_CAP_C0603-10UF,6.3V,20%,X6S,A 1        P3V3_AUX_CLK_GEN_VDDMXCK_CK440
                                  2        GND                     
C1311            Q_CAP_C0402-1UF,25V,10%,X6S,CHA 1        P3V3_AUX_CLK_GEN_VDDXTAL_CK440
                                  2        GND                     
C1312            Q_CAP_C0402-1UF,25V,10%,X6S,CHA 1        P3V3_AUX_CLK_GEN_VDDMXCK_CK440
                                  2        GND                     
C1313            Q_CAP_C0603-10UF,6.3V,20%,X6S,A 1        P3V3_AUX_CLK_GEN_VDDA25M_CK440
                                  2        GND                     
C1314            Q_CAP_C0603-10UF,6.3V,20%,X6S,A 1        P3V3_AUX_CLK_GEN_VDDPT_CK440
                                  2        GND                     
C1315            Q_CAP_C0402-1UF,25V,10%,X6S,CHA 1        P3V3_AUX                
                                  2        GND                     
C1316            Q_CAP_C0402-0.047UF,25V,10%,X7A 1        FM_COMP_P3V3_STBY_CEXT  
                                  2        GND                     
C1317            Q_CAP_0402-0.1UF,25V,10%,X7R,CA 1        P3V3_AUX                
                                  2        GND                     
C1318            Q_CAP_C0402-1UF,25V,10%,EMPTY,A 1        PWRGD_DSW_PWROK_R1      
                                  2        GND                     
C1319            Q_CAP_C0402-1UF,25V,10%,X6S,CHA 1        PWRGD_DSW_PWROK         
                                  2        GND                     
C1320            Q_CAP_0402-0.1UF,25V,10%,X7R,CA 1        P3V3_AUX                
                                  2        GND                     
C1321            Q_CAP_0402-0.1UF,25V,10%,X7R,CA 1        P3V3_AUX                
                                  2        GND                     
C1322            Q_CAP_0402-0.1UF,25V,10%,X7R,CA 1        P3V3_AUX                
                                  2        GND                     
C1323            Q_CAP_0402-0.1UF,25V,10%,X7R,CA 1        P1V8_PCH_AUX            
                                  2        GND                     
C1324            Q_CAP_0402-0.1UF,25V,10%,EMPTYA 1        FM_CK440Q_DEV_25M_EN    
                                  2        GND                     
C1325            Q_CAP_0402-0.1UF,25V,10%,X7R,CA 1        FM_PLD_REV_N            
                                  2        GND                     
C1326            Q_CAP_C0402-100NF,50V,10%,X7R,A 1        P5V_AUX                 
                                  2        GND                     
C1331            Q_CAP_C0805-10UF,16V,10%,X6S,CA 1        P5V                     
                                  2        GND                     
C1332            Q_CAP_C0402-100NF,50V,10%,X7R,A 1        P3V3_AUX                
                                  2        GND                     
C1333            Q_CAP_C0805-10UF,16V,10%,X6S,CA 1        P3V3_AUX                
                                  2        GND                     
C1337            Q_CAP_C0603-22UF,6.3V,20%,X6S,A 1        P5V                     
                                  2        GND                     
C1338            Q_CAP_C0805-10UF,16V,10%,EMPTYA 1        P3V3_AUX                
                                  2        GND                     
C1339            Q_CAP_C0402-100NF,50V,10%,X7R,A 1        P3V3                    
                                  2        GND                     
C1340            Q_CAP_C0805-10UF,16V,10%,X6S,CA 1        P3V3                    
                                  2        GND                     
C1341            Q_CAP_C0603-22UF,6.3V,20%,X6S,A 1        P5V                     
                                  2        GND                     
C1342            Q_CAP_C0603-22UF,6.3V,20%,X6S,A 1        P5V_USB_INT             
                                  2        GND                     
C1343            Q_CAP_C0603-22UF,6.3V,20%,X6S,A 1        P5V_USB_INT             
                                  2        GND                     
C1344            Q_CAP_0402-0.1UF,25V,10%,X7R,CA 1        P3V3_AUX_SENSE          
                                  2        GND                     
C1345            Q_CAP_0402-0.1UF,25V,10%,X7R,CA 1        P3V3_SENSE              
                                  2        GND                     
C1346            Q_CAP_0402-0.1UF,25V,10%,X7R,CA 1        P3V3_RTC_AUX_SENSE      
                                  2        GND                     
C1347            Q_CAP_0402-0.1UF,25V,10%,X7R,CA 1        P3V3_AUX                
                                  2        GND                     
C1351            Q_CAP_0402-0.1UF,25V,10%,X7R,CA 1        P12V_AUX_SENSE          
                                  2        GND                     
C1353            Q_CAP_C0402-22UF,4V,20%,X6S,CHA 1        PVNN_MAIN_CPU1          
                                  2        GND                     
C1358            Q_CAP_0402-0.1UF,25V,10%,X7R,CA 1        P12V_AUX                
                                  2        GND                     
C1359            Q_CAP_C0805-10UF,25V,10%,X6S,CA 1        P12V_AUX                
                                  2        GND                     
C1360            Q_CAP_0402-0.1UF,25V,10%,X7R,CA 1        P12V_REAR_CPU           
                                  2        GND                     
C1361            Q_CAP_C0805-10UF,25V,10%,X6S,CA 1        P12V_REAR_CPU           
                                  2        GND                     
C1362            Q_CAP_C0402-22UF,4V,20%,X6S,CHA 1        PVNN_MAIN_CPU0          
                                  2        GND                     
C1363            Q_CAP_C0402-22UF,4V,20%,X6S,CHA 1        PVNN_MAIN_CPU0          
                                  2        GND                     
C1364            Q_CAP_C0402-22UF,4V,20%,X6S,CHA 1        PVNN_MAIN_CPU0          
                                  2        GND                     
C1365            Q_CAP_C0402-22UF,4V,20%,X6S,CHA 1        PVNN_MAIN_CPU1          
                                  2        GND                     
C1366            Q_CAP_C0402-22UF,4V,20%,X6S,CHA 1        PVNN_MAIN_CPU1          
                                  2        GND                     
C1387            Q_CAP_C0805-100UF,4V,20%,X6S,CA 1        PVNN_MAIN_CPU1          
                                  2        GND                     
C1388            Q_CAP_C0805-100UF,4V,20%,X6S,CA 1        PVPP_HBM_CPU1           
                                  2        GND                     
C1389            Q_CAP_C0603-47UF,2.5V,20%,X6S,A 1        PVNN_MAIN_CPU1          
                                  2        GND                     
C1390            Q_CAP_C0805-100UF,4V,20%,X6S,CA 1        PVPP_HBM_CPU1           
                                  2        GND                     
C1391            Q_CAP_C0603-47UF,2.5V,20%,X6S,A 1        PVNN_MAIN_CPU1          
                                  2        GND                     
C1392            Q_CAP_C0805-100UF,4V,20%,X6S,CA 1        PVPP_HBM_CPU1           
                                  2        GND                     
C1393            Q_CAP_C0603-47UF,2.5V,20%,X6S,A 1        PVNN_MAIN_CPU1          
                                  2        GND                     
C1396            Q_CAP_C0805-100UF,4V,20%,X6S,CA 1        PVPP_HBM_CPU0           
                                  2        GND                     
C1397            Q_CAP_C0805-100UF,4V,20%,X6S,CA 1        PVPP_HBM_CPU0           
                                  2        GND                     
C1398            Q_CAP_C0805-100UF,4V,20%,X6S,CA 1        PVPP_HBM_CPU0           
                                  2        GND                     
C1399            Q_CAP_C0805-100UF,4V,20%,X6S,CA 1        PVNN_MAIN_CPU0          
                                  2        GND                     
C1400            Q_CAP_C0805-100UF,4V,20%,X6S,CA 1        PVNN_MAIN_CPU0          
                                  2        GND                     
C1403            Q_CAP_C0805-100UF,4V,20%,X6S,CA 1        PVNN_MAIN_CPU1          
                                  2        GND                     
C1404            Q_CAP_C0805-100UF,4V,20%,X6S,CA 1        PVNN_MAIN_CPU1          
                                  2        GND                     
C1405            Q_CAP_C0603-47UF,2.5V,20%,X6S,A 1        PVNN_MAIN_CPU0          
                                  2        GND                     
C1406            Q_CAP_C0603-47UF,2.5V,20%,X6S,A 1        PVNN_MAIN_CPU0          
                                  2        GND                     
C1407            Q_CAP_C0603-47UF,2.5V,20%,X6S,A 1        PVNN_MAIN_CPU0          
                                  2        GND                     
C1408            Q_CAP_0402-0.1UF,25V,10%,X7R,CA 1        PGPPA_AUX               
                                  2        GND                     
C1409            Q_CAP_C0603-10UF,6.3V,20%,X6S,A 1        P3V3_DB2000_VDD         
                                  2        GND                     
C1420            Q_CAP_DIFFBUS_C0201-DIFF BUS_0B 1        P3E_PCH_M2_RX_C_DN<3>   
                                  2        P3E_PCH_M2_RX_DN<3>     
C1421            Q_CAP_DIFFBUS_C0201-DIFF BUS_0B 1        P3E_PCH_M2_RX_C_DP<3>   
                                  2        P3E_PCH_M2_RX_DP<3>     
C1430            Q_CAP_0402-0.1UF,25V,10%,X7R,CA 1        P12V_AUX                
                                  2        GND                     
C1431            Q_CAP_C0805-10UF,25V,10%,X6S,CA 1        P12V_AUX                
                                  2        GND                     
C1432            Q_CAP_0402-0.1UF,25V,10%,X7R,CA 1        P12V_FRONT_CPU          
                                  2        GND                     
C1433            Q_CAP_C0805-10UF,25V,10%,X6S,CA 1        P12V_FRONT_CPU          
                                  2        GND                     
C1436            Q_CAP_C0201-0.22UF,6.3V,10%,X6A 1        PVPP_HBM_CPU0           
                                  2        GND                     
C1437            Q_CAP_C0201-0.22UF,6.3V,10%,X6A 1        PVPP_HBM_CPU1           
                                  2        GND                     
C1438            Q_CAP_C0805-22UF,16V,20%,X6S,CA 1        P3V3_AUX                
                                  2        GND                     
C1439            Q_CAP_C0805-22UF,16V,20%,X6S,CA 1        P12V_REAR_CPU           
                                  2        GND                     
C1440            Q_CAP_0402-0.1UF,25V,10%,X7R,CA 1        P12V_REAR_CPU           
                                  2        GND                     
C1441            Q_CAP_0402-0.1UF,25V,10%,X7R,CA 1        P12V_REAR_CPU           
                                  2        GND                     
C1442            Q_CAP_0402-0.1UF,25V,10%,X7R,CA 1        P12V_REAR_CPU           
                                  2        GND                     
C1443            Q_CAP_0402-0.1UF,25V,10%,X7R,CA 1        P12V_REAR_CPU           
                                  2        GND                     
C1444            Q_CAP_0402-0.1UF,25V,10%,X7R,CA 1        P12V_REAR_CPU           
                                  2        GND                     
C1445            Q_CAP_C0805-22UF,16V,20%,X6S,CA 1        P3V3_AUX                
                                  2        GND                     
C1446            Q_CAP_0402-0.1UF,25V,10%,X7R,CA 1        P3V3                    
                                  2        GND                     
C1447            Q_CAP_0402-0.1UF,25V,10%,X7R,CA 1        P3V3                    
                                  2        GND                     
C1448            Q_CAP_C0805-22UF,16V,20%,X6S,CA 1        P3V3_AUX                
                                  2        GND                     
C1449            Q_CAP_C0805-22UF,16V,20%,X6S,CA 1        P12V_REAR_CPU           
                                  2        GND                     
C1450            Q_CAP_0402-0.1UF,25V,10%,X7R,CA 1        P12V_REAR_CPU           
                                  2        GND                     
C1451            Q_CAP_0402-0.1UF,25V,10%,X7R,CA 1        P12V_REAR_CPU           
                                  2        GND                     
C1452            Q_CAP_0402-0.1UF,25V,10%,X7R,CA 1        P12V_REAR_CPU           
                                  2        GND                     
C1453            Q_CAP_0402-0.1UF,25V,10%,X7R,CA 1        P12V_REAR_CPU           
                                  2        GND                     
C1454            Q_CAP_0402-0.1UF,25V,10%,X7R,CA 1        P12V_REAR_CPU           
                                  2        GND                     
C1455            Q_CAP_C0805-22UF,16V,20%,X6S,CA 1        P3V3_AUX                
                                  2        GND                     
C1456            Q_CAP_0402-0.1UF,25V,10%,X7R,CA 1        P3V3                    
                                  2        GND                     
C1457            Q_CAP_0402-0.1UF,25V,10%,X7R,CA 1        P3V3                    
                                  2        GND                     
C1459            Q_CAP_C0805-22UF,16V,20%,X6S,CA 1        P12V_REAR_CPU           
                                  2        GND                     
C1460            Q_CAP_0402-0.1UF,25V,10%,X7R,CA 1        P12V_REAR_CPU           
                                  2        GND                     
C1461            Q_CAP_0402-0.1UF,25V,10%,X7R,CA 1        P12V_REAR_CPU           
                                  2        GND                     
C1462            Q_CAP_0402-0.1UF,25V,10%,X7R,CA 1        P12V_REAR_CPU           
                                  2        GND                     
C1463            Q_CAP_0402-0.1UF,25V,10%,X7R,CA 1        P12V_REAR_CPU           
                                  2        GND                     
C1464            Q_CAP_0402-0.1UF,25V,10%,X7R,CA 1        P12V_REAR_CPU           
                                  2        GND                     
C1465            Q_CAP_C0805-22UF,16V,20%,X6S,CA 1        P3V3_AUX                
                                  2        GND                     
C1466            Q_CAP_0402-0.1UF,25V,10%,X7R,CA 1        P3V3                    
                                  2        GND                     
C1467            Q_CAP_0402-0.1UF,25V,10%,X7R,CA 1        P3V3                    
                                  2        GND                     
C1469            Q_CAP_C0805-22UF,16V,20%,X6S,CA 1        P12V_REAR_CPU           
                                  2        GND                     
C1470            Q_CAP_0402-0.1UF,25V,10%,X7R,CA 1        P12V_REAR_CPU           
                                  2        GND                     
C1471            Q_CAP_0402-0.1UF,25V,10%,X7R,CA 1        P12V_REAR_CPU           
                                  2        GND                     
C1472            Q_CAP_0402-0.1UF,25V,10%,X7R,CA 1        P12V_REAR_CPU           
                                  2        GND                     
C1473            Q_CAP_0402-0.1UF,25V,10%,X7R,CA 1        P12V_REAR_CPU           
                                  2        GND                     
C1474            Q_CAP_0402-0.1UF,25V,10%,X7R,CA 1        P12V_REAR_CPU           
                                  2        GND                     
C1475            Q_CAP_C0805-22UF,16V,20%,X6S,CA 1        P3V3_AUX                
                                  2        GND                     
C1476            Q_CAP_0402-0.1UF,25V,10%,X7R,CA 1        P3V3                    
                                  2        GND                     
C1477            Q_CAP_0402-0.1UF,25V,10%,X7R,CA 1        P3V3                    
                                  2        GND                     
C1480            Q_CAP_C0402-100NF,50V,10%,X7R,A 1        P3V3_E1S_2_DVDT         
                                  2        GND                     
C1481            Q_CAP_0402-0.1UF,25V,10%,X7R,CA 1        P3V3_AUX                
                                  2        GND                     
C1482            Q_CAP_0402-0.1UF,25V,10%,X7R,CA 1        P3V3_AUX                
                                  2        GND                     
C1483            Q_CAP_C0805-10UF,25V,10%,X6S,CA 1        P3V3_E1S_2              
                                  2        GND                     
C1484            Q_CAP_C0402-100NF,50V,10%,X7R,A 1        P3V3_E1S_1_DVDT         
                                  2        GND                     
C1485            Q_CAP_0402-0.1UF,25V,10%,X7R,CA 1        P3V3_AUX                
                                  2        GND                     
C1486            Q_CAP_0402-0.1UF,25V,10%,X7R,CA 1        P3V3_AUX                
                                  2        GND                     
C1487            Q_CAP_C0805-10UF,25V,10%,X6S,CA 1        P3V3_E1S_1              
                                  2        GND                     
C1488            Q_CAP_C0805-10UF,25V,10%,X6S,CA 1        P3V3_E1S_3              
                                  2        GND                     
C1489            Q_CAP_C0805-22UF,16V,20%,X6S,CA 1        P12V_E1S_1              
                                  2        GND                     
C1490            Q_CAP_C0805-22UF,16V,20%,X6S,CA 1        P12V_E1S_1              
                                  2        GND                     
C1491            Q_CAP_C0805-22UF,16V,20%,X6S,CA 1        P12V_E1S_2              
                                  2        GND                     
C1492            Q_CAP_C0805-22UF,16V,20%,X6S,CA 1        P12V_E1S_3              
                                  2        GND                     
C1493            Q_CAP_C0805-22UF,16V,20%,X6S,CA 1        P12V_E1S_2              
                                  2        GND                     
C1494            Q_CAP_C0805-22UF,16V,20%,X6S,CA 1        P12V_E1S_3              
                                  2        GND                     
C1495            Q_CAP_0402-0.1UF,25V,10%,X7R,CA 1        P12V_E1S_2              
                                  2        GND                     
C1496            Q_CAP_0402-0.1UF,25V,10%,X7R,CA 1        P12V_E1S_3              
                                  2        GND                     
C1497            Q_CAP_0402-0.1UF,25V,10%,X7R,CA 1        P12V_E1S_2              
                                  2        GND                     
C1498            Q_CAP_0402-0.1UF,25V,10%,X7R,CA 1        P12V_E1S_3              
                                  2        GND                     
C1499            Q_CAP_0402-0.1UF,25V,10%,X7R,CA 1        P3V3_E1S_2              
                                  2        GND                     
C1500            Q_CAP_0402-0.1UF,25V,10%,X7R,CA 1        P3V3_E1S_3              
                                  2        GND                     
C1501            Q_CAP_0402-0.1UF,25V,10%,X7R,CA 1        P3V3_E1S_2              
                                  2        GND                     
C1502            Q_CAP_0402-0.1UF,25V,10%,X7R,CA 1        P3V3_E1S_3              
                                  2        GND                     
C1503            Q_CAP_C0402-0.047UF,25V,10%,X7A 1        P12V_E1S_0_DVDT         
                                  2        GND                     
C1504            Q_CAP_C0402-0.047UF,25V,10%,X7A 1        P12V_E1S_2_DVDT         
                                  2        GND                     
C1505            Q_CAP_0402-0.1UF,25V,10%,X7R,CA 1        P12V_FRONT_CPU          
                                  2        GND                     
C1506            Q_CAP_C0805-10UF,25V,10%,X6S,CA 1        P12V_E1S_0              
                                  2        GND                     
C1507            Q_CAP_0402-27PF  ,50V ,5% ,NPOA 1        XTAL_PCH_RTC2_R         
                                  2        GND                     
C1508            Q_CAP_0402-27PF  ,50V ,5% ,NPOA 1        XTAL_PCH_RTC1           
                                  2        GND                     
C1509            Q_CAP_C0805-10UF,25V,10%,X6S,CA 1        P12V_E1S_2              
                                  2        GND                     
C1510            Q_CAP_C0402-0.047UF,25V,10%,X7A 1        P12V_E1S_1_DVDT         
                                  2        GND                     
C1511            Q_CAP_C0402-0.047UF,25V,10%,X7A 1        P12V_E1S_3_DVDT         
                                  2        GND                     
C1512            Q_CAP_0402-0.1UF,25V,10%,X7R,CA 1        P12V_FRONT_CPU          
                                  2        GND                     
C1513            Q_CAP_0402-0.1UF,25V,10%,X7R,CA 1        P12V_FRONT_CPU          
                                  2        GND                     
C1514            Q_CAP_C0805-10UF,25V,10%,X6S,CA 1        P12V_E1S_1              
                                  2        GND                     
C1515            Q_CAP_C0805-10UF,25V,10%,X6S,CA 1        P12V_E1S_3              
                                  2        GND                     
C1516            Q_CAP_DIFFBUS_C0201-DIFF BUS_0A 1        P5E_CPU1_PE3_TX_C_DN<15>
                                  2        P5E_CPU1_PE3_TX_DN<15>  
C1517            Q_CAP_DIFFBUS_C0201-DIFF BUS_0A 1        P5E_CPU1_PE3_TX_C_DP<15>
                                  2        P5E_CPU1_PE3_TX_DP<15>  
C1518            Q_CAP_DIFFBUS_C0201-DIFF BUS_0A 1        P5E_CPU1_PE3_TX_C_DN<14>
                                  2        P5E_CPU1_PE3_TX_DN<14>  
C1519            Q_CAP_DIFFBUS_C0201-DIFF BUS_0A 1        P5E_CPU1_PE3_TX_C_DP<14>
                                  2        P5E_CPU1_PE3_TX_DP<14>  
C1520            Q_CAP_DIFFBUS_C0201-DIFF BUS_0A 1        P5E_CPU1_PE3_TX_C_DN<13>
                                  2        P5E_CPU1_PE3_TX_DN<13>  
C1521            Q_CAP_DIFFBUS_C0201-DIFF BUS_0A 1        P5E_CPU1_PE3_TX_C_DP<13>
                                  2        P5E_CPU1_PE3_TX_DP<13>  
C1522            Q_CAP_DIFFBUS_C0201-DIFF BUS_0A 1        P5E_CPU1_PE3_TX_C_DN<12>
                                  2        P5E_CPU1_PE3_TX_DN<12>  
C1523            Q_CAP_DIFFBUS_C0201-DIFF BUS_0A 1        P5E_CPU1_PE3_TX_C_DP<12>
                                  2        P5E_CPU1_PE3_TX_DP<12>  
C1524            Q_CAP_DIFFBUS_C0201-DIFF BUS_0A 1        P5E_CPU1_PE3_TX_C_DN<11>
                                  2        P5E_CPU1_PE3_TX_DN<11>  
C1525            Q_CAP_DIFFBUS_C0201-DIFF BUS_0A 1        P5E_CPU1_PE3_TX_C_DP<11>
                                  2        P5E_CPU1_PE3_TX_DP<11>  
C1526            Q_CAP_DIFFBUS_C0201-DIFF BUS_0A 1        P5E_CPU1_PE3_TX_C_DN<10>
                                  2        P5E_CPU1_PE3_TX_DN<10>  
C1527            Q_CAP_DIFFBUS_C0201-DIFF BUS_0A 1        P5E_CPU1_PE3_TX_C_DP<10>
                                  2        P5E_CPU1_PE3_TX_DP<10>  
C1528            Q_CAP_DIFFBUS_C0201-DIFF BUS_0A 1        P5E_CPU1_PE3_TX_C_DN<9> 
                                  2        P5E_CPU1_PE3_TX_DN<9>   
C1529            Q_CAP_DIFFBUS_C0201-DIFF BUS_0A 1        P5E_CPU1_PE3_TX_C_DP<9> 
                                  2        P5E_CPU1_PE3_TX_DP<9>   
C1530            Q_CAP_DIFFBUS_C0201-DIFF BUS_0A 1        P5E_CPU1_PE3_TX_C_DN<8> 
                                  2        P5E_CPU1_PE3_TX_DN<8>   
C1531            Q_CAP_DIFFBUS_C0201-DIFF BUS_0A 1        P5E_CPU1_PE3_TX_C_DP<8> 
                                  2        P5E_CPU1_PE3_TX_DP<8>   
C1532            Q_CAP_DIFFBUS_C0201-DIFF BUS_0A 1        P5E_CPU1_PE3_TX_C_DN<7> 
                                  2        P5E_CPU1_PE3_TX_DN<7>   
C1533            Q_CAP_DIFFBUS_C0201-DIFF BUS_0A 1        P5E_CPU1_PE3_TX_C_DP<7> 
                                  2        P5E_CPU1_PE3_TX_DP<7>   
C1534            Q_CAP_DIFFBUS_C0201-DIFF BUS_0A 1        P5E_CPU1_PE3_TX_C_DN<6> 
                                  2        P5E_CPU1_PE3_TX_DN<6>   
C1535            Q_CAP_DIFFBUS_C0201-DIFF BUS_0A 1        P5E_CPU1_PE3_TX_C_DP<6> 
                                  2        P5E_CPU1_PE3_TX_DP<6>   
C1536            Q_CAP_DIFFBUS_C0201-DIFF BUS_0A 1        P5E_CPU1_PE3_TX_C_DN<5> 
                                  2        P5E_CPU1_PE3_TX_DN<5>   
C1537            Q_CAP_DIFFBUS_C0201-DIFF BUS_0A 1        P5E_CPU1_PE3_TX_C_DP<5> 
                                  2        P5E_CPU1_PE3_TX_DP<5>   
C1538            Q_CAP_DIFFBUS_C0201-DIFF BUS_0A 1        P5E_CPU1_PE3_TX_C_DN<4> 
                                  2        P5E_CPU1_PE3_TX_DN<4>   
C1539            Q_CAP_DIFFBUS_C0201-DIFF BUS_0A 1        P5E_CPU1_PE3_TX_C_DP<4> 
                                  2        P5E_CPU1_PE3_TX_DP<4>   
C1540            Q_CAP_DIFFBUS_C0201-DIFF BUS_0A 1        P5E_CPU1_PE3_TX_C_DN<3> 
                                  2        P5E_CPU1_PE3_TX_DN<3>   
C1541            Q_CAP_DIFFBUS_C0201-DIFF BUS_0A 1        P5E_CPU1_PE3_TX_C_DP<3> 
                                  2        P5E_CPU1_PE3_TX_DP<3>   
C1542            Q_CAP_DIFFBUS_C0201-DIFF BUS_0A 1        P5E_CPU1_PE3_TX_C_DN<2> 
                                  2        P5E_CPU1_PE3_TX_DN<2>   
C1543            Q_CAP_DIFFBUS_C0201-DIFF BUS_0A 1        P5E_CPU1_PE3_TX_C_DP<2> 
                                  2        P5E_CPU1_PE3_TX_DP<2>   
C1544            Q_CAP_DIFFBUS_C0201-DIFF BUS_0A 1        P5E_CPU1_PE3_TX_C_DN<1> 
                                  2        P5E_CPU1_PE3_TX_DN<1>   
C1545            Q_CAP_DIFFBUS_C0201-DIFF BUS_0A 1        P5E_CPU1_PE3_TX_C_DP<1> 
                                  2        P5E_CPU1_PE3_TX_DP<1>   
C1546            Q_CAP_DIFFBUS_C0201-DIFF BUS_0A 1        P5E_CPU1_PE3_TX_C_DN<0> 
                                  2        P5E_CPU1_PE3_TX_DN<0>   
C1547            Q_CAP_DIFFBUS_C0201-DIFF BUS_0A 1        P5E_CPU1_PE3_TX_C_DP<0> 
                                  2        P5E_CPU1_PE3_TX_DP<0>   
C1548            Q_CAP_DIFFBUS_C0201-DIFF BUS_0A 1        P5E_CPU0_PE4_TX_C_DN<15>
                                  2        P5E_CPU0_PE4_TX_DN<15>  
C1549            Q_CAP_DIFFBUS_C0201-DIFF BUS_0A 1        P5E_CPU0_PE4_TX_C_DP<15>
                                  2        P5E_CPU0_PE4_TX_DP<15>  
C1550            Q_CAP_DIFFBUS_C0201-DIFF BUS_0A 1        P5E_CPU0_PE4_TX_C_DN<14>
                                  2        P5E_CPU0_PE4_TX_DN<14>  
C1551            Q_CAP_DIFFBUS_C0201-DIFF BUS_0A 1        P5E_CPU0_PE4_TX_C_DP<14>
                                  2        P5E_CPU0_PE4_TX_DP<14>  
C1552            Q_CAP_DIFFBUS_C0201-DIFF BUS_0A 1        P5E_CPU0_PE4_TX_C_DN<13>
                                  2        P5E_CPU0_PE4_TX_DN<13>  
C1553            Q_CAP_DIFFBUS_C0201-DIFF BUS_0A 1        P5E_CPU0_PE4_TX_C_DP<13>
                                  2        P5E_CPU0_PE4_TX_DP<13>  
C1554            Q_CAP_DIFFBUS_C0201-DIFF BUS_0A 1        P5E_CPU0_PE4_TX_C_DN<12>
                                  2        P5E_CPU0_PE4_TX_DN<12>  
C1555            Q_CAP_DIFFBUS_C0201-DIFF BUS_0A 1        P5E_CPU0_PE4_TX_C_DP<12>
                                  2        P5E_CPU0_PE4_TX_DP<12>  
C1556            Q_CAP_DIFFBUS_C0201-DIFF BUS_0A 1        P5E_CPU0_PE4_TX_C_DN<11>
                                  2        P5E_CPU0_PE4_TX_DN<11>  
C1557            Q_CAP_DIFFBUS_C0201-DIFF BUS_0A 1        P5E_CPU0_PE4_TX_C_DP<11>
                                  2        P5E_CPU0_PE4_TX_DP<11>  
C1558            Q_CAP_DIFFBUS_C0201-DIFF BUS_0A 1        P5E_CPU0_PE4_TX_C_DN<10>
                                  2        P5E_CPU0_PE4_TX_DN<10>  
C1559            Q_CAP_DIFFBUS_C0201-DIFF BUS_0A 1        P5E_CPU0_PE4_TX_C_DP<10>
                                  2        P5E_CPU0_PE4_TX_DP<10>  
C1560            Q_CAP_DIFFBUS_C0201-DIFF BUS_0A 1        P5E_CPU0_PE4_TX_C_DN<9> 
                                  2        P5E_CPU0_PE4_TX_DN<9>   
C1561            Q_CAP_DIFFBUS_C0201-DIFF BUS_0A 1        P5E_CPU0_PE4_TX_C_DP<9> 
                                  2        P5E_CPU0_PE4_TX_DP<9>   
C1562            Q_CAP_DIFFBUS_C0201-DIFF BUS_0A 1        P5E_CPU0_PE4_TX_C_DN<8> 
                                  2        P5E_CPU0_PE4_TX_DN<8>   
C1563            Q_CAP_DIFFBUS_C0201-DIFF BUS_0A 1        P5E_CPU0_PE4_TX_C_DP<8> 
                                  2        P5E_CPU0_PE4_TX_DP<8>   
C1564            Q_CAP_DIFFBUS_C0201-DIFF BUS_0A 1        P5E_CPU0_PE4_TX_C_DN<7> 
                                  2        P5E_CPU0_PE4_TX_DN<7>   
C1565            Q_CAP_DIFFBUS_C0201-DIFF BUS_0A 1        P5E_CPU0_PE4_TX_C_DP<7> 
                                  2        P5E_CPU0_PE4_TX_DP<7>   
C1566            Q_CAP_DIFFBUS_C0201-DIFF BUS_0A 1        P5E_CPU0_PE4_TX_C_DN<6> 
                                  2        P5E_CPU0_PE4_TX_DN<6>   
C1567            Q_CAP_DIFFBUS_C0201-DIFF BUS_0A 1        P5E_CPU0_PE4_TX_C_DP<6> 
                                  2        P5E_CPU0_PE4_TX_DP<6>   
C1568            Q_CAP_DIFFBUS_C0201-DIFF BUS_0A 1        P5E_CPU0_PE4_TX_C_DN<5> 
                                  2        P5E_CPU0_PE4_TX_DN<5>   
C1569            Q_CAP_DIFFBUS_C0201-DIFF BUS_0A 1        P5E_CPU0_PE4_TX_C_DP<5> 
                                  2        P5E_CPU0_PE4_TX_DP<5>   
C1570            Q_CAP_DIFFBUS_C0201-DIFF BUS_0A 1        P5E_CPU0_PE4_TX_C_DN<4> 
                                  2        P5E_CPU0_PE4_TX_DN<4>   
C1571            Q_CAP_DIFFBUS_C0201-DIFF BUS_0A 1        P5E_CPU0_PE4_TX_C_DP<4> 
                                  2        P5E_CPU0_PE4_TX_DP<4>   
C1572            Q_CAP_DIFFBUS_C0201-DIFF BUS_0A 1        P5E_CPU0_PE4_TX_C_DN<3> 
                                  2        P5E_CPU0_PE4_TX_DN<3>   
C1573            Q_CAP_DIFFBUS_C0201-DIFF BUS_0A 1        P5E_CPU0_PE4_TX_C_DP<3> 
                                  2        P5E_CPU0_PE4_TX_DP<3>   
C1574            Q_CAP_DIFFBUS_C0201-DIFF BUS_0A 1        P5E_CPU0_PE4_TX_C_DN<2> 
                                  2        P5E_CPU0_PE4_TX_DN<2>   
C1575            Q_CAP_DIFFBUS_C0201-DIFF BUS_0A 1        P5E_CPU0_PE4_TX_C_DP<2> 
                                  2        P5E_CPU0_PE4_TX_DP<2>   
C1576            Q_CAP_DIFFBUS_C0201-DIFF BUS_0A 1        P5E_CPU0_PE4_TX_C_DN<1> 
                                  2        P5E_CPU0_PE4_TX_DN<1>   
C1577            Q_CAP_DIFFBUS_C0201-DIFF BUS_0A 1        P5E_CPU0_PE4_TX_C_DP<1> 
                                  2        P5E_CPU0_PE4_TX_DP<1>   
C1578            Q_CAP_DIFFBUS_C0201-DIFF BUS_0A 1        P5E_CPU0_PE4_TX_C_DN<0> 
                                  2        P5E_CPU0_PE4_TX_DN<0>   
C1579            Q_CAP_DIFFBUS_C0201-DIFF BUS_0A 1        P5E_CPU0_PE4_TX_C_DP<0> 
                                  2        P5E_CPU0_PE4_TX_DP<0>   
C1580            Q_CAP_0402-1NF,50V,10%,X7R,CH2A 1        MP5981_0_CLREF          
                                  2        GND                     
C1581            Q_CAP_C0402-1UF,25V,10%,EMPTY,A 1        VDD3                    
                                  2        GND                     
C1582            Q_CAP_C0402-100NF,50V,10%,X7R,A 1        MP5981_0_ON_PD          
                                  2        GND                     
C1583            Q_CAP_C0402-100NF,50V,10%,X7R,A 1        MPS5981_SS              
                                  2        GND                     
C1584            Q_CAP_C0402-100NF,50V,10%,X7R,A 1        MP5981_1_ON_PD          
                                  2        GND                     
C1585            Q_CAP_0402-1NF,50V,10%,X7R,CH2A 1        MP5981_1_CLREF          
                                  2        GND                     
C1586            Q_CAP_C0402-100NF,50V,10%,X7R,A 1        MPS5981_1_SS            
                                  2        GND                     
C1587            Q_CAP_C0402-1UF,25V,10%,EMPTY,A 1        VDD3                    
                                  2        GND                     
C1588            Q_CAP_0402-0.1UF,25V,10%,X7R,CA 1        P3V3_AUX                
                                  2        GND                     
C1589            Q_CAP_0402-0.1UF,25V,10%,X7R,CA 1        P3V3_AUX                
                                  2        GND                     
C1590            Q_CAP_0402-0.1UF,25V,10%,X7R,CA 1        P3V3_AUX                
                                  2        GND                     
C1591            Q_CAP_0402-0.1UF,25V,10%,X7R,CA 1        P3V3_AUX                
                                  2        GND                     
C1592            Q_CAP_0402-0.1UF,25V,10%,X7R,CA 1        P3V3_AUX                
                                  2        GND                     
C1593            Q_CAP_0402-0.1UF,25V,10%,X7R,CA 1        P3V3_AUX                
                                  2        GND                     
C1594            Q_CAP_0402-0.1UF,25V,10%,X7R,CA 1        P3V3_AUX                
                                  2        GND                     
C1595            Q_CAP_0402-0.1UF,25V,10%,X7R,CA 1        P3V3_AUX                
                                  2        GND                     
C1596            Q_CAP_C0402-0.047UF,25V,10%,X7A 1        P12V_SCM_DVDT           
                                  2        GND                     
C1597            Q_CAP_0402-0.1UF,25V,10%,X7R,CA 1        P12V_AUX                
                                  2        GND                     
C1598            Q_CAP_C0805-10UF,25V,10%,X6S,CA 1        P12V_SCM                
                                  2        GND                     
C1599            Q_CAP_C0805-22UF,10V,20%,X6S,CA 1        P3V3_AUX                
                                  2        GND                     
C1600            Q_CAP_C0805-22UF,10V,20%,X6S,CA 1        P3V3_AUX                
                                  2        GND                     
C1601            Q_CAPP_SMLF-100UF,16V,20%,POSCA 1        P12V_FRONT_CPU          
                                  2        GND                     
C1602            Q_CAP_0402-0.1UF,25V,10%,X7R,CA 1        P12V_FRONT_CPU          
                                  2        GND                     
C1603            Q_CAPP_SMLF-100UF,16V,20%,POSCA 1        P3V3                    
                                  2        GND                     
C1604            Q_CAP_0402-0.1UF,25V,10%,X7R,CA 1        P3V3                    
                                  2        GND                     
C1605            Q_CAP_C0402-1UF,25V,10%,X6S,CHA 1        P3V3_AUX                
                                  2        GND                     
C1606            Q_CAP_0402-0.1UF,25V,10%,X7R,CA 1        P3V3_AUX                
                                  2        GND                     
C1607            Q_CAP_0402-0.1UF,25V,10%,X7R,CA 1        P3V3_AUX                
                                  2        GND                     
C2443            Q_CAP_C0402-10UF,6.3V,20%,X6S,A 1        PVNN_TERM_CPU0          
                                  2        GND                     
C2444            Q_CAP_0402-0.1UF,25V,10%,X7R,CA 1        PVNN_TERM_CPU0          
                                  2        GND                     
C2445            Q_CAP_0402-1000PF,50V,5%,EMPTYA 1        FM_PVPP_HBM_CPU1_EN     
                                  2        GND                     
C2446            Q_CAP_0402-1000PF,50V,5%,X7R,TA 1        PWRGD_PVPP_HBM_CPU1_R   
                                  2        GND                     
D0               Q_LED_SMLF-LED_GREEN,19-213/GVA A        PU_PLD_HEARTBEAT_LVC3   
                                  C        FM_PLD_HEARTBEAT_LVC3_D 
D4               SCHOTTKY_AC-SX34F,SMLF,IC,BC00A A        GND                     
                                  C        P12V_OCP_SFF            
D6               Q_LED_SMLF-LED_RED,19-217/R6C-A A        LED_CPU_RMCA_CATERR     
                                  C        GND                     
D7               BAT547F-BAT547F,SMLF,IC,BC0BATA 1        P3V3                    
                                  3        P5V                     
D8               DIODE_TVS-SMF14A,SMLF,IC,BCSMFA A        GND                     
                                  C        P12V_FRONT_CPU          
D9               DIODE_TVS-SMF14A,SMLF,IC,BCSMFA A        GND                     
                                  C        P12V_FRONT_CPU          
D10              DIODE_TVS-SMF14A,SMLF,IC,BCSMFA A        GND                     
                                  C        P12V_FRONT_CPU          
D11              DIODE_TVS-SMF14A,SMLF,IC,BCSMFA A        GND                     
                                  C        P12V_FRONT_CPU          
D12              DIODE_TVS-SMF14A,SMLF,IC,BCSMFA A        GND                     
                                  C        P12V_AUX                
DB1              TDR_3P_TH2-EMPTY,N_A 1        T_GND                   
                                  2        TDR_SE_40_OHM_TOP       
                                  3        TDR_SE_40_OHM_TOP       
DB2              TDR_3P_TH2-EMPTY,N_A 1        T_GND                   
                                  2        TDR_SE_40_OHM_IN1       
                                  3        TDR_SE_40_OHM_IN1       
DB3              TDR_3P_TH2-EMPTY,N_A 1        T_GND                   
                                  2        TDR_SE_40_OHM_IN2       
                                  3        TDR_SE_40_OHM_IN2       
DB4              TDR_3P_TH2-EMPTY,N_A 1        T_GND                   
                                  2        TDR_SE_40_OHM_IN3       
                                  3        TDR_SE_40_OHM_IN3       
DB5              TDR_3P_TH2-EMPTY,N_A 1        T_GND                   
                                  2        TDR_SE_40_OHM_IN4       
                                  3        TDR_SE_40_OHM_IN4       
DB6              TDR_3P_TH2-EMPTY,N_A 1        T_GND                   
                                  2        TDR_SE_40_OHM_BOT       
                                  3        TDR_SE_40_OHM_BOT       
DB7              TDR_3P_TH2-EMPTY,N_A 1        T_GND                   
                                  2        TDR_SE_50_OHM_TOP       
                                  3        TDR_SE_50_OHM_TOP       
DB8              TDR_3P_TH2-EMPTY,N_A 1        T_GND                   
                                  2        TDR_SE_50_OHM_IN1       
                                  3        TDR_SE_50_OHM_IN1       
DB9              TDR_3P_TH2-EMPTY,N_A 1        T_GND                   
                                  2        TDR_SE_50_OHM_IN2       
                                  3        TDR_SE_50_OHM_IN2       
DB10             TDR_3P_TH2-EMPTY,N_A 1        T_GND                   
                                  2        TDR_SE_50_OHM_IN3       
                                  3        TDR_SE_50_OHM_IN3       
DB11             TDR_3P_TH2-EMPTY,N_A 1        T_GND                   
                                  2        TDR_SE_50_OHM_IN4       
                                  3        TDR_SE_50_OHM_IN4       
DB12             TDR_3P_TH2-EMPTY,N_A 1        T_GND                   
                                  2        TDR_SE_50_OHM_BOT       
                                  3        TDR_SE_50_OHM_BOT       
H1               HOLE_TH-EMPTY,HOLE1087 1        GND                     
H2               HOLE_TH-EMPTY,HOLE1087 1        GND                     
H3               HOLE_TH-EMPTY,HOLE1087 1        GND                     
H4               HOLE_TH-EMPTY,HOLE1087 1        GND                     
H5               HOLE_TH-EMPTY,HOLE1087 1        GND                     
H6               HOLE_TH-EMPTY,HOLE1087 1        GND                     
H7               HOLE_TH-EMPTY,HOLE1087 1        GND                     
H8               HOLE_TH-EMPTY,HOLE1087 1        GND                     
H9               HOLE_TH-EMPTY,HOLE1087 1        GND                     
H10              HOLE_TH-EMPTY,HOLE1087 1        GND                     
H11              HOLE_TH-EMPTY,HOLE1087 1        GND                     
H12              HOLE_TH-EMPTY,HOLE1087 1        GND                     
H13              HOLE_TH-EMPTY,HOLE1087 1        GND                     
H31              HOLE_TH-EMPTY,HOLE1214 1        GND                     
H32              HOLE_TH-EMPTY,HOLE1214 1        GND                     
H35              HOLE_TH-EMPTY,HOLE1098 1        GND                     
H37              HOLE_TH-EMPTY,HOLE1098 1        GND                     
H39              HOLE_TH-EMPTY,HOLE1222 1        GND                     
H40              HOLE_TH-EMPTY,HOLE1222 1        GND                     
H44              HOLE_TH-EMPTY,HOLE1212 1        GND                     
H45              HOLE_TH-EMPTY,HOLE1212 1        GND                     
H47              HOLE_TH-EMPTY,HOLE1212 1        GND                     
H49              HOLE_TH-EMPTY,HOLE1212 1        GND                     
H54              HOLE_TH-EMPTY,HOLE1087 1        GND                     
H55              HOLE_TH-EMPTY,HOLE1087 1        GND                     
J1               SCONN288_ADR50001P013C01-SCONNA 1        P12V_S3_AUX_CPU0_NVDIMM 
                                  3        P3V3_AUX                
                                  4        I3C_SPD_DDRABCD_CPU0_LVC1_SCL
                                  5        I3C_SPD_DDRABCD_CPU0_LVC1_SDA
                                  6        GND                     
                                  7        M_A_CPU0_SA_DQ<0>       
                                  8        GND                     
                                  9        M_A_CPU0_SA_DQ<1>       
                                  10       GND                     
                                  11       M_A_CPU0_SA_DQS_DP<0>   
                                  12       M_A_CPU0_SA_DQS_DN<0>   
                                  13       GND                     
                                  14       M_A_CPU0_SA_DQ<4>       
                                  15       GND                     
                                  16       M_A_CPU0_SA_DQ<5>       
                                  17       GND                     
                                  18       M_A_CPU0_SA_DQ<8>       
                                  19       GND                     
                                  20       M_A_CPU0_SA_DQ<9>       
                                  21       GND                     
                                  22       M_A_CPU0_SA_DQS_DP<1>   
                                  23       M_A_CPU0_SA_DQS_DN<1>   
                                  24       GND                     
                                  25       M_A_CPU0_SA_DQ<12>      
                                  26       GND                     
                                  27       M_A_CPU0_SA_DQ<13>      
                                  28       GND                     
                                  29       M_A_CPU0_SA_DQ<16>      
                                  30       GND                     
                                  31       M_A_CPU0_SA_DQ<17>      
                                  32       GND                     
                                  33       M_A_CPU0_SA_DQS_DP<2>   
                                  34       M_A_CPU0_SA_DQS_DN<2>   
                                  35       GND                     
                                  36       M_A_CPU0_SA_DQ<20>      
                                  37       GND                     
                                  38       M_A_CPU0_SA_DQ<21>      
                                  39       GND                     
                                  40       M_A_CPU0_SA_DQ<24>      
                                  41       GND                     
                                  42       M_A_CPU0_SA_DQ<25>      
                                  43       GND                     
                                  44       M_A_CPU0_SA_DQS_DP<3>   
                                  45       M_A_CPU0_SA_DQS_DN<3>   
                                  46       GND                     
                                  47       M_A_CPU0_SA_DQ<28>      
                                  48       GND                     
                                  49       M_A_CPU0_SA_DQ<29>      
                                  50       GND                     
                                  51       M_A_CPU0_SA_CB<0>       
                                  52       GND                     
                                  53       M_A_CPU0_SA_CB<1>       
                                  54       GND                     
                                  55       M_A_CPU0_SA_DQS_DP<4>   
                                  56       M_A_CPU0_SA_DQS_DN<4>   
                                  57       GND                     
                                  58       M_A_CPU0_SA_CB<4>       
                                  59       GND                     
                                  60       M_A_CPU0_SA_CB<5>       
                                  61       GND                     
                                  62       M_A_CPU0_ALERT_N        
                                  63       GND                     
                                  64       M_A_CPU0_SA_CS_N<0>     
                                  65       GND                     
                                  66       M_A_CPU0_SA_CA<0>       
                                  67       GND                     
                                  68       M_A_CPU0_SA_CA<2>       
                                  69       GND                     
                                  70       M_A_CPU0_SA_CA<4>       
                                  71       GND                     
                                  72       M_A_CPU0_SA_CA<6>       
                                  73       GND                     
                                  74       M_A_CPU0_SA_PAR         
                                  75       GND                     
                                  76       M_A_CPU0_SB_CA<0>       
                                  77       GND                     
                                  78       M_A_CPU0_SB_CA<2>       
                                  79       GND                     
                                  80       M_A_CPU0_SB_CA<4>       
                                  81       GND                     
                                  82       M_A_CPU0_SB_CA<6>       
                                  83       GND                     
                                  84       M_A_CPU0_SB_CS_N<0>     
                                  85       GND                     
                                  86       M_A_CPU0_SA_RSP<0>      
                                  87       M_A_CPU0_SB_RSP<0>      
                                  88       GND                     
                                  89       M_A_CPU0_SB_CB<4>       
                                  90       GND                     
                                  91       M_A_CPU0_SB_CB<5>       
                                  92       GND                     
                                  93       M_A_CPU0_SB_DQS_DP<9>   
                                  94       M_A_CPU0_SB_DQS_DN<9>   
                                  95       GND                     
                                  96       M_A_CPU0_SB_CB<0>       
                                  97       GND                     
                                  98       M_A_CPU0_SB_CB<1>       
                                  99       GND                     
                                  100      M_A_CPU0_SB_DQ<0>       
                                  101      GND                     
                                  102      M_A_CPU0_SB_DQ<1>       
                                  103      GND                     
                                  104      M_A_CPU0_SB_DQS_DP<0>   
                                  105      M_A_CPU0_SB_DQS_DN<0>   
                                  106      GND                     
                                  107      M_A_CPU0_SB_DQ<4>       
                                  108      GND                     
                                  109      M_A_CPU0_SB_DQ<5>       
                                  110      GND                     
                                  111      M_A_CPU0_SB_DQ<8>       
                                  112      GND                     
                                  113      M_A_CPU0_SB_DQ<9>       
                                  114      GND                     
                                  115      M_A_CPU0_SB_DQS_DP<1>   
                                  116      M_A_CPU0_SB_DQS_DN<1>   
                                  117      GND                     
                                  118      M_A_CPU0_SB_DQ<12>      
                                  119      GND                     
                                  120      M_A_CPU0_SB_DQ<13>      
                                  121      GND                     
                                  122      M_A_CPU0_SB_DQ<16>      
                                  123      GND                     
                                  124      M_A_CPU0_SB_DQ<17>      
                                  125      GND                     
                                  126      M_A_CPU0_SB_DQS_DP<2>   
                                  127      M_A_CPU0_SB_DQS_DN<2>   
                                  128      GND                     
                                  129      M_A_CPU0_SB_DQ<20>      
                                  130      GND                     
                                  131      M_A_CPU0_SB_DQ<21>      
                                  132      GND                     
                                  133      M_A_CPU0_SB_DQ<24>      
                                  134      GND                     
                                  135      M_A_CPU0_SB_DQ<25>      
                                  136      GND                     
                                  137      M_A_CPU0_SB_DQS_DP<3>   
                                  138      M_A_CPU0_SB_DQS_DN<3>   
                                  139      GND                     
                                  140      M_A_CPU0_SB_DQ<28>      
                                  141      GND                     
                                  142      M_A_CPU0_SB_DQ<29>      
                                  143      GND                     
                                  145      P12V_S3_AUX_CPU0_NVDIMM 
                                  146      P12V_S3_AUX_CPU0_NVDIMM 
                                  147      PWRGD_CHA_CPU0_DIMM1    
                                  148      PD_CHA_CPU0_DIMM1_SAA   
                                  151      GND                     
                                  152      M_A_CPU0_SA_DQ<2>       
                                  153      GND                     
                                  154      M_A_CPU0_SA_DQ<3>       
                                  155      GND                     
                                  156      M_A_CPU0_SA_DQS_DN<5>   
                                  157      M_A_CPU0_SA_DQS_DP<5>   
                                  158      GND                     
                                  159      M_A_CPU0_SA_DQ<6>       
                                  160      GND                     
                                  161      M_A_CPU0_SA_DQ<7>       
                                  162      GND                     
                                  163      M_A_CPU0_SA_DQ<10>      
                                  164      GND                     
                                  165      M_A_CPU0_SA_DQ<11>      
                                  166      GND                     
                                  167      M_A_CPU0_SA_DQS_DN<6>   
                                  168      M_A_CPU0_SA_DQS_DP<6>   
                                  169      GND                     
                                  170      M_A_CPU0_SA_DQ<14>      
                                  171      GND                     
                                  172      M_A_CPU0_SA_DQ<15>      
                                  173      GND                     
                                  174      M_A_CPU0_SA_DQ<18>      
                                  175      GND                     
                                  176      M_A_CPU0_SA_DQ<19>      
                                  177      GND                     
                                  178      M_A_CPU0_SA_DQS_DN<7>   
                                  179      M_A_CPU0_SA_DQS_DP<7>   
                                  180      GND                     
                                  181      M_A_CPU0_SA_DQ<22>      
                                  182      GND                     
                                  183      M_A_CPU0_SA_DQ<23>      
                                  184      GND                     
                                  185      M_A_CPU0_SA_DQ<26>      
                                  186      GND                     
                                  187      M_A_CPU0_SA_DQ<27>      
                                  188      GND                     
                                  189      M_A_CPU0_SA_DQS_DN<8>   
                                  190      M_A_CPU0_SA_DQS_DP<8>   
                                  191      GND                     
                                  192      M_A_CPU0_SA_DQ<30>      
                                  193      GND                     
                                  194      M_A_CPU0_SA_DQ<31>      
                                  195      GND                     
                                  196      M_A_CPU0_SA_CB<2>       
                                  197      GND                     
                                  198      M_A_CPU0_SA_CB<3>       
                                  199      GND                     
                                  200      M_A_CPU0_SA_DQS_DN<9>   
                                  201      M_A_CPU0_SA_DQS_DP<9>   
                                  202      GND                     
                                  203      M_A_CPU0_SA_CB<6>       
                                  204      GND                     
                                  205      M_A_CPU0_SA_CB<7>       
                                  206      GND                     
                                  207      RST_M_AB_CPU0_FPGA_N    
                                  208      GND                     
                                  209      M_A_CPU0_SA_CS_N<1>     
                                  210      GND                     
                                  211      M_A_CPU0_SA_CA<1>       
                                  212      GND                     
                                  213      M_A_CPU0_SA_CA<3>       
                                  214      GND                     
                                  215      M_A_CPU0_SA_CA<5>       
                                  216      GND                     
                                  217      M_A_CPU0_CLK_DP<0>      
                                  218      M_A_CPU0_CLK_DN<0>      
                                  219      GND                     
                                  221      M_A_CPU0_SB_CA<1>       
                                  222      GND                     
                                  223      M_A_CPU0_SB_CA<3>       
                                  224      GND                     
                                  225      M_A_CPU0_SB_CA<5>       
                                  226      GND                     
                                  227      M_A_CPU0_SB_PAR         
                                  228      GND                     
                                  229      M_A_CPU0_SB_CS_N<1>     
                                  230      GND                     
                                  233      GND                     
                                  234      M_A_CPU0_SB_CB<6>       
                                  235      GND                     
                                  236      M_A_CPU0_SB_CB<7>       
                                  237      GND                     
                                  238      M_A_CPU0_SB_DQS_DN<4>   
                                  239      M_A_CPU0_SB_DQS_DP<4>   
                                  240      GND                     
                                  241      M_A_CPU0_SB_CB<2>       
                                  242      GND                     
                                  243      M_A_CPU0_SB_CB<3>       
                                  244      GND                     
                                  245      M_A_CPU0_SB_DQ<2>       
                                  246      GND                     
                                  247      M_A_CPU0_SB_DQ<3>       
                                  248      GND                     
                                  249      M_A_CPU0_SB_DQS_DN<5>   
                                  250      M_A_CPU0_SB_DQS_DP<5>   
                                  251      GND                     
                                  252      M_A_CPU0_SB_DQ<6>       
                                  253      GND                     
                                  254      M_A_CPU0_SB_DQ<7>       
                                  255      GND                     
                                  256      M_A_CPU0_SB_DQ<10>      
                                  257      GND                     
                                  258      M_A_CPU0_SB_DQ<11>      
                                  259      GND                     
                                  260      M_A_CPU0_SB_DQS_DN<6>   
                                  261      M_A_CPU0_SB_DQS_DP<6>   
                                  262      GND                     
                                  263      M_A_CPU0_SB_DQ<14>      
                                  264      GND                     
                                  265      M_A_CPU0_SB_DQ<15>      
                                  266      GND                     
                                  267      M_A_CPU0_SB_DQ<18>      
                                  268      GND                     
                                  269      M_A_CPU0_SB_DQ<19>      
                                  270      GND                     
                                  271      M_A_CPU0_SB_DQS_DN<7>   
                                  272      M_A_CPU0_SB_DQS_DP<7>   
                                  273      GND                     
                                  274      M_A_CPU0_SB_DQ<22>      
                                  275      GND                     
                                  276      M_A_CPU0_SB_DQ<23>      
                                  277      GND                     
                                  278      M_A_CPU0_SB_DQ<26>      
                                  279      GND                     
                                  280      M_A_CPU0_SB_DQ<27>      
                                  281      GND                     
                                  282      M_A_CPU0_SB_DQS_DN<8>   
                                  283      M_A_CPU0_SB_DQS_DP<8>   
                                  284      GND                     
                                  285      M_A_CPU0_SB_DQ<30>      
                                  286      GND                     
                                  287      M_A_CPU0_SB_DQ<31>      
                                  288      GND                     
                                  G1       GND                     
                                  G2       GND                     
                                  G3       GND                     
J2               SCONN288_ADR50001P003C01-SCONNA 1        P12V_S3_AUX_CPU0_NVDIMM 
                                  3        P3V3_AUX                
                                  4        I3C_SPD_DDRABCD_CPU0_LVC1_SCL
                                  5        I3C_SPD_DDRABCD_CPU0_LVC1_SDA
                                  6        GND                     
                                  7        M_A_CPU0_SA_DQ<0>       
                                  8        GND                     
                                  9        M_A_CPU0_SA_DQ<1>       
                                  10       GND                     
                                  11       M_A_CPU0_SA_DQS_DP<0>   
                                  12       M_A_CPU0_SA_DQS_DN<0>   
                                  13       GND                     
                                  14       M_A_CPU0_SA_DQ<4>       
                                  15       GND                     
                                  16       M_A_CPU0_SA_DQ<5>       
                                  17       GND                     
                                  18       M_A_CPU0_SA_DQ<8>       
                                  19       GND                     
                                  20       M_A_CPU0_SA_DQ<9>       
                                  21       GND                     
                                  22       M_A_CPU0_SA_DQS_DP<1>   
                                  23       M_A_CPU0_SA_DQS_DN<1>   
                                  24       GND                     
                                  25       M_A_CPU0_SA_DQ<12>      
                                  26       GND                     
                                  27       M_A_CPU0_SA_DQ<13>      
                                  28       GND                     
                                  29       M_A_CPU0_SA_DQ<16>      
                                  30       GND                     
                                  31       M_A_CPU0_SA_DQ<17>      
                                  32       GND                     
                                  33       M_A_CPU0_SA_DQS_DP<2>   
                                  34       M_A_CPU0_SA_DQS_DN<2>   
                                  35       GND                     
                                  36       M_A_CPU0_SA_DQ<20>      
                                  37       GND                     
                                  38       M_A_CPU0_SA_DQ<21>      
                                  39       GND                     
                                  40       M_A_CPU0_SA_DQ<24>      
                                  41       GND                     
                                  42       M_A_CPU0_SA_DQ<25>      
                                  43       GND                     
                                  44       M_A_CPU0_SA_DQS_DP<3>   
                                  45       M_A_CPU0_SA_DQS_DN<3>   
                                  46       GND                     
                                  47       M_A_CPU0_SA_DQ<28>      
                                  48       GND                     
                                  49       M_A_CPU0_SA_DQ<29>      
                                  50       GND                     
                                  51       M_A_CPU0_SA_CB<0>       
                                  52       GND                     
                                  53       M_A_CPU0_SA_CB<1>       
                                  54       GND                     
                                  55       M_A_CPU0_SA_DQS_DP<4>   
                                  56       M_A_CPU0_SA_DQS_DN<4>   
                                  57       GND                     
                                  58       M_A_CPU0_SA_CB<4>       
                                  59       GND                     
                                  60       M_A_CPU0_SA_CB<5>       
                                  61       GND                     
                                  62       M_A_CPU0_ALERT_N        
                                  63       GND                     
                                  64       M_A_CPU0_SA_CS_N<2>     
                                  65       GND                     
                                  66       M_A_CPU0_SA_CA<0>       
                                  67       GND                     
                                  68       M_A_CPU0_SA_CA<2>       
                                  69       GND                     
                                  70       M_A_CPU0_SA_CA<4>       
                                  71       GND                     
                                  72       M_A_CPU0_SA_CA<6>       
                                  73       GND                     
                                  74       M_A_CPU0_SA_PAR         
                                  75       GND                     
                                  76       M_A_CPU0_SB_CA<0>       
                                  77       GND                     
                                  78       M_A_CPU0_SB_CA<2>       
                                  79       GND                     
                                  80       M_A_CPU0_SB_CA<4>       
                                  81       GND                     
                                  82       M_A_CPU0_SB_CA<6>       
                                  83       GND                     
                                  84       M_A_CPU0_SB_CS_N<2>     
                                  85       GND                     
                                  86       M_A_CPU0_SA_RSP<1>      
                                  87       M_A_CPU0_SB_RSP<1>      
                                  88       GND                     
                                  89       M_A_CPU0_SB_CB<4>       
                                  90       GND                     
                                  91       M_A_CPU0_SB_CB<5>       
                                  92       GND                     
                                  93       M_A_CPU0_SB_DQS_DP<9>   
                                  94       M_A_CPU0_SB_DQS_DN<9>   
                                  95       GND                     
                                  96       M_A_CPU0_SB_CB<0>       
                                  97       GND                     
                                  98       M_A_CPU0_SB_CB<1>       
                                  99       GND                     
                                  100      M_A_CPU0_SB_DQ<0>       
                                  101      GND                     
                                  102      M_A_CPU0_SB_DQ<1>       
                                  103      GND                     
                                  104      M_A_CPU0_SB_DQS_DP<0>   
                                  105      M_A_CPU0_SB_DQS_DN<0>   
                                  106      GND                     
                                  107      M_A_CPU0_SB_DQ<4>       
                                  108      GND                     
                                  109      M_A_CPU0_SB_DQ<5>       
                                  110      GND                     
                                  111      M_A_CPU0_SB_DQ<8>       
                                  112      GND                     
                                  113      M_A_CPU0_SB_DQ<9>       
                                  114      GND                     
                                  115      M_A_CPU0_SB_DQS_DP<1>   
                                  116      M_A_CPU0_SB_DQS_DN<1>   
                                  117      GND                     
                                  118      M_A_CPU0_SB_DQ<12>      
                                  119      GND                     
                                  120      M_A_CPU0_SB_DQ<13>      
                                  121      GND                     
                                  122      M_A_CPU0_SB_DQ<16>      
                                  123      GND                     
                                  124      M_A_CPU0_SB_DQ<17>      
                                  125      GND                     
                                  126      M_A_CPU0_SB_DQS_DP<2>   
                                  127      M_A_CPU0_SB_DQS_DN<2>   
                                  128      GND                     
                                  129      M_A_CPU0_SB_DQ<20>      
                                  130      GND                     
                                  131      M_A_CPU0_SB_DQ<21>      
                                  132      GND                     
                                  133      M_A_CPU0_SB_DQ<24>      
                                  134      GND                     
                                  135      M_A_CPU0_SB_DQ<25>      
                                  136      GND                     
                                  137      M_A_CPU0_SB_DQS_DP<3>   
                                  138      M_A_CPU0_SB_DQS_DN<3>   
                                  139      GND                     
                                  140      M_A_CPU0_SB_DQ<28>      
                                  141      GND                     
                                  142      M_A_CPU0_SB_DQ<29>      
                                  143      GND                     
                                  145      P12V_S3_AUX_CPU0_NVDIMM 
                                  146      P12V_S3_AUX_CPU0_NVDIMM 
                                  147      PWRGD_CHA_CPU0_DIMM2    
                                  148      PD_CHA_CPU0_DIMM2_SAA   
                                  151      GND                     
                                  152      M_A_CPU0_SA_DQ<2>       
                                  153      GND                     
                                  154      M_A_CPU0_SA_DQ<3>       
                                  155      GND                     
                                  156      M_A_CPU0_SA_DQS_DN<5>   
                                  157      M_A_CPU0_SA_DQS_DP<5>   
                                  158      GND                     
                                  159      M_A_CPU0_SA_DQ<6>       
                                  160      GND                     
                                  161      M_A_CPU0_SA_DQ<7>       
                                  162      GND                     
                                  163      M_A_CPU0_SA_DQ<10>      
                                  164      GND                     
                                  165      M_A_CPU0_SA_DQ<11>      
                                  166      GND                     
                                  167      M_A_CPU0_SA_DQS_DN<6>   
                                  168      M_A_CPU0_SA_DQS_DP<6>   
                                  169      GND                     
                                  170      M_A_CPU0_SA_DQ<14>      
                                  171      GND                     
                                  172      M_A_CPU0_SA_DQ<15>      
                                  173      GND                     
                                  174      M_A_CPU0_SA_DQ<18>      
                                  175      GND                     
                                  176      M_A_CPU0_SA_DQ<19>      
                                  177      GND                     
                                  178      M_A_CPU0_SA_DQS_DN<7>   
                                  179      M_A_CPU0_SA_DQS_DP<7>   
                                  180      GND                     
                                  181      M_A_CPU0_SA_DQ<22>      
                                  182      GND                     
                                  183      M_A_CPU0_SA_DQ<23>      
                                  184      GND                     
                                  185      M_A_CPU0_SA_DQ<26>      
                                  186      GND                     
                                  187      M_A_CPU0_SA_DQ<27>      
                                  188      GND                     
                                  189      M_A_CPU0_SA_DQS_DN<8>   
                                  190      M_A_CPU0_SA_DQS_DP<8>   
                                  191      GND                     
                                  192      M_A_CPU0_SA_DQ<30>      
                                  193      GND                     
                                  194      M_A_CPU0_SA_DQ<31>      
                                  195      GND                     
                                  196      M_A_CPU0_SA_CB<2>       
                                  197      GND                     
                                  198      M_A_CPU0_SA_CB<3>       
                                  199      GND                     
                                  200      M_A_CPU0_SA_DQS_DN<9>   
                                  201      M_A_CPU0_SA_DQS_DP<9>   
                                  202      GND                     
                                  203      M_A_CPU0_SA_CB<6>       
                                  204      GND                     
                                  205      M_A_CPU0_SA_CB<7>       
                                  206      GND                     
                                  207      RST_M_AB_CPU0_FPGA_N    
                                  208      GND                     
                                  209      M_A_CPU0_SA_CS_N<3>     
                                  210      GND                     
                                  211      M_A_CPU0_SA_CA<1>       
                                  212      GND                     
                                  213      M_A_CPU0_SA_CA<3>       
                                  214      GND                     
                                  215      M_A_CPU0_SA_CA<5>       
                                  216      GND                     
                                  217      M_A_CPU0_CLK_DP<1>      
                                  218      M_A_CPU0_CLK_DN<1>      
                                  219      GND                     
                                  221      M_A_CPU0_SB_CA<1>       
                                  222      GND                     
                                  223      M_A_CPU0_SB_CA<3>       
                                  224      GND                     
                                  225      M_A_CPU0_SB_CA<5>       
                                  226      GND                     
                                  227      M_A_CPU0_SB_PAR         
                                  228      GND                     
                                  229      M_A_CPU0_SB_CS_N<3>     
                                  230      GND                     
                                  233      GND                     
                                  234      M_A_CPU0_SB_CB<6>       
                                  235      GND                     
                                  236      M_A_CPU0_SB_CB<7>       
                                  237      GND                     
                                  238      M_A_CPU0_SB_DQS_DN<4>   
                                  239      M_A_CPU0_SB_DQS_DP<4>   
                                  240      GND                     
                                  241      M_A_CPU0_SB_CB<2>       
                                  242      GND                     
                                  243      M_A_CPU0_SB_CB<3>       
                                  244      GND                     
                                  245      M_A_CPU0_SB_DQ<2>       
                                  246      GND                     
                                  247      M_A_CPU0_SB_DQ<3>       
                                  248      GND                     
                                  249      M_A_CPU0_SB_DQS_DN<5>   
                                  250      M_A_CPU0_SB_DQS_DP<5>   
                                  251      GND                     
                                  252      M_A_CPU0_SB_DQ<6>       
                                  253      GND                     
                                  254      M_A_CPU0_SB_DQ<7>       
                                  255      GND                     
                                  256      M_A_CPU0_SB_DQ<10>      
                                  257      GND                     
                                  258      M_A_CPU0_SB_DQ<11>      
                                  259      GND                     
                                  260      M_A_CPU0_SB_DQS_DN<6>   
                                  261      M_A_CPU0_SB_DQS_DP<6>   
                                  262      GND                     
                                  263      M_A_CPU0_SB_DQ<14>      
                                  264      GND                     
                                  265      M_A_CPU0_SB_DQ<15>      
                                  266      GND                     
                                  267      M_A_CPU0_SB_DQ<18>      
                                  268      GND                     
                                  269      M_A_CPU0_SB_DQ<19>      
                                  270      GND                     
                                  271      M_A_CPU0_SB_DQS_DN<7>   
                                  272      M_A_CPU0_SB_DQS_DP<7>   
                                  273      GND                     
                                  274      M_A_CPU0_SB_DQ<22>      
                                  275      GND                     
                                  276      M_A_CPU0_SB_DQ<23>      
                                  277      GND                     
                                  278      M_A_CPU0_SB_DQ<26>      
                                  279      GND                     
                                  280      M_A_CPU0_SB_DQ<27>      
                                  281      GND                     
                                  282      M_A_CPU0_SB_DQS_DN<8>   
                                  283      M_A_CPU0_SB_DQS_DP<8>   
                                  284      GND                     
                                  285      M_A_CPU0_SB_DQ<30>      
                                  286      GND                     
                                  287      M_A_CPU0_SB_DQ<31>      
                                  288      GND                     
                                  G1       GND                     
                                  G2       GND                     
                                  G3       GND                     
J3               SCONN288_ADR50001P013C01-SCONNA 1        P12V_S3_AUX_CPU0_NVDIMM 
                                  3        P3V3_AUX                
                                  4        I3C_SPD_DDRABCD_CPU0_LVC1_SCL
                                  5        I3C_SPD_DDRABCD_CPU0_LVC1_SDA
                                  6        GND                     
                                  7        M_B_CPU0_SA_DQ<0>       
                                  8        GND                     
                                  9        M_B_CPU0_SA_DQ<1>       
                                  10       GND                     
                                  11       M_B_CPU0_SA_DQS_DP<0>   
                                  12       M_B_CPU0_SA_DQS_DN<0>   
                                  13       GND                     
                                  14       M_B_CPU0_SA_DQ<4>       
                                  15       GND                     
                                  16       M_B_CPU0_SA_DQ<5>       
                                  17       GND                     
                                  18       M_B_CPU0_SA_DQ<8>       
                                  19       GND                     
                                  20       M_B_CPU0_SA_DQ<9>       
                                  21       GND                     
                                  22       M_B_CPU0_SA_DQS_DP<1>   
                                  23       M_B_CPU0_SA_DQS_DN<1>   
                                  24       GND                     
                                  25       M_B_CPU0_SA_DQ<12>      
                                  26       GND                     
                                  27       M_B_CPU0_SA_DQ<13>      
                                  28       GND                     
                                  29       M_B_CPU0_SA_DQ<16>      
                                  30       GND                     
                                  31       M_B_CPU0_SA_DQ<17>      
                                  32       GND                     
                                  33       M_B_CPU0_SA_DQS_DP<2>   
                                  34       M_B_CPU0_SA_DQS_DN<2>   
                                  35       GND                     
                                  36       M_B_CPU0_SA_DQ<20>      
                                  37       GND                     
                                  38       M_B_CPU0_SA_DQ<21>      
                                  39       GND                     
                                  40       M_B_CPU0_SA_DQ<24>      
                                  41       GND                     
                                  42       M_B_CPU0_SA_DQ<25>      
                                  43       GND                     
                                  44       M_B_CPU0_SA_DQS_DP<3>   
                                  45       M_B_CPU0_SA_DQS_DN<3>   
                                  46       GND                     
                                  47       M_B_CPU0_SA_DQ<28>      
                                  48       GND                     
                                  49       M_B_CPU0_SA_DQ<29>      
                                  50       GND                     
                                  51       M_B_CPU0_SA_CB<0>       
                                  52       GND                     
                                  53       M_B_CPU0_SA_CB<1>       
                                  54       GND                     
                                  55       M_B_CPU0_SA_DQS_DP<4>   
                                  56       M_B_CPU0_SA_DQS_DN<4>   
                                  57       GND                     
                                  58       M_B_CPU0_SA_CB<4>       
                                  59       GND                     
                                  60       M_B_CPU0_SA_CB<5>       
                                  61       GND                     
                                  62       M_B_CPU0_ALERT_N        
                                  63       GND                     
                                  64       M_B_CPU0_SA_CS_N<0>     
                                  65       GND                     
                                  66       M_B_CPU0_SA_CA<0>       
                                  67       GND                     
                                  68       M_B_CPU0_SA_CA<2>       
                                  69       GND                     
                                  70       M_B_CPU0_SA_CA<4>       
                                  71       GND                     
                                  72       M_B_CPU0_SA_CA<6>       
                                  73       GND                     
                                  74       M_B_CPU0_SA_PAR         
                                  75       GND                     
                                  76       M_B_CPU0_SB_CA<0>       
                                  77       GND                     
                                  78       M_B_CPU0_SB_CA<2>       
                                  79       GND                     
                                  80       M_B_CPU0_SB_CA<4>       
                                  81       GND                     
                                  82       M_B_CPU0_SB_CA<6>       
                                  83       GND                     
                                  84       M_B_CPU0_SB_CS_N<0>     
                                  85       GND                     
                                  86       M_B_CPU0_SA_RSP<0>      
                                  87       M_B_CPU0_SB_RSP<0>      
                                  88       GND                     
                                  89       M_B_CPU0_SB_CB<4>       
                                  90       GND                     
                                  91       M_B_CPU0_SB_CB<5>       
                                  92       GND                     
                                  93       M_B_CPU0_SB_DQS_DP<9>   
                                  94       M_B_CPU0_SB_DQS_DN<9>   
                                  95       GND                     
                                  96       M_B_CPU0_SB_CB<0>       
                                  97       GND                     
                                  98       M_B_CPU0_SB_CB<1>       
                                  99       GND                     
                                  100      M_B_CPU0_SB_DQ<0>       
                                  101      GND                     
                                  102      M_B_CPU0_SB_DQ<1>       
                                  103      GND                     
                                  104      M_B_CPU0_SB_DQS_DP<0>   
                                  105      M_B_CPU0_SB_DQS_DN<0>   
                                  106      GND                     
                                  107      M_B_CPU0_SB_DQ<4>       
                                  108      GND                     
                                  109      M_B_CPU0_SB_DQ<5>       
                                  110      GND                     
                                  111      M_B_CPU0_SB_DQ<8>       
                                  112      GND                     
                                  113      M_B_CPU0_SB_DQ<9>       
                                  114      GND                     
                                  115      M_B_CPU0_SB_DQS_DP<1>   
                                  116      M_B_CPU0_SB_DQS_DN<1>   
                                  117      GND                     
                                  118      M_B_CPU0_SB_DQ<12>      
                                  119      GND                     
                                  120      M_B_CPU0_SB_DQ<13>      
                                  121      GND                     
                                  122      M_B_CPU0_SB_DQ<16>      
                                  123      GND                     
                                  124      M_B_CPU0_SB_DQ<17>      
                                  125      GND                     
                                  126      M_B_CPU0_SB_DQS_DP<2>   
                                  127      M_B_CPU0_SB_DQS_DN<2>   
                                  128      GND                     
                                  129      M_B_CPU0_SB_DQ<20>      
                                  130      GND                     
                                  131      M_B_CPU0_SB_DQ<21>      
                                  132      GND                     
                                  133      M_B_CPU0_SB_DQ<24>      
                                  134      GND                     
                                  135      M_B_CPU0_SB_DQ<25>      
                                  136      GND                     
                                  137      M_B_CPU0_SB_DQS_DP<3>   
                                  138      M_B_CPU0_SB_DQS_DN<3>   
                                  139      GND                     
                                  140      M_B_CPU0_SB_DQ<28>      
                                  141      GND                     
                                  142      M_B_CPU0_SB_DQ<29>      
                                  143      GND                     
                                  145      P12V_S3_AUX_CPU0_NVDIMM 
                                  146      P12V_S3_AUX_CPU0_NVDIMM 
                                  147      PWRGD_CHB_CPU0_DIMM1    
                                  148      PD_CHB_CPU0_DIMM1_SAA   
                                  151      GND                     
                                  152      M_B_CPU0_SA_DQ<2>       
                                  153      GND                     
                                  154      M_B_CPU0_SA_DQ<3>       
                                  155      GND                     
                                  156      M_B_CPU0_SA_DQS_DN<5>   
                                  157      M_B_CPU0_SA_DQS_DP<5>   
                                  158      GND                     
                                  159      M_B_CPU0_SA_DQ<6>       
                                  160      GND                     
                                  161      M_B_CPU0_SA_DQ<7>       
                                  162      GND                     
                                  163      M_B_CPU0_SA_DQ<10>      
                                  164      GND                     
                                  165      M_B_CPU0_SA_DQ<11>      
                                  166      GND                     
                                  167      M_B_CPU0_SA_DQS_DN<6>   
                                  168      M_B_CPU0_SA_DQS_DP<6>   
                                  169      GND                     
                                  170      M_B_CPU0_SA_DQ<14>      
                                  171      GND                     
                                  172      M_B_CPU0_SA_DQ<15>      
                                  173      GND                     
                                  174      M_B_CPU0_SA_DQ<18>      
                                  175      GND                     
                                  176      M_B_CPU0_SA_DQ<19>      
                                  177      GND                     
                                  178      M_B_CPU0_SA_DQS_DN<7>   
                                  179      M_B_CPU0_SA_DQS_DP<7>   
                                  180      GND                     
                                  181      M_B_CPU0_SA_DQ<22>      
                                  182      GND                     
                                  183      M_B_CPU0_SA_DQ<23>      
                                  184      GND                     
                                  185      M_B_CPU0_SA_DQ<26>      
                                  186      GND                     
                                  187      M_B_CPU0_SA_DQ<27>      
                                  188      GND                     
                                  189      M_B_CPU0_SA_DQS_DN<8>   
                                  190      M_B_CPU0_SA_DQS_DP<8>   
                                  191      GND                     
                                  192      M_B_CPU0_SA_DQ<30>      
                                  193      GND                     
                                  194      M_B_CPU0_SA_DQ<31>      
                                  195      GND                     
                                  196      M_B_CPU0_SA_CB<2>       
                                  197      GND                     
                                  198      M_B_CPU0_SA_CB<3>       
                                  199      GND                     
                                  200      M_B_CPU0_SA_DQS_DN<9>   
                                  201      M_B_CPU0_SA_DQS_DP<9>   
                                  202      GND                     
                                  203      M_B_CPU0_SA_CB<6>       
                                  204      GND                     
                                  205      M_B_CPU0_SA_CB<7>       
                                  206      GND                     
                                  207      RST_M_AB_CPU0_FPGA_N    
                                  208      GND                     
                                  209      M_B_CPU0_SA_CS_N<1>     
                                  210      GND                     
                                  211      M_B_CPU0_SA_CA<1>       
                                  212      GND                     
                                  213      M_B_CPU0_SA_CA<3>       
                                  214      GND                     
                                  215      M_B_CPU0_SA_CA<5>       
                                  216      GND                     
                                  217      M_B_CPU0_CLK_DP<0>      
                                  218      M_B_CPU0_CLK_DN<0>      
                                  219      GND                     
                                  221      M_B_CPU0_SB_CA<1>       
                                  222      GND                     
                                  223      M_B_CPU0_SB_CA<3>       
                                  224      GND                     
                                  225      M_B_CPU0_SB_CA<5>       
                                  226      GND                     
                                  227      M_B_CPU0_SB_PAR         
                                  228      GND                     
                                  229      M_B_CPU0_SB_CS_N<1>     
                                  230      GND                     
                                  233      GND                     
                                  234      M_B_CPU0_SB_CB<6>       
                                  235      GND                     
                                  236      M_B_CPU0_SB_CB<7>       
                                  237      GND                     
                                  238      M_B_CPU0_SB_DQS_DN<4>   
                                  239      M_B_CPU0_SB_DQS_DP<4>   
                                  240      GND                     
                                  241      M_B_CPU0_SB_CB<2>       
                                  242      GND                     
                                  243      M_B_CPU0_SB_CB<3>       
                                  244      GND                     
                                  245      M_B_CPU0_SB_DQ<2>       
                                  246      GND                     
                                  247      M_B_CPU0_SB_DQ<3>       
                                  248      GND                     
                                  249      M_B_CPU0_SB_DQS_DN<5>   
                                  250      M_B_CPU0_SB_DQS_DP<5>   
                                  251      GND                     
                                  252      M_B_CPU0_SB_DQ<6>       
                                  253      GND                     
                                  254      M_B_CPU0_SB_DQ<7>       
                                  255      GND                     
                                  256      M_B_CPU0_SB_DQ<10>      
                                  257      GND                     
                                  258      M_B_CPU0_SB_DQ<11>      
                                  259      GND                     
                                  260      M_B_CPU0_SB_DQS_DN<6>   
                                  261      M_B_CPU0_SB_DQS_DP<6>   
                                  262      GND                     
                                  263      M_B_CPU0_SB_DQ<14>      
                                  264      GND                     
                                  265      M_B_CPU0_SB_DQ<15>      
                                  266      GND                     
                                  267      M_B_CPU0_SB_DQ<18>      
                                  268      GND                     
                                  269      M_B_CPU0_SB_DQ<19>      
                                  270      GND                     
                                  271      M_B_CPU0_SB_DQS_DN<7>   
                                  272      M_B_CPU0_SB_DQS_DP<7>   
                                  273      GND                     
                                  274      M_B_CPU0_SB_DQ<22>      
                                  275      GND                     
                                  276      M_B_CPU0_SB_DQ<23>      
                                  277      GND                     
                                  278      M_B_CPU0_SB_DQ<26>      
                                  279      GND                     
                                  280      M_B_CPU0_SB_DQ<27>      
                                  281      GND                     
                                  282      M_B_CPU0_SB_DQS_DN<8>   
                                  283      M_B_CPU0_SB_DQS_DP<8>   
                                  284      GND                     
                                  285      M_B_CPU0_SB_DQ<30>      
                                  286      GND                     
                                  287      M_B_CPU0_SB_DQ<31>      
                                  288      GND                     
                                  G1       GND                     
                                  G2       GND                     
                                  G3       GND                     
J4               SCONN288_ADR50001P003C01-SCONNA 1        P12V_S3_AUX_CPU0_NVDIMM 
                                  3        P3V3_AUX                
                                  4        I3C_SPD_DDRABCD_CPU0_LVC1_SCL
                                  5        I3C_SPD_DDRABCD_CPU0_LVC1_SDA
                                  6        GND                     
                                  7        M_B_CPU0_SA_DQ<0>       
                                  8        GND                     
                                  9        M_B_CPU0_SA_DQ<1>       
                                  10       GND                     
                                  11       M_B_CPU0_SA_DQS_DP<0>   
                                  12       M_B_CPU0_SA_DQS_DN<0>   
                                  13       GND                     
                                  14       M_B_CPU0_SA_DQ<4>       
                                  15       GND                     
                                  16       M_B_CPU0_SA_DQ<5>       
                                  17       GND                     
                                  18       M_B_CPU0_SA_DQ<8>       
                                  19       GND                     
                                  20       M_B_CPU0_SA_DQ<9>       
                                  21       GND                     
                                  22       M_B_CPU0_SA_DQS_DP<1>   
                                  23       M_B_CPU0_SA_DQS_DN<1>   
                                  24       GND                     
                                  25       M_B_CPU0_SA_DQ<12>      
                                  26       GND                     
                                  27       M_B_CPU0_SA_DQ<13>      
                                  28       GND                     
                                  29       M_B_CPU0_SA_DQ<16>      
                                  30       GND                     
                                  31       M_B_CPU0_SA_DQ<17>      
                                  32       GND                     
                                  33       M_B_CPU0_SA_DQS_DP<2>   
                                  34       M_B_CPU0_SA_DQS_DN<2>   
                                  35       GND                     
                                  36       M_B_CPU0_SA_DQ<20>      
                                  37       GND                     
                                  38       M_B_CPU0_SA_DQ<21>      
                                  39       GND                     
                                  40       M_B_CPU0_SA_DQ<24>      
                                  41       GND                     
                                  42       M_B_CPU0_SA_DQ<25>      
                                  43       GND                     
                                  44       M_B_CPU0_SA_DQS_DP<3>   
                                  45       M_B_CPU0_SA_DQS_DN<3>   
                                  46       GND                     
                                  47       M_B_CPU0_SA_DQ<28>      
                                  48       GND                     
                                  49       M_B_CPU0_SA_DQ<29>      
                                  50       GND                     
                                  51       M_B_CPU0_SA_CB<0>       
                                  52       GND                     
                                  53       M_B_CPU0_SA_CB<1>       
                                  54       GND                     
                                  55       M_B_CPU0_SA_DQS_DP<4>   
                                  56       M_B_CPU0_SA_DQS_DN<4>   
                                  57       GND                     
                                  58       M_B_CPU0_SA_CB<4>       
                                  59       GND                     
                                  60       M_B_CPU0_SA_CB<5>       
                                  61       GND                     
                                  62       M_B_CPU0_ALERT_N        
                                  63       GND                     
                                  64       M_B_CPU0_SA_CS_N<2>     
                                  65       GND                     
                                  66       M_B_CPU0_SA_CA<0>       
                                  67       GND                     
                                  68       M_B_CPU0_SA_CA<2>       
                                  69       GND                     
                                  70       M_B_CPU0_SA_CA<4>       
                                  71       GND                     
                                  72       M_B_CPU0_SA_CA<6>       
                                  73       GND                     
                                  74       M_B_CPU0_SA_PAR         
                                  75       GND                     
                                  76       M_B_CPU0_SB_CA<0>       
                                  77       GND                     
                                  78       M_B_CPU0_SB_CA<2>       
                                  79       GND                     
                                  80       M_B_CPU0_SB_CA<4>       
                                  81       GND                     
                                  82       M_B_CPU0_SB_CA<6>       
                                  83       GND                     
                                  84       M_B_CPU0_SB_CS_N<2>     
                                  85       GND                     
                                  86       M_B_CPU0_SA_RSP<1>      
                                  87       M_B_CPU0_SB_RSP<1>      
                                  88       GND                     
                                  89       M_B_CPU0_SB_CB<4>       
                                  90       GND                     
                                  91       M_B_CPU0_SB_CB<5>       
                                  92       GND                     
                                  93       M_B_CPU0_SB_DQS_DP<9>   
                                  94       M_B_CPU0_SB_DQS_DN<9>   
                                  95       GND                     
                                  96       M_B_CPU0_SB_CB<0>       
                                  97       GND                     
                                  98       M_B_CPU0_SB_CB<1>       
                                  99       GND                     
                                  100      M_B_CPU0_SB_DQ<0>       
                                  101      GND                     
                                  102      M_B_CPU0_SB_DQ<1>       
                                  103      GND                     
                                  104      M_B_CPU0_SB_DQS_DP<0>   
                                  105      M_B_CPU0_SB_DQS_DN<0>   
                                  106      GND                     
                                  107      M_B_CPU0_SB_DQ<4>       
                                  108      GND                     
                                  109      M_B_CPU0_SB_DQ<5>       
                                  110      GND                     
                                  111      M_B_CPU0_SB_DQ<8>       
                                  112      GND                     
                                  113      M_B_CPU0_SB_DQ<9>       
                                  114      GND                     
                                  115      M_B_CPU0_SB_DQS_DP<1>   
                                  116      M_B_CPU0_SB_DQS_DN<1>   
                                  117      GND                     
                                  118      M_B_CPU0_SB_DQ<12>      
                                  119      GND                     
                                  120      M_B_CPU0_SB_DQ<13>      
                                  121      GND                     
                                  122      M_B_CPU0_SB_DQ<16>      
                                  123      GND                     
                                  124      M_B_CPU0_SB_DQ<17>      
                                  125      GND                     
                                  126      M_B_CPU0_SB_DQS_DP<2>   
                                  127      M_B_CPU0_SB_DQS_DN<2>   
                                  128      GND                     
                                  129      M_B_CPU0_SB_DQ<20>      
                                  130      GND                     
                                  131      M_B_CPU0_SB_DQ<21>      
                                  132      GND                     
                                  133      M_B_CPU0_SB_DQ<24>      
                                  134      GND                     
                                  135      M_B_CPU0_SB_DQ<25>      
                                  136      GND                     
                                  137      M_B_CPU0_SB_DQS_DP<3>   
                                  138      M_B_CPU0_SB_DQS_DN<3>   
                                  139      GND                     
                                  140      M_B_CPU0_SB_DQ<28>      
                                  141      GND                     
                                  142      M_B_CPU0_SB_DQ<29>      
                                  143      GND                     
                                  145      P12V_S3_AUX_CPU0_NVDIMM 
                                  146      P12V_S3_AUX_CPU0_NVDIMM 
                                  147      PWRGD_CHB_CPU0_DIMM2    
                                  148      PD_CHB_CPU0_DIMM2_SAA   
                                  151      GND                     
                                  152      M_B_CPU0_SA_DQ<2>       
                                  153      GND                     
                                  154      M_B_CPU0_SA_DQ<3>       
                                  155      GND                     
                                  156      M_B_CPU0_SA_DQS_DN<5>   
                                  157      M_B_CPU0_SA_DQS_DP<5>   
                                  158      GND                     
                                  159      M_B_CPU0_SA_DQ<6>       
                                  160      GND                     
                                  161      M_B_CPU0_SA_DQ<7>       
                                  162      GND                     
                                  163      M_B_CPU0_SA_DQ<10>      
                                  164      GND                     
                                  165      M_B_CPU0_SA_DQ<11>      
                                  166      GND                     
                                  167      M_B_CPU0_SA_DQS_DN<6>   
                                  168      M_B_CPU0_SA_DQS_DP<6>   
                                  169      GND                     
                                  170      M_B_CPU0_SA_DQ<14>      
                                  171      GND                     
                                  172      M_B_CPU0_SA_DQ<15>      
                                  173      GND                     
                                  174      M_B_CPU0_SA_DQ<18>      
                                  175      GND                     
                                  176      M_B_CPU0_SA_DQ<19>      
                                  177      GND                     
                                  178      M_B_CPU0_SA_DQS_DN<7>   
                                  179      M_B_CPU0_SA_DQS_DP<7>   
                                  180      GND                     
                                  181      M_B_CPU0_SA_DQ<22>      
                                  182      GND                     
                                  183      M_B_CPU0_SA_DQ<23>      
                                  184      GND                     
                                  185      M_B_CPU0_SA_DQ<26>      
                                  186      GND                     
                                  187      M_B_CPU0_SA_DQ<27>      
                                  188      GND                     
                                  189      M_B_CPU0_SA_DQS_DN<8>   
                                  190      M_B_CPU0_SA_DQS_DP<8>   
                                  191      GND                     
                                  192      M_B_CPU0_SA_DQ<30>      
                                  193      GND                     
                                  194      M_B_CPU0_SA_DQ<31>      
                                  195      GND                     
                                  196      M_B_CPU0_SA_CB<2>       
                                  197      GND                     
                                  198      M_B_CPU0_SA_CB<3>       
                                  199      GND                     
                                  200      M_B_CPU0_SA_DQS_DN<9>   
                                  201      M_B_CPU0_SA_DQS_DP<9>   
                                  202      GND                     
                                  203      M_B_CPU0_SA_CB<6>       
                                  204      GND                     
                                  205      M_B_CPU0_SA_CB<7>       
                                  206      GND                     
                                  207      RST_M_AB_CPU0_FPGA_N    
                                  208      GND                     
                                  209      M_B_CPU0_SA_CS_N<3>     
                                  210      GND                     
                                  211      M_B_CPU0_SA_CA<1>       
                                  212      GND                     
                                  213      M_B_CPU0_SA_CA<3>       
                                  214      GND                     
                                  215      M_B_CPU0_SA_CA<5>       
                                  216      GND                     
                                  217      M_B_CPU0_CLK_DP<1>      
                                  218      M_B_CPU0_CLK_DN<1>      
                                  219      GND                     
                                  221      M_B_CPU0_SB_CA<1>       
                                  222      GND                     
                                  223      M_B_CPU0_SB_CA<3>       
                                  224      GND                     
                                  225      M_B_CPU0_SB_CA<5>       
                                  226      GND                     
                                  227      M_B_CPU0_SB_PAR         
                                  228      GND                     
                                  229      M_B_CPU0_SB_CS_N<3>     
                                  230      GND                     
                                  233      GND                     
                                  234      M_B_CPU0_SB_CB<6>       
                                  235      GND                     
                                  236      M_B_CPU0_SB_CB<7>       
                                  237      GND                     
                                  238      M_B_CPU0_SB_DQS_DN<4>   
                                  239      M_B_CPU0_SB_DQS_DP<4>   
                                  240      GND                     
                                  241      M_B_CPU0_SB_CB<2>       
                                  242      GND                     
                                  243      M_B_CPU0_SB_CB<3>       
                                  244      GND                     
                                  245      M_B_CPU0_SB_DQ<2>       
                                  246      GND                     
                                  247      M_B_CPU0_SB_DQ<3>       
                                  248      GND                     
                                  249      M_B_CPU0_SB_DQS_DN<5>   
                                  250      M_B_CPU0_SB_DQS_DP<5>   
                                  251      GND                     
                                  252      M_B_CPU0_SB_DQ<6>       
                                  253      GND                     
                                  254      M_B_CPU0_SB_DQ<7>       
                                  255      GND                     
                                  256      M_B_CPU0_SB_DQ<10>      
                                  257      GND                     
                                  258      M_B_CPU0_SB_DQ<11>      
                                  259      GND                     
                                  260      M_B_CPU0_SB_DQS_DN<6>   
                                  261      M_B_CPU0_SB_DQS_DP<6>   
                                  262      GND                     
                                  263      M_B_CPU0_SB_DQ<14>      
                                  264      GND                     
                                  265      M_B_CPU0_SB_DQ<15>      
                                  266      GND                     
                                  267      M_B_CPU0_SB_DQ<18>      
                                  268      GND                     
                                  269      M_B_CPU0_SB_DQ<19>      
                                  270      GND                     
                                  271      M_B_CPU0_SB_DQS_DN<7>   
                                  272      M_B_CPU0_SB_DQS_DP<7>   
                                  273      GND                     
                                  274      M_B_CPU0_SB_DQ<22>      
                                  275      GND                     
                                  276      M_B_CPU0_SB_DQ<23>      
                                  277      GND                     
                                  278      M_B_CPU0_SB_DQ<26>      
                                  279      GND                     
                                  280      M_B_CPU0_SB_DQ<27>      
                                  281      GND                     
                                  282      M_B_CPU0_SB_DQS_DN<8>   
                                  283      M_B_CPU0_SB_DQS_DP<8>   
                                  284      GND                     
                                  285      M_B_CPU0_SB_DQ<30>      
                                  286      GND                     
                                  287      M_B_CPU0_SB_DQ<31>      
                                  288      GND                     
                                  G1       GND                     
                                  G2       GND                     
                                  G3       GND                     
J5               SCONN288_ADR50001P013C01-SCONNA 1        P12V_S3_AUX_CPU0_NVDIMM 
                                  3        P3V3_AUX                
                                  4        I3C_SPD_DDRABCD_CPU0_LVC1_SCL
                                  5        I3C_SPD_DDRABCD_CPU0_LVC1_SDA
                                  6        GND                     
                                  7        M_C_CPU0_SA_DQ<0>       
                                  8        GND                     
                                  9        M_C_CPU0_SA_DQ<1>       
                                  10       GND                     
                                  11       M_C_CPU0_SA_DQS_DP<0>   
                                  12       M_C_CPU0_SA_DQS_DN<0>   
                                  13       GND                     
                                  14       M_C_CPU0_SA_DQ<4>       
                                  15       GND                     
                                  16       M_C_CPU0_SA_DQ<5>       
                                  17       GND                     
                                  18       M_C_CPU0_SA_DQ<8>       
                                  19       GND                     
                                  20       M_C_CPU0_SA_DQ<9>       
                                  21       GND                     
                                  22       M_C_CPU0_SA_DQS_DP<1>   
                                  23       M_C_CPU0_SA_DQS_DN<1>   
                                  24       GND                     
                                  25       M_C_CPU0_SA_DQ<12>      
                                  26       GND                     
                                  27       M_C_CPU0_SA_DQ<13>      
                                  28       GND                     
                                  29       M_C_CPU0_SA_DQ<16>      
                                  30       GND                     
                                  31       M_C_CPU0_SA_DQ<17>      
                                  32       GND                     
                                  33       M_C_CPU0_SA_DQS_DP<2>   
                                  34       M_C_CPU0_SA_DQS_DN<2>   
                                  35       GND                     
                                  36       M_C_CPU0_SA_DQ<20>      
                                  37       GND                     
                                  38       M_C_CPU0_SA_DQ<21>      
                                  39       GND                     
                                  40       M_C_CPU0_SA_DQ<24>      
                                  41       GND                     
                                  42       M_C_CPU0_SA_DQ<25>      
                                  43       GND                     
                                  44       M_C_CPU0_SA_DQS_DP<3>   
                                  45       M_C_CPU0_SA_DQS_DN<3>   
                                  46       GND                     
                                  47       M_C_CPU0_SA_DQ<28>      
                                  48       GND                     
                                  49       M_C_CPU0_SA_DQ<29>      
                                  50       GND                     
                                  51       M_C_CPU0_SA_CB<0>       
                                  52       GND                     
                                  53       M_C_CPU0_SA_CB<1>       
                                  54       GND                     
                                  55       M_C_CPU0_SA_DQS_DP<4>   
                                  56       M_C_CPU0_SA_DQS_DN<4>   
                                  57       GND                     
                                  58       M_C_CPU0_SA_CB<4>       
                                  59       GND                     
                                  60       M_C_CPU0_SA_CB<5>       
                                  61       GND                     
                                  62       M_C_CPU0_ALERT_N        
                                  63       GND                     
                                  64       M_C_CPU0_SA_CS_N<0>     
                                  65       GND                     
                                  66       M_C_CPU0_SA_CA<0>       
                                  67       GND                     
                                  68       M_C_CPU0_SA_CA<2>       
                                  69       GND                     
                                  70       M_C_CPU0_SA_CA<4>       
                                  71       GND                     
                                  72       M_C_CPU0_SA_CA<6>       
                                  73       GND                     
                                  74       M_C_CPU0_SA_PAR         
                                  75       GND                     
                                  76       M_C_CPU0_SB_CA<0>       
                                  77       GND                     
                                  78       M_C_CPU0_SB_CA<2>       
                                  79       GND                     
                                  80       M_C_CPU0_SB_CA<4>       
                                  81       GND                     
                                  82       M_C_CPU0_SB_CA<6>       
                                  83       GND                     
                                  84       M_C_CPU0_SB_CS_N<0>     
                                  85       GND                     
                                  86       M_C_CPU0_SA_RSP<0>      
                                  87       M_C_CPU0_SB_RSP<0>      
                                  88       GND                     
                                  89       M_C_CPU0_SB_CB<4>       
                                  90       GND                     
                                  91       M_C_CPU0_SB_CB<5>       
                                  92       GND                     
                                  93       M_C_CPU0_SB_DQS_DP<9>   
                                  94       M_C_CPU0_SB_DQS_DN<9>   
                                  95       GND                     
                                  96       M_C_CPU0_SB_CB<0>       
                                  97       GND                     
                                  98       M_C_CPU0_SB_CB<1>       
                                  99       GND                     
                                  100      M_C_CPU0_SB_DQ<0>       
                                  101      GND                     
                                  102      M_C_CPU0_SB_DQ<1>       
                                  103      GND                     
                                  104      M_C_CPU0_SB_DQS_DP<0>   
                                  105      M_C_CPU0_SB_DQS_DN<0>   
                                  106      GND                     
                                  107      M_C_CPU0_SB_DQ<4>       
                                  108      GND                     
                                  109      M_C_CPU0_SB_DQ<5>       
                                  110      GND                     
                                  111      M_C_CPU0_SB_DQ<8>       
                                  112      GND                     
                                  113      M_C_CPU0_SB_DQ<9>       
                                  114      GND                     
                                  115      M_C_CPU0_SB_DQS_DP<1>   
                                  116      M_C_CPU0_SB_DQS_DN<1>   
                                  117      GND                     
                                  118      M_C_CPU0_SB_DQ<12>      
                                  119      GND                     
                                  120      M_C_CPU0_SB_DQ<13>      
                                  121      GND                     
                                  122      M_C_CPU0_SB_DQ<16>      
                                  123      GND                     
                                  124      M_C_CPU0_SB_DQ<17>      
                                  125      GND                     
                                  126      M_C_CPU0_SB_DQS_DP<2>   
                                  127      M_C_CPU0_SB_DQS_DN<2>   
                                  128      GND                     
                                  129      M_C_CPU0_SB_DQ<20>      
                                  130      GND                     
                                  131      M_C_CPU0_SB_DQ<21>      
                                  132      GND                     
                                  133      M_C_CPU0_SB_DQ<24>      
                                  134      GND                     
                                  135      M_C_CPU0_SB_DQ<25>      
                                  136      GND                     
                                  137      M_C_CPU0_SB_DQS_DP<3>   
                                  138      M_C_CPU0_SB_DQS_DN<3>   
                                  139      GND                     
                                  140      M_C_CPU0_SB_DQ<28>      
                                  141      GND                     
                                  142      M_C_CPU0_SB_DQ<29>      
                                  143      GND                     
                                  145      P12V_S3_AUX_CPU0_NVDIMM 
                                  146      P12V_S3_AUX_CPU0_NVDIMM 
                                  147      PWRGD_CHC_CPU0_DIMM1    
                                  148      PD_CHC_CPU0_DIMM1_SAA   
                                  151      GND                     
                                  152      M_C_CPU0_SA_DQ<2>       
                                  153      GND                     
                                  154      M_C_CPU0_SA_DQ<3>       
                                  155      GND                     
                                  156      M_C_CPU0_SA_DQS_DN<5>   
                                  157      M_C_CPU0_SA_DQS_DP<5>   
                                  158      GND                     
                                  159      M_C_CPU0_SA_DQ<6>       
                                  160      GND                     
                                  161      M_C_CPU0_SA_DQ<7>       
                                  162      GND                     
                                  163      M_C_CPU0_SA_DQ<10>      
                                  164      GND                     
                                  165      M_C_CPU0_SA_DQ<11>      
                                  166      GND                     
                                  167      M_C_CPU0_SA_DQS_DN<6>   
                                  168      M_C_CPU0_SA_DQS_DP<6>   
                                  169      GND                     
                                  170      M_C_CPU0_SA_DQ<14>      
                                  171      GND                     
                                  172      M_C_CPU0_SA_DQ<15>      
                                  173      GND                     
                                  174      M_C_CPU0_SA_DQ<18>      
                                  175      GND                     
                                  176      M_C_CPU0_SA_DQ<19>      
                                  177      GND                     
                                  178      M_C_CPU0_SA_DQS_DN<7>   
                                  179      M_C_CPU0_SA_DQS_DP<7>   
                                  180      GND                     
                                  181      M_C_CPU0_SA_DQ<22>      
                                  182      GND                     
                                  183      M_C_CPU0_SA_DQ<23>      
                                  184      GND                     
                                  185      M_C_CPU0_SA_DQ<26>      
                                  186      GND                     
                                  187      M_C_CPU0_SA_DQ<27>      
                                  188      GND                     
                                  189      M_C_CPU0_SA_DQS_DN<8>   
                                  190      M_C_CPU0_SA_DQS_DP<8>   
                                  191      GND                     
                                  192      M_C_CPU0_SA_DQ<30>      
                                  193      GND                     
                                  194      M_C_CPU0_SA_DQ<31>      
                                  195      GND                     
                                  196      M_C_CPU0_SA_CB<2>       
                                  197      GND                     
                                  198      M_C_CPU0_SA_CB<3>       
                                  199      GND                     
                                  200      M_C_CPU0_SA_DQS_DN<9>   
                                  201      M_C_CPU0_SA_DQS_DP<9>   
                                  202      GND                     
                                  203      M_C_CPU0_SA_CB<6>       
                                  204      GND                     
                                  205      M_C_CPU0_SA_CB<7>       
                                  206      GND                     
                                  207      RST_M_CD_CPU0_FPGA_N    
                                  208      GND                     
                                  209      M_C_CPU0_SA_CS_N<1>     
                                  210      GND                     
                                  211      M_C_CPU0_SA_CA<1>       
                                  212      GND                     
                                  213      M_C_CPU0_SA_CA<3>       
                                  214      GND                     
                                  215      M_C_CPU0_SA_CA<5>       
                                  216      GND                     
                                  217      M_C_CPU0_CLK_DP<0>      
                                  218      M_C_CPU0_CLK_DN<0>      
                                  219      GND                     
                                  221      M_C_CPU0_SB_CA<1>       
                                  222      GND                     
                                  223      M_C_CPU0_SB_CA<3>       
                                  224      GND                     
                                  225      M_C_CPU0_SB_CA<5>       
                                  226      GND                     
                                  227      M_C_CPU0_SB_PAR         
                                  228      GND                     
                                  229      M_C_CPU0_SB_CS_N<1>     
                                  230      GND                     
                                  233      GND                     
                                  234      M_C_CPU0_SB_CB<6>       
                                  235      GND                     
                                  236      M_C_CPU0_SB_CB<7>       
                                  237      GND                     
                                  238      M_C_CPU0_SB_DQS_DN<4>   
                                  239      M_C_CPU0_SB_DQS_DP<4>   
                                  240      GND                     
                                  241      M_C_CPU0_SB_CB<2>       
                                  242      GND                     
                                  243      M_C_CPU0_SB_CB<3>       
                                  244      GND                     
                                  245      M_C_CPU0_SB_DQ<2>       
                                  246      GND                     
                                  247      M_C_CPU0_SB_DQ<3>       
                                  248      GND                     
                                  249      M_C_CPU0_SB_DQS_DN<5>   
                                  250      M_C_CPU0_SB_DQS_DP<5>   
                                  251      GND                     
                                  252      M_C_CPU0_SB_DQ<6>       
                                  253      GND                     
                                  254      M_C_CPU0_SB_DQ<7>       
                                  255      GND                     
                                  256      M_C_CPU0_SB_DQ<10>      
                                  257      GND                     
                                  258      M_C_CPU0_SB_DQ<11>      
                                  259      GND                     
                                  260      M_C_CPU0_SB_DQS_DN<6>   
                                  261      M_C_CPU0_SB_DQS_DP<6>   
                                  262      GND                     
                                  263      M_C_CPU0_SB_DQ<14>      
                                  264      GND                     
                                  265      M_C_CPU0_SB_DQ<15>      
                                  266      GND                     
                                  267      M_C_CPU0_SB_DQ<18>      
                                  268      GND                     
                                  269      M_C_CPU0_SB_DQ<19>      
                                  270      GND                     
                                  271      M_C_CPU0_SB_DQS_DN<7>   
                                  272      M_C_CPU0_SB_DQS_DP<7>   
                                  273      GND                     
                                  274      M_C_CPU0_SB_DQ<22>      
                                  275      GND                     
                                  276      M_C_CPU0_SB_DQ<23>      
                                  277      GND                     
                                  278      M_C_CPU0_SB_DQ<26>      
                                  279      GND                     
                                  280      M_C_CPU0_SB_DQ<27>      
                                  281      GND                     
                                  282      M_C_CPU0_SB_DQS_DN<8>   
                                  283      M_C_CPU0_SB_DQS_DP<8>   
                                  284      GND                     
                                  285      M_C_CPU0_SB_DQ<30>      
                                  286      GND                     
                                  287      M_C_CPU0_SB_DQ<31>      
                                  288      GND                     
                                  G1       GND                     
                                  G2       GND                     
                                  G3       GND                     
J6               SCONN288_ADR50001P003C01-SCONNA 1        P12V_S3_AUX_CPU0_NVDIMM 
                                  3        P3V3_AUX                
                                  4        I3C_SPD_DDRABCD_CPU0_LVC1_SCL
                                  5        I3C_SPD_DDRABCD_CPU0_LVC1_SDA
                                  6        GND                     
                                  7        M_C_CPU0_SA_DQ<0>       
                                  8        GND                     
                                  9        M_C_CPU0_SA_DQ<1>       
                                  10       GND                     
                                  11       M_C_CPU0_SA_DQS_DP<0>   
                                  12       M_C_CPU0_SA_DQS_DN<0>   
                                  13       GND                     
                                  14       M_C_CPU0_SA_DQ<4>       
                                  15       GND                     
                                  16       M_C_CPU0_SA_DQ<5>       
                                  17       GND                     
                                  18       M_C_CPU0_SA_DQ<8>       
                                  19       GND                     
                                  20       M_C_CPU0_SA_DQ<9>       
                                  21       GND                     
                                  22       M_C_CPU0_SA_DQS_DP<1>   
                                  23       M_C_CPU0_SA_DQS_DN<1>   
                                  24       GND                     
                                  25       M_C_CPU0_SA_DQ<12>      
                                  26       GND                     
                                  27       M_C_CPU0_SA_DQ<13>      
                                  28       GND                     
                                  29       M_C_CPU0_SA_DQ<16>      
                                  30       GND                     
                                  31       M_C_CPU0_SA_DQ<17>      
                                  32       GND                     
                                  33       M_C_CPU0_SA_DQS_DP<2>   
                                  34       M_C_CPU0_SA_DQS_DN<2>   
                                  35       GND                     
                                  36       M_C_CPU0_SA_DQ<20>      
                                  37       GND                     
                                  38       M_C_CPU0_SA_DQ<21>      
                                  39       GND                     
                                  40       M_C_CPU0_SA_DQ<24>      
                                  41       GND                     
                                  42       M_C_CPU0_SA_DQ<25>      
                                  43       GND                     
                                  44       M_C_CPU0_SA_DQS_DP<3>   
                                  45       M_C_CPU0_SA_DQS_DN<3>   
                                  46       GND                     
                                  47       M_C_CPU0_SA_DQ<28>      
                                  48       GND                     
                                  49       M_C_CPU0_SA_DQ<29>      
                                  50       GND                     
                                  51       M_C_CPU0_SA_CB<0>       
                                  52       GND                     
                                  53       M_C_CPU0_SA_CB<1>       
                                  54       GND                     
                                  55       M_C_CPU0_SA_DQS_DP<4>   
                                  56       M_C_CPU0_SA_DQS_DN<4>   
                                  57       GND                     
                                  58       M_C_CPU0_SA_CB<4>       
                                  59       GND                     
                                  60       M_C_CPU0_SA_CB<5>       
                                  61       GND                     
                                  62       M_C_CPU0_ALERT_N        
                                  63       GND                     
                                  64       M_C_CPU0_SA_CS_N<2>     
                                  65       GND                     
                                  66       M_C_CPU0_SA_CA<0>       
                                  67       GND                     
                                  68       M_C_CPU0_SA_CA<2>       
                                  69       GND                     
                                  70       M_C_CPU0_SA_CA<4>       
                                  71       GND                     
                                  72       M_C_CPU0_SA_CA<6>       
                                  73       GND                     
                                  74       M_C_CPU0_SA_PAR         
                                  75       GND                     
                                  76       M_C_CPU0_SB_CA<0>       
                                  77       GND                     
                                  78       M_C_CPU0_SB_CA<2>       
                                  79       GND                     
                                  80       M_C_CPU0_SB_CA<4>       
                                  81       GND                     
                                  82       M_C_CPU0_SB_CA<6>       
                                  83       GND                     
                                  84       M_C_CPU0_SB_CS_N<2>     
                                  85       GND                     
                                  86       M_C_CPU0_SA_RSP<1>      
                                  87       M_C_CPU0_SB_RSP<1>      
                                  88       GND                     
                                  89       M_C_CPU0_SB_CB<4>       
                                  90       GND                     
                                  91       M_C_CPU0_SB_CB<5>       
                                  92       GND                     
                                  93       M_C_CPU0_SB_DQS_DP<9>   
                                  94       M_C_CPU0_SB_DQS_DN<9>   
                                  95       GND                     
                                  96       M_C_CPU0_SB_CB<0>       
                                  97       GND                     
                                  98       M_C_CPU0_SB_CB<1>       
                                  99       GND                     
                                  100      M_C_CPU0_SB_DQ<0>       
                                  101      GND                     
                                  102      M_C_CPU0_SB_DQ<1>       
                                  103      GND                     
                                  104      M_C_CPU0_SB_DQS_DP<0>   
                                  105      M_C_CPU0_SB_DQS_DN<0>   
                                  106      GND                     
                                  107      M_C_CPU0_SB_DQ<4>       
                                  108      GND                     
                                  109      M_C_CPU0_SB_DQ<5>       
                                  110      GND                     
                                  111      M_C_CPU0_SB_DQ<8>       
                                  112      GND                     
                                  113      M_C_CPU0_SB_DQ<9>       
                                  114      GND                     
                                  115      M_C_CPU0_SB_DQS_DP<1>   
                                  116      M_C_CPU0_SB_DQS_DN<1>   
                                  117      GND                     
                                  118      M_C_CPU0_SB_DQ<12>      
                                  119      GND                     
                                  120      M_C_CPU0_SB_DQ<13>      
                                  121      GND                     
                                  122      M_C_CPU0_SB_DQ<16>      
                                  123      GND                     
                                  124      M_C_CPU0_SB_DQ<17>      
                                  125      GND                     
                                  126      M_C_CPU0_SB_DQS_DP<2>   
                                  127      M_C_CPU0_SB_DQS_DN<2>   
                                  128      GND                     
                                  129      M_C_CPU0_SB_DQ<20>      
                                  130      GND                     
                                  131      M_C_CPU0_SB_DQ<21>      
                                  132      GND                     
                                  133      M_C_CPU0_SB_DQ<24>      
                                  134      GND                     
                                  135      M_C_CPU0_SB_DQ<25>      
                                  136      GND                     
                                  137      M_C_CPU0_SB_DQS_DP<3>   
                                  138      M_C_CPU0_SB_DQS_DN<3>   
                                  139      GND                     
                                  140      M_C_CPU0_SB_DQ<28>      
                                  141      GND                     
                                  142      M_C_CPU0_SB_DQ<29>      
                                  143      GND                     
                                  145      P12V_S3_AUX_CPU0_NVDIMM 
                                  146      P12V_S3_AUX_CPU0_NVDIMM 
                                  147      PWRGD_CHC_CPU0_DIMM2    
                                  148      PD_CHC_CPU0_DIMM2_SAA   
                                  151      GND                     
                                  152      M_C_CPU0_SA_DQ<2>       
                                  153      GND                     
                                  154      M_C_CPU0_SA_DQ<3>       
                                  155      GND                     
                                  156      M_C_CPU0_SA_DQS_DN<5>   
                                  157      M_C_CPU0_SA_DQS_DP<5>   
                                  158      GND                     
                                  159      M_C_CPU0_SA_DQ<6>       
                                  160      GND                     
                                  161      M_C_CPU0_SA_DQ<7>       
                                  162      GND                     
                                  163      M_C_CPU0_SA_DQ<10>      
                                  164      GND                     
                                  165      M_C_CPU0_SA_DQ<11>      
                                  166      GND                     
                                  167      M_C_CPU0_SA_DQS_DN<6>   
                                  168      M_C_CPU0_SA_DQS_DP<6>   
                                  169      GND                     
                                  170      M_C_CPU0_SA_DQ<14>      
                                  171      GND                     
                                  172      M_C_CPU0_SA_DQ<15>      
                                  173      GND                     
                                  174      M_C_CPU0_SA_DQ<18>      
                                  175      GND                     
                                  176      M_C_CPU0_SA_DQ<19>      
                                  177      GND                     
                                  178      M_C_CPU0_SA_DQS_DN<7>   
                                  179      M_C_CPU0_SA_DQS_DP<7>   
                                  180      GND                     
                                  181      M_C_CPU0_SA_DQ<22>      
                                  182      GND                     
                                  183      M_C_CPU0_SA_DQ<23>      
                                  184      GND                     
                                  185      M_C_CPU0_SA_DQ<26>      
                                  186      GND                     
                                  187      M_C_CPU0_SA_DQ<27>      
                                  188      GND                     
                                  189      M_C_CPU0_SA_DQS_DN<8>   
                                  190      M_C_CPU0_SA_DQS_DP<8>   
                                  191      GND                     
                                  192      M_C_CPU0_SA_DQ<30>      
                                  193      GND                     
                                  194      M_C_CPU0_SA_DQ<31>      
                                  195      GND                     
                                  196      M_C_CPU0_SA_CB<2>       
                                  197      GND                     
                                  198      M_C_CPU0_SA_CB<3>       
                                  199      GND                     
                                  200      M_C_CPU0_SA_DQS_DN<9>   
                                  201      M_C_CPU0_SA_DQS_DP<9>   
                                  202      GND                     
                                  203      M_C_CPU0_SA_CB<6>       
                                  204      GND                     
                                  205      M_C_CPU0_SA_CB<7>       
                                  206      GND                     
                                  207      RST_M_CD_CPU0_FPGA_N    
                                  208      GND                     
                                  209      M_C_CPU0_SA_CS_N<3>     
                                  210      GND                     
                                  211      M_C_CPU0_SA_CA<1>       
                                  212      GND                     
                                  213      M_C_CPU0_SA_CA<3>       
                                  214      GND                     
                                  215      M_C_CPU0_SA_CA<5>       
                                  216      GND                     
                                  217      M_C_CPU0_CLK_DP<1>      
                                  218      M_C_CPU0_CLK_DN<1>      
                                  219      GND                     
                                  221      M_C_CPU0_SB_CA<1>       
                                  222      GND                     
                                  223      M_C_CPU0_SB_CA<3>       
                                  224      GND                     
                                  225      M_C_CPU0_SB_CA<5>       
                                  226      GND                     
                                  227      M_C_CPU0_SB_PAR         
                                  228      GND                     
                                  229      M_C_CPU0_SB_CS_N<3>     
                                  230      GND                     
                                  233      GND                     
                                  234      M_C_CPU0_SB_CB<6>       
                                  235      GND                     
                                  236      M_C_CPU0_SB_CB<7>       
                                  237      GND                     
                                  238      M_C_CPU0_SB_DQS_DN<4>   
                                  239      M_C_CPU0_SB_DQS_DP<4>   
                                  240      GND                     
                                  241      M_C_CPU0_SB_CB<2>       
                                  242      GND                     
                                  243      M_C_CPU0_SB_CB<3>       
                                  244      GND                     
                                  245      M_C_CPU0_SB_DQ<2>       
                                  246      GND                     
                                  247      M_C_CPU0_SB_DQ<3>       
                                  248      GND                     
                                  249      M_C_CPU0_SB_DQS_DN<5>   
                                  250      M_C_CPU0_SB_DQS_DP<5>   
                                  251      GND                     
                                  252      M_C_CPU0_SB_DQ<6>       
                                  253      GND                     
                                  254      M_C_CPU0_SB_DQ<7>       
                                  255      GND                     
                                  256      M_C_CPU0_SB_DQ<10>      
                                  257      GND                     
                                  258      M_C_CPU0_SB_DQ<11>      
                                  259      GND                     
                                  260      M_C_CPU0_SB_DQS_DN<6>   
                                  261      M_C_CPU0_SB_DQS_DP<6>   
                                  262      GND                     
                                  263      M_C_CPU0_SB_DQ<14>      
                                  264      GND                     
                                  265      M_C_CPU0_SB_DQ<15>      
                                  266      GND                     
                                  267      M_C_CPU0_SB_DQ<18>      
                                  268      GND                     
                                  269      M_C_CPU0_SB_DQ<19>      
                                  270      GND                     
                                  271      M_C_CPU0_SB_DQS_DN<7>   
                                  272      M_C_CPU0_SB_DQS_DP<7>   
                                  273      GND                     
                                  274      M_C_CPU0_SB_DQ<22>      
                                  275      GND                     
                                  276      M_C_CPU0_SB_DQ<23>      
                                  277      GND                     
                                  278      M_C_CPU0_SB_DQ<26>      
                                  279      GND                     
                                  280      M_C_CPU0_SB_DQ<27>      
                                  281      GND                     
                                  282      M_C_CPU0_SB_DQS_DN<8>   
                                  283      M_C_CPU0_SB_DQS_DP<8>   
                                  284      GND                     
                                  285      M_C_CPU0_SB_DQ<30>      
                                  286      GND                     
                                  287      M_C_CPU0_SB_DQ<31>      
                                  288      GND                     
                                  G1       GND                     
                                  G2       GND                     
                                  G3       GND                     
J7               SCONN288_ADR50001P013C01-SCONNA 1        P12V_S3_AUX_CPU0_NVDIMM 
                                  3        P3V3_AUX                
                                  4        I3C_SPD_DDRABCD_CPU0_LVC1_SCL
                                  5        I3C_SPD_DDRABCD_CPU0_LVC1_SDA
                                  6        GND                     
                                  7        M_D_CPU0_SA_DQ<0>       
                                  8        GND                     
                                  9        M_D_CPU0_SA_DQ<1>       
                                  10       GND                     
                                  11       M_D_CPU0_SA_DQS_DP<0>   
                                  12       M_D_CPU0_SA_DQS_DN<0>   
                                  13       GND                     
                                  14       M_D_CPU0_SA_DQ<4>       
                                  15       GND                     
                                  16       M_D_CPU0_SA_DQ<5>       
                                  17       GND                     
                                  18       M_D_CPU0_SA_DQ<8>       
                                  19       GND                     
                                  20       M_D_CPU0_SA_DQ<9>       
                                  21       GND                     
                                  22       M_D_CPU0_SA_DQS_DP<1>   
                                  23       M_D_CPU0_SA_DQS_DN<1>   
                                  24       GND                     
                                  25       M_D_CPU0_SA_DQ<12>      
                                  26       GND                     
                                  27       M_D_CPU0_SA_DQ<13>      
                                  28       GND                     
                                  29       M_D_CPU0_SA_DQ<16>      
                                  30       GND                     
                                  31       M_D_CPU0_SA_DQ<17>      
                                  32       GND                     
                                  33       M_D_CPU0_SA_DQS_DP<2>   
                                  34       M_D_CPU0_SA_DQS_DN<2>   
                                  35       GND                     
                                  36       M_D_CPU0_SA_DQ<20>      
                                  37       GND                     
                                  38       M_D_CPU0_SA_DQ<21>      
                                  39       GND                     
                                  40       M_D_CPU0_SA_DQ<24>      
                                  41       GND                     
                                  42       M_D_CPU0_SA_DQ<25>      
                                  43       GND                     
                                  44       M_D_CPU0_SA_DQS_DP<3>   
                                  45       M_D_CPU0_SA_DQS_DN<3>   
                                  46       GND                     
                                  47       M_D_CPU0_SA_DQ<28>      
                                  48       GND                     
                                  49       M_D_CPU0_SA_DQ<29>      
                                  50       GND                     
                                  51       M_D_CPU0_SA_CB<0>       
                                  52       GND                     
                                  53       M_D_CPU0_SA_CB<1>       
                                  54       GND                     
                                  55       M_D_CPU0_SA_DQS_DP<4>   
                                  56       M_D_CPU0_SA_DQS_DN<4>   
                                  57       GND                     
                                  58       M_D_CPU0_SA_CB<4>       
                                  59       GND                     
                                  60       M_D_CPU0_SA_CB<5>       
                                  61       GND                     
                                  62       M_D_CPU0_ALERT_N        
                                  63       GND                     
                                  64       M_D_CPU0_SA_CS_N<0>     
                                  65       GND                     
                                  66       M_D_CPU0_SA_CA<0>       
                                  67       GND                     
                                  68       M_D_CPU0_SA_CA<2>       
                                  69       GND                     
                                  70       M_D_CPU0_SA_CA<4>       
                                  71       GND                     
                                  72       M_D_CPU0_SA_CA<6>       
                                  73       GND                     
                                  74       M_D_CPU0_SA_PAR         
                                  75       GND                     
                                  76       M_D_CPU0_SB_CA<0>       
                                  77       GND                     
                                  78       M_D_CPU0_SB_CA<2>       
                                  79       GND                     
                                  80       M_D_CPU0_SB_CA<4>       
                                  81       GND                     
                                  82       M_D_CPU0_SB_CA<6>       
                                  83       GND                     
                                  84       M_D_CPU0_SB_CS_N<0>     
                                  85       GND                     
                                  86       M_D_CPU0_SA_RSP<0>      
                                  87       M_D_CPU0_SB_RSP<0>      
                                  88       GND                     
                                  89       M_D_CPU0_SB_CB<4>       
                                  90       GND                     
                                  91       M_D_CPU0_SB_CB<5>       
                                  92       GND                     
                                  93       M_D_CPU0_SB_DQS_DP<9>   
                                  94       M_D_CPU0_SB_DQS_DN<9>   
                                  95       GND                     
                                  96       M_D_CPU0_SB_CB<0>       
                                  97       GND                     
                                  98       M_D_CPU0_SB_CB<1>       
                                  99       GND                     
                                  100      M_D_CPU0_SB_DQ<0>       
                                  101      GND                     
                                  102      M_D_CPU0_SB_DQ<1>       
                                  103      GND                     
                                  104      M_D_CPU0_SB_DQS_DP<0>   
                                  105      M_D_CPU0_SB_DQS_DN<0>   
                                  106      GND                     
                                  107      M_D_CPU0_SB_DQ<4>       
                                  108      GND                     
                                  109      M_D_CPU0_SB_DQ<5>       
                                  110      GND                     
                                  111      M_D_CPU0_SB_DQ<8>       
                                  112      GND                     
                                  113      M_D_CPU0_SB_DQ<9>       
                                  114      GND                     
                                  115      M_D_CPU0_SB_DQS_DP<1>   
                                  116      M_D_CPU0_SB_DQS_DN<1>   
                                  117      GND                     
                                  118      M_D_CPU0_SB_DQ<12>      
                                  119      GND                     
                                  120      M_D_CPU0_SB_DQ<13>      
                                  121      GND                     
                                  122      M_D_CPU0_SB_DQ<16>      
                                  123      GND                     
                                  124      M_D_CPU0_SB_DQ<17>      
                                  125      GND                     
                                  126      M_D_CPU0_SB_DQS_DP<2>   
                                  127      M_D_CPU0_SB_DQS_DN<2>   
                                  128      GND                     
                                  129      M_D_CPU0_SB_DQ<20>      
                                  130      GND                     
                                  131      M_D_CPU0_SB_DQ<21>      
                                  132      GND                     
                                  133      M_D_CPU0_SB_DQ<24>      
                                  134      GND                     
                                  135      M_D_CPU0_SB_DQ<25>      
                                  136      GND                     
                                  137      M_D_CPU0_SB_DQS_DP<3>   
                                  138      M_D_CPU0_SB_DQS_DN<3>   
                                  139      GND                     
                                  140      M_D_CPU0_SB_DQ<28>      
                                  141      GND                     
                                  142      M_D_CPU0_SB_DQ<29>      
                                  143      GND                     
                                  145      P12V_S3_AUX_CPU0_NVDIMM 
                                  146      P12V_S3_AUX_CPU0_NVDIMM 
                                  147      PWRGD_CHD_CPU0_DIMM1    
                                  148      PD_CHD_CPU0_DIMM1_SAA   
                                  151      GND                     
                                  152      M_D_CPU0_SA_DQ<2>       
                                  153      GND                     
                                  154      M_D_CPU0_SA_DQ<3>       
                                  155      GND                     
                                  156      M_D_CPU0_SA_DQS_DN<5>   
                                  157      M_D_CPU0_SA_DQS_DP<5>   
                                  158      GND                     
                                  159      M_D_CPU0_SA_DQ<6>       
                                  160      GND                     
                                  161      M_D_CPU0_SA_DQ<7>       
                                  162      GND                     
                                  163      M_D_CPU0_SA_DQ<10>      
                                  164      GND                     
                                  165      M_D_CPU0_SA_DQ<11>      
                                  166      GND                     
                                  167      M_D_CPU0_SA_DQS_DN<6>   
                                  168      M_D_CPU0_SA_DQS_DP<6>   
                                  169      GND                     
                                  170      M_D_CPU0_SA_DQ<14>      
                                  171      GND                     
                                  172      M_D_CPU0_SA_DQ<15>      
                                  173      GND                     
                                  174      M_D_CPU0_SA_DQ<18>      
                                  175      GND                     
                                  176      M_D_CPU0_SA_DQ<19>      
                                  177      GND                     
                                  178      M_D_CPU0_SA_DQS_DN<7>   
                                  179      M_D_CPU0_SA_DQS_DP<7>   
                                  180      GND                     
                                  181      M_D_CPU0_SA_DQ<22>      
                                  182      GND                     
                                  183      M_D_CPU0_SA_DQ<23>      
                                  184      GND                     
                                  185      M_D_CPU0_SA_DQ<26>      
                                  186      GND                     
                                  187      M_D_CPU0_SA_DQ<27>      
                                  188      GND                     
                                  189      M_D_CPU0_SA_DQS_DN<8>   
                                  190      M_D_CPU0_SA_DQS_DP<8>   
                                  191      GND                     
                                  192      M_D_CPU0_SA_DQ<30>      
                                  193      GND                     
                                  194      M_D_CPU0_SA_DQ<31>      
                                  195      GND                     
                                  196      M_D_CPU0_SA_CB<2>       
                                  197      GND                     
                                  198      M_D_CPU0_SA_CB<3>       
                                  199      GND                     
                                  200      M_D_CPU0_SA_DQS_DN<9>   
                                  201      M_D_CPU0_SA_DQS_DP<9>   
                                  202      GND                     
                                  203      M_D_CPU0_SA_CB<6>       
                                  204      GND                     
                                  205      M_D_CPU0_SA_CB<7>       
                                  206      GND                     
                                  207      RST_M_CD_CPU0_FPGA_N    
                                  208      GND                     
                                  209      M_D_CPU0_SA_CS_N<1>     
                                  210      GND                     
                                  211      M_D_CPU0_SA_CA<1>       
                                  212      GND                     
                                  213      M_D_CPU0_SA_CA<3>       
                                  214      GND                     
                                  215      M_D_CPU0_SA_CA<5>       
                                  216      GND                     
                                  217      M_D_CPU0_CLK_DP<0>      
                                  218      M_D_CPU0_CLK_DN<0>      
                                  219      GND                     
                                  221      M_D_CPU0_SB_CA<1>       
                                  222      GND                     
                                  223      M_D_CPU0_SB_CA<3>       
                                  224      GND                     
                                  225      M_D_CPU0_SB_CA<5>       
                                  226      GND                     
                                  227      M_D_CPU0_SB_PAR         
                                  228      GND                     
                                  229      M_D_CPU0_SB_CS_N<1>     
                                  230      GND                     
                                  233      GND                     
                                  234      M_D_CPU0_SB_CB<6>       
                                  235      GND                     
                                  236      M_D_CPU0_SB_CB<7>       
                                  237      GND                     
                                  238      M_D_CPU0_SB_DQS_DN<4>   
                                  239      M_D_CPU0_SB_DQS_DP<4>   
                                  240      GND                     
                                  241      M_D_CPU0_SB_CB<2>       
                                  242      GND                     
                                  243      M_D_CPU0_SB_CB<3>       
                                  244      GND                     
                                  245      M_D_CPU0_SB_DQ<2>       
                                  246      GND                     
                                  247      M_D_CPU0_SB_DQ<3>       
                                  248      GND                     
                                  249      M_D_CPU0_SB_DQS_DN<5>   
                                  250      M_D_CPU0_SB_DQS_DP<5>   
                                  251      GND                     
                                  252      M_D_CPU0_SB_DQ<6>       
                                  253      GND                     
                                  254      M_D_CPU0_SB_DQ<7>       
                                  255      GND                     
                                  256      M_D_CPU0_SB_DQ<10>      
                                  257      GND                     
                                  258      M_D_CPU0_SB_DQ<11>      
                                  259      GND                     
                                  260      M_D_CPU0_SB_DQS_DN<6>   
                                  261      M_D_CPU0_SB_DQS_DP<6>   
                                  262      GND                     
                                  263      M_D_CPU0_SB_DQ<14>      
                                  264      GND                     
                                  265      M_D_CPU0_SB_DQ<15>      
                                  266      GND                     
                                  267      M_D_CPU0_SB_DQ<18>      
                                  268      GND                     
                                  269      M_D_CPU0_SB_DQ<19>      
                                  270      GND                     
                                  271      M_D_CPU0_SB_DQS_DN<7>   
                                  272      M_D_CPU0_SB_DQS_DP<7>   
                                  273      GND                     
                                  274      M_D_CPU0_SB_DQ<22>      
                                  275      GND                     
                                  276      M_D_CPU0_SB_DQ<23>      
                                  277      GND                     
                                  278      M_D_CPU0_SB_DQ<26>      
                                  279      GND                     
                                  280      M_D_CPU0_SB_DQ<27>      
                                  281      GND                     
                                  282      M_D_CPU0_SB_DQS_DN<8>   
                                  283      M_D_CPU0_SB_DQS_DP<8>   
                                  284      GND                     
                                  285      M_D_CPU0_SB_DQ<30>      
                                  286      GND                     
                                  287      M_D_CPU0_SB_DQ<31>      
                                  288      GND                     
                                  G1       GND                     
                                  G2       GND                     
                                  G3       GND                     
J8               SCONN288_ADR50001P003C01-SCONNA 1        P12V_S3_AUX_CPU0_NVDIMM 
                                  3        P3V3_AUX                
                                  4        I3C_SPD_DDRABCD_CPU0_LVC1_SCL
                                  5        I3C_SPD_DDRABCD_CPU0_LVC1_SDA
                                  6        GND                     
                                  7        M_D_CPU0_SA_DQ<0>       
                                  8        GND                     
                                  9        M_D_CPU0_SA_DQ<1>       
                                  10       GND                     
                                  11       M_D_CPU0_SA_DQS_DP<0>   
                                  12       M_D_CPU0_SA_DQS_DN<0>   
                                  13       GND                     
                                  14       M_D_CPU0_SA_DQ<4>       
                                  15       GND                     
                                  16       M_D_CPU0_SA_DQ<5>       
                                  17       GND                     
                                  18       M_D_CPU0_SA_DQ<8>       
                                  19       GND                     
                                  20       M_D_CPU0_SA_DQ<9>       
                                  21       GND                     
                                  22       M_D_CPU0_SA_DQS_DP<1>   
                                  23       M_D_CPU0_SA_DQS_DN<1>   
                                  24       GND                     
                                  25       M_D_CPU0_SA_DQ<12>      
                                  26       GND                     
                                  27       M_D_CPU0_SA_DQ<13>      
                                  28       GND                     
                                  29       M_D_CPU0_SA_DQ<16>      
                                  30       GND                     
                                  31       M_D_CPU0_SA_DQ<17>      
                                  32       GND                     
                                  33       M_D_CPU0_SA_DQS_DP<2>   
                                  34       M_D_CPU0_SA_DQS_DN<2>   
                                  35       GND                     
                                  36       M_D_CPU0_SA_DQ<20>      
                                  37       GND                     
                                  38       M_D_CPU0_SA_DQ<21>      
                                  39       GND                     
                                  40       M_D_CPU0_SA_DQ<24>      
                                  41       GND                     
                                  42       M_D_CPU0_SA_DQ<25>      
                                  43       GND                     
                                  44       M_D_CPU0_SA_DQS_DP<3>   
                                  45       M_D_CPU0_SA_DQS_DN<3>   
                                  46       GND                     
                                  47       M_D_CPU0_SA_DQ<28>      
                                  48       GND                     
                                  49       M_D_CPU0_SA_DQ<29>      
                                  50       GND                     
                                  51       M_D_CPU0_SA_CB<0>       
                                  52       GND                     
                                  53       M_D_CPU0_SA_CB<1>       
                                  54       GND                     
                                  55       M_D_CPU0_SA_DQS_DP<4>   
                                  56       M_D_CPU0_SA_DQS_DN<4>   
                                  57       GND                     
                                  58       M_D_CPU0_SA_CB<4>       
                                  59       GND                     
                                  60       M_D_CPU0_SA_CB<5>       
                                  61       GND                     
                                  62       M_D_CPU0_ALERT_N        
                                  63       GND                     
                                  64       M_D_CPU0_SA_CS_N<2>     
                                  65       GND                     
                                  66       M_D_CPU0_SA_CA<0>       
                                  67       GND                     
                                  68       M_D_CPU0_SA_CA<2>       
                                  69       GND                     
                                  70       M_D_CPU0_SA_CA<4>       
                                  71       GND                     
                                  72       M_D_CPU0_SA_CA<6>       
                                  73       GND                     
                                  74       M_D_CPU0_SA_PAR         
                                  75       GND                     
                                  76       M_D_CPU0_SB_CA<0>       
                                  77       GND                     
                                  78       M_D_CPU0_SB_CA<2>       
                                  79       GND                     
                                  80       M_D_CPU0_SB_CA<4>       
                                  81       GND                     
                                  82       M_D_CPU0_SB_CA<6>       
                                  83       GND                     
                                  84       M_D_CPU0_SB_CS_N<2>     
                                  85       GND                     
                                  86       M_D_CPU0_SA_RSP<1>      
                                  87       M_D_CPU0_SB_RSP<1>      
                                  88       GND                     
                                  89       M_D_CPU0_SB_CB<4>       
                                  90       GND                     
                                  91       M_D_CPU0_SB_CB<5>       
                                  92       GND                     
                                  93       M_D_CPU0_SB_DQS_DP<9>   
                                  94       M_D_CPU0_SB_DQS_DN<9>   
                                  95       GND                     
                                  96       M_D_CPU0_SB_CB<0>       
                                  97       GND                     
                                  98       M_D_CPU0_SB_CB<1>       
                                  99       GND                     
                                  100      M_D_CPU0_SB_DQ<0>       
                                  101      GND                     
                                  102      M_D_CPU0_SB_DQ<1>       
                                  103      GND                     
                                  104      M_D_CPU0_SB_DQS_DP<0>   
                                  105      M_D_CPU0_SB_DQS_DN<0>   
                                  106      GND                     
                                  107      M_D_CPU0_SB_DQ<4>       
                                  108      GND                     
                                  109      M_D_CPU0_SB_DQ<5>       
                                  110      GND                     
                                  111      M_D_CPU0_SB_DQ<8>       
                                  112      GND                     
                                  113      M_D_CPU0_SB_DQ<9>       
                                  114      GND                     
                                  115      M_D_CPU0_SB_DQS_DP<1>   
                                  116      M_D_CPU0_SB_DQS_DN<1>   
                                  117      GND                     
                                  118      M_D_CPU0_SB_DQ<12>      
                                  119      GND                     
                                  120      M_D_CPU0_SB_DQ<13>      
                                  121      GND                     
                                  122      M_D_CPU0_SB_DQ<16>      
                                  123      GND                     
                                  124      M_D_CPU0_SB_DQ<17>      
                                  125      GND                     
                                  126      M_D_CPU0_SB_DQS_DP<2>   
                                  127      M_D_CPU0_SB_DQS_DN<2>   
                                  128      GND                     
                                  129      M_D_CPU0_SB_DQ<20>      
                                  130      GND                     
                                  131      M_D_CPU0_SB_DQ<21>      
                                  132      GND                     
                                  133      M_D_CPU0_SB_DQ<24>      
                                  134      GND                     
                                  135      M_D_CPU0_SB_DQ<25>      
                                  136      GND                     
                                  137      M_D_CPU0_SB_DQS_DP<3>   
                                  138      M_D_CPU0_SB_DQS_DN<3>   
                                  139      GND                     
                                  140      M_D_CPU0_SB_DQ<28>      
                                  141      GND                     
                                  142      M_D_CPU0_SB_DQ<29>      
                                  143      GND                     
                                  145      P12V_S3_AUX_CPU0_NVDIMM 
                                  146      P12V_S3_AUX_CPU0_NVDIMM 
                                  147      PWRGD_CHD_CPU0_DIMM2    
                                  148      PD_CHD_CPU0_DIMM2_SAA   
                                  151      GND                     
                                  152      M_D_CPU0_SA_DQ<2>       
                                  153      GND                     
                                  154      M_D_CPU0_SA_DQ<3>       
                                  155      GND                     
                                  156      M_D_CPU0_SA_DQS_DN<5>   
                                  157      M_D_CPU0_SA_DQS_DP<5>   
                                  158      GND                     
                                  159      M_D_CPU0_SA_DQ<6>       
                                  160      GND                     
                                  161      M_D_CPU0_SA_DQ<7>       
                                  162      GND                     
                                  163      M_D_CPU0_SA_DQ<10>      
                                  164      GND                     
                                  165      M_D_CPU0_SA_DQ<11>      
                                  166      GND                     
                                  167      M_D_CPU0_SA_DQS_DN<6>   
                                  168      M_D_CPU0_SA_DQS_DP<6>   
                                  169      GND                     
                                  170      M_D_CPU0_SA_DQ<14>      
                                  171      GND                     
                                  172      M_D_CPU0_SA_DQ<15>      
                                  173      GND                     
                                  174      M_D_CPU0_SA_DQ<18>      
                                  175      GND                     
                                  176      M_D_CPU0_SA_DQ<19>      
                                  177      GND                     
                                  178      M_D_CPU0_SA_DQS_DN<7>   
                                  179      M_D_CPU0_SA_DQS_DP<7>   
                                  180      GND                     
                                  181      M_D_CPU0_SA_DQ<22>      
                                  182      GND                     
                                  183      M_D_CPU0_SA_DQ<23>      
                                  184      GND                     
                                  185      M_D_CPU0_SA_DQ<26>      
                                  186      GND                     
                                  187      M_D_CPU0_SA_DQ<27>      
                                  188      GND                     
                                  189      M_D_CPU0_SA_DQS_DN<8>   
                                  190      M_D_CPU0_SA_DQS_DP<8>   
                                  191      GND                     
                                  192      M_D_CPU0_SA_DQ<30>      
                                  193      GND                     
                                  194      M_D_CPU0_SA_DQ<31>      
                                  195      GND                     
                                  196      M_D_CPU0_SA_CB<2>       
                                  197      GND                     
                                  198      M_D_CPU0_SA_CB<3>       
                                  199      GND                     
                                  200      M_D_CPU0_SA_DQS_DN<9>   
                                  201      M_D_CPU0_SA_DQS_DP<9>   
                                  202      GND                     
                                  203      M_D_CPU0_SA_CB<6>       
                                  204      GND                     
                                  205      M_D_CPU0_SA_CB<7>       
                                  206      GND                     
                                  207      RST_M_CD_CPU0_FPGA_N    
                                  208      GND                     
                                  209      M_D_CPU0_SA_CS_N<3>     
                                  210      GND                     
                                  211      M_D_CPU0_SA_CA<1>       
                                  212      GND                     
                                  213      M_D_CPU0_SA_CA<3>       
                                  214      GND                     
                                  215      M_D_CPU0_SA_CA<5>       
                                  216      GND                     
                                  217      M_D_CPU0_CLK_DP<1>      
                                  218      M_D_CPU0_CLK_DN<1>      
                                  219      GND                     
                                  221      M_D_CPU0_SB_CA<1>       
                                  222      GND                     
                                  223      M_D_CPU0_SB_CA<3>       
                                  224      GND                     
                                  225      M_D_CPU0_SB_CA<5>       
                                  226      GND                     
                                  227      M_D_CPU0_SB_PAR         
                                  228      GND                     
                                  229      M_D_CPU0_SB_CS_N<3>     
                                  230      GND                     
                                  233      GND                     
                                  234      M_D_CPU0_SB_CB<6>       
                                  235      GND                     
                                  236      M_D_CPU0_SB_CB<7>       
                                  237      GND                     
                                  238      M_D_CPU0_SB_DQS_DN<4>   
                                  239      M_D_CPU0_SB_DQS_DP<4>   
                                  240      GND                     
                                  241      M_D_CPU0_SB_CB<2>       
                                  242      GND                     
                                  243      M_D_CPU0_SB_CB<3>       
                                  244      GND                     
                                  245      M_D_CPU0_SB_DQ<2>       
                                  246      GND                     
                                  247      M_D_CPU0_SB_DQ<3>       
                                  248      GND                     
                                  249      M_D_CPU0_SB_DQS_DN<5>   
                                  250      M_D_CPU0_SB_DQS_DP<5>   
                                  251      GND                     
                                  252      M_D_CPU0_SB_DQ<6>       
                                  253      GND                     
                                  254      M_D_CPU0_SB_DQ<7>       
                                  255      GND                     
                                  256      M_D_CPU0_SB_DQ<10>      
                                  257      GND                     
                                  258      M_D_CPU0_SB_DQ<11>      
                                  259      GND                     
                                  260      M_D_CPU0_SB_DQS_DN<6>   
                                  261      M_D_CPU0_SB_DQS_DP<6>   
                                  262      GND                     
                                  263      M_D_CPU0_SB_DQ<14>      
                                  264      GND                     
                                  265      M_D_CPU0_SB_DQ<15>      
                                  266      GND                     
                                  267      M_D_CPU0_SB_DQ<18>      
                                  268      GND                     
                                  269      M_D_CPU0_SB_DQ<19>      
                                  270      GND                     
                                  271      M_D_CPU0_SB_DQS_DN<7>   
                                  272      M_D_CPU0_SB_DQS_DP<7>   
                                  273      GND                     
                                  274      M_D_CPU0_SB_DQ<22>      
                                  275      GND                     
                                  276      M_D_CPU0_SB_DQ<23>      
                                  277      GND                     
                                  278      M_D_CPU0_SB_DQ<26>      
                                  279      GND                     
                                  280      M_D_CPU0_SB_DQ<27>      
                                  281      GND                     
                                  282      M_D_CPU0_SB_DQS_DN<8>   
                                  283      M_D_CPU0_SB_DQS_DP<8>   
                                  284      GND                     
                                  285      M_D_CPU0_SB_DQ<30>      
                                  286      GND                     
                                  287      M_D_CPU0_SB_DQ<31>      
                                  288      GND                     
                                  G1       GND                     
                                  G2       GND                     
                                  G3       GND                     
J9               SCONN288_ADR50001P013C01-SCONNA 1        P12V_S3_AUX_CPU0_NVDIMM 
                                  3        P3V3_AUX                
                                  4        I3C_SPD_DDREFGH_CPU0_LVC1_SCL
                                  5        I3C_SPD_DDREFGH_CPU0_LVC1_SDA
                                  6        GND                     
                                  7        M_E_CPU0_SA_DQ<0>       
                                  8        GND                     
                                  9        M_E_CPU0_SA_DQ<1>       
                                  10       GND                     
                                  11       M_E_CPU0_SA_DQS_DP<0>   
                                  12       M_E_CPU0_SA_DQS_DN<0>   
                                  13       GND                     
                                  14       M_E_CPU0_SA_DQ<4>       
                                  15       GND                     
                                  16       M_E_CPU0_SA_DQ<5>       
                                  17       GND                     
                                  18       M_E_CPU0_SA_DQ<8>       
                                  19       GND                     
                                  20       M_E_CPU0_SA_DQ<9>       
                                  21       GND                     
                                  22       M_E_CPU0_SA_DQS_DP<1>   
                                  23       M_E_CPU0_SA_DQS_DN<1>   
                                  24       GND                     
                                  25       M_E_CPU0_SA_DQ<12>      
                                  26       GND                     
                                  27       M_E_CPU0_SA_DQ<13>      
                                  28       GND                     
                                  29       M_E_CPU0_SA_DQ<16>      
                                  30       GND                     
                                  31       M_E_CPU0_SA_DQ<17>      
                                  32       GND                     
                                  33       M_E_CPU0_SA_DQS_DP<2>   
                                  34       M_E_CPU0_SA_DQS_DN<2>   
                                  35       GND                     
                                  36       M_E_CPU0_SA_DQ<20>      
                                  37       GND                     
                                  38       M_E_CPU0_SA_DQ<21>      
                                  39       GND                     
                                  40       M_E_CPU0_SA_DQ<24>      
                                  41       GND                     
                                  42       M_E_CPU0_SA_DQ<25>      
                                  43       GND                     
                                  44       M_E_CPU0_SA_DQS_DP<3>   
                                  45       M_E_CPU0_SA_DQS_DN<3>   
                                  46       GND                     
                                  47       M_E_CPU0_SA_DQ<28>      
                                  48       GND                     
                                  49       M_E_CPU0_SA_DQ<29>      
                                  50       GND                     
                                  51       M_E_CPU0_SA_CB<0>       
                                  52       GND                     
                                  53       M_E_CPU0_SA_CB<1>       
                                  54       GND                     
                                  55       M_E_CPU0_SA_DQS_DP<4>   
                                  56       M_E_CPU0_SA_DQS_DN<4>   
                                  57       GND                     
                                  58       M_E_CPU0_SA_CB<4>       
                                  59       GND                     
                                  60       M_E_CPU0_SA_CB<5>       
                                  61       GND                     
                                  62       M_E_CPU0_ALERT_N        
                                  63       GND                     
                                  64       M_E_CPU0_SA_CS_N<0>     
                                  65       GND                     
                                  66       M_E_CPU0_SA_CA<0>       
                                  67       GND                     
                                  68       M_E_CPU0_SA_CA<2>       
                                  69       GND                     
                                  70       M_E_CPU0_SA_CA<4>       
                                  71       GND                     
                                  72       M_E_CPU0_SA_CA<6>       
                                  73       GND                     
                                  74       M_E_CPU0_SA_PAR         
                                  75       GND                     
                                  76       M_E_CPU0_SB_CA<0>       
                                  77       GND                     
                                  78       M_E_CPU0_SB_CA<2>       
                                  79       GND                     
                                  80       M_E_CPU0_SB_CA<4>       
                                  81       GND                     
                                  82       M_E_CPU0_SB_CA<6>       
                                  83       GND                     
                                  84       M_E_CPU0_SB_CS_N<0>     
                                  85       GND                     
                                  86       M_E_CPU0_SA_RSP<0>      
                                  87       M_E_CPU0_SB_RSP<0>      
                                  88       GND                     
                                  89       M_E_CPU0_SB_CB<4>       
                                  90       GND                     
                                  91       M_E_CPU0_SB_CB<5>       
                                  92       GND                     
                                  93       M_E_CPU0_SB_DQS_DP<9>   
                                  94       M_E_CPU0_SB_DQS_DN<9>   
                                  95       GND                     
                                  96       M_E_CPU0_SB_CB<0>       
                                  97       GND                     
                                  98       M_E_CPU0_SB_CB<1>       
                                  99       GND                     
                                  100      M_E_CPU0_SB_DQ<0>       
                                  101      GND                     
                                  102      M_E_CPU0_SB_DQ<1>       
                                  103      GND                     
                                  104      M_E_CPU0_SB_DQS_DP<0>   
                                  105      M_E_CPU0_SB_DQS_DN<0>   
                                  106      GND                     
                                  107      M_E_CPU0_SB_DQ<4>       
                                  108      GND                     
                                  109      M_E_CPU0_SB_DQ<5>       
                                  110      GND                     
                                  111      M_E_CPU0_SB_DQ<8>       
                                  112      GND                     
                                  113      M_E_CPU0_SB_DQ<9>       
                                  114      GND                     
                                  115      M_E_CPU0_SB_DQS_DP<1>   
                                  116      M_E_CPU0_SB_DQS_DN<1>   
                                  117      GND                     
                                  118      M_E_CPU0_SB_DQ<12>      
                                  119      GND                     
                                  120      M_E_CPU0_SB_DQ<13>      
                                  121      GND                     
                                  122      M_E_CPU0_SB_DQ<16>      
                                  123      GND                     
                                  124      M_E_CPU0_SB_DQ<17>      
                                  125      GND                     
                                  126      M_E_CPU0_SB_DQS_DP<2>   
                                  127      M_E_CPU0_SB_DQS_DN<2>   
                                  128      GND                     
                                  129      M_E_CPU0_SB_DQ<20>      
                                  130      GND                     
                                  131      M_E_CPU0_SB_DQ<21>      
                                  132      GND                     
                                  133      M_E_CPU0_SB_DQ<24>      
                                  134      GND                     
                                  135      M_E_CPU0_SB_DQ<25>      
                                  136      GND                     
                                  137      M_E_CPU0_SB_DQS_DP<3>   
                                  138      M_E_CPU0_SB_DQS_DN<3>   
                                  139      GND                     
                                  140      M_E_CPU0_SB_DQ<28>      
                                  141      GND                     
                                  142      M_E_CPU0_SB_DQ<29>      
                                  143      GND                     
                                  145      P12V_S3_AUX_CPU0_NVDIMM 
                                  146      P12V_S3_AUX_CPU0_NVDIMM 
                                  147      PWRGD_CHE_CPU0_DIMM1    
                                  148      PD_CHE_CPU0_DIMM1_SAA   
                                  151      GND                     
                                  152      M_E_CPU0_SA_DQ<2>       
                                  153      GND                     
                                  154      M_E_CPU0_SA_DQ<3>       
                                  155      GND                     
                                  156      M_E_CPU0_SA_DQS_DN<5>   
                                  157      M_E_CPU0_SA_DQS_DP<5>   
                                  158      GND                     
                                  159      M_E_CPU0_SA_DQ<6>       
                                  160      GND                     
                                  161      M_E_CPU0_SA_DQ<7>       
                                  162      GND                     
                                  163      M_E_CPU0_SA_DQ<10>      
                                  164      GND                     
                                  165      M_E_CPU0_SA_DQ<11>      
                                  166      GND                     
                                  167      M_E_CPU0_SA_DQS_DN<6>   
                                  168      M_E_CPU0_SA_DQS_DP<6>   
                                  169      GND                     
                                  170      M_E_CPU0_SA_DQ<14>      
                                  171      GND                     
                                  172      M_E_CPU0_SA_DQ<15>      
                                  173      GND                     
                                  174      M_E_CPU0_SA_DQ<18>      
                                  175      GND                     
                                  176      M_E_CPU0_SA_DQ<19>      
                                  177      GND                     
                                  178      M_E_CPU0_SA_DQS_DN<7>   
                                  179      M_E_CPU0_SA_DQS_DP<7>   
                                  180      GND                     
                                  181      M_E_CPU0_SA_DQ<22>      
                                  182      GND                     
                                  183      M_E_CPU0_SA_DQ<23>      
                                  184      GND                     
                                  185      M_E_CPU0_SA_DQ<26>      
                                  186      GND                     
                                  187      M_E_CPU0_SA_DQ<27>      
                                  188      GND                     
                                  189      M_E_CPU0_SA_DQS_DN<8>   
                                  190      M_E_CPU0_SA_DQS_DP<8>   
                                  191      GND                     
                                  192      M_E_CPU0_SA_DQ<30>      
                                  193      GND                     
                                  194      M_E_CPU0_SA_DQ<31>      
                                  195      GND                     
                                  196      M_E_CPU0_SA_CB<2>       
                                  197      GND                     
                                  198      M_E_CPU0_SA_CB<3>       
                                  199      GND                     
                                  200      M_E_CPU0_SA_DQS_DN<9>   
                                  201      M_E_CPU0_SA_DQS_DP<9>   
                                  202      GND                     
                                  203      M_E_CPU0_SA_CB<6>       
                                  204      GND                     
                                  205      M_E_CPU0_SA_CB<7>       
                                  206      GND                     
                                  207      RST_M_EF_CPU0_FPGA_N    
                                  208      GND                     
                                  209      M_E_CPU0_SA_CS_N<1>     
                                  210      GND                     
                                  211      M_E_CPU0_SA_CA<1>       
                                  212      GND                     
                                  213      M_E_CPU0_SA_CA<3>       
                                  214      GND                     
                                  215      M_E_CPU0_SA_CA<5>       
                                  216      GND                     
                                  217      M_E_CPU0_CLK_DP<0>      
                                  218      M_E_CPU0_CLK_DN<0>      
                                  219      GND                     
                                  221      M_E_CPU0_SB_CA<1>       
                                  222      GND                     
                                  223      M_E_CPU0_SB_CA<3>       
                                  224      GND                     
                                  225      M_E_CPU0_SB_CA<5>       
                                  226      GND                     
                                  227      M_E_CPU0_SB_PAR         
                                  228      GND                     
                                  229      M_E_CPU0_SB_CS_N<1>     
                                  230      GND                     
                                  233      GND                     
                                  234      M_E_CPU0_SB_CB<6>       
                                  235      GND                     
                                  236      M_E_CPU0_SB_CB<7>       
                                  237      GND                     
                                  238      M_E_CPU0_SB_DQS_DN<4>   
                                  239      M_E_CPU0_SB_DQS_DP<4>   
                                  240      GND                     
                                  241      M_E_CPU0_SB_CB<2>       
                                  242      GND                     
                                  243      M_E_CPU0_SB_CB<3>       
                                  244      GND                     
                                  245      M_E_CPU0_SB_DQ<2>       
                                  246      GND                     
                                  247      M_E_CPU0_SB_DQ<3>       
                                  248      GND                     
                                  249      M_E_CPU0_SB_DQS_DN<5>   
                                  250      M_E_CPU0_SB_DQS_DP<5>   
                                  251      GND                     
                                  252      M_E_CPU0_SB_DQ<6>       
                                  253      GND                     
                                  254      M_E_CPU0_SB_DQ<7>       
                                  255      GND                     
                                  256      M_E_CPU0_SB_DQ<10>      
                                  257      GND                     
                                  258      M_E_CPU0_SB_DQ<11>      
                                  259      GND                     
                                  260      M_E_CPU0_SB_DQS_DN<6>   
                                  261      M_E_CPU0_SB_DQS_DP<6>   
                                  262      GND                     
                                  263      M_E_CPU0_SB_DQ<14>      
                                  264      GND                     
                                  265      M_E_CPU0_SB_DQ<15>      
                                  266      GND                     
                                  267      M_E_CPU0_SB_DQ<18>      
                                  268      GND                     
                                  269      M_E_CPU0_SB_DQ<19>      
                                  270      GND                     
                                  271      M_E_CPU0_SB_DQS_DN<7>   
                                  272      M_E_CPU0_SB_DQS_DP<7>   
                                  273      GND                     
                                  274      M_E_CPU0_SB_DQ<22>      
                                  275      GND                     
                                  276      M_E_CPU0_SB_DQ<23>      
                                  277      GND                     
                                  278      M_E_CPU0_SB_DQ<26>      
                                  279      GND                     
                                  280      M_E_CPU0_SB_DQ<27>      
                                  281      GND                     
                                  282      M_E_CPU0_SB_DQS_DN<8>   
                                  283      M_E_CPU0_SB_DQS_DP<8>   
                                  284      GND                     
                                  285      M_E_CPU0_SB_DQ<30>      
                                  286      GND                     
                                  287      M_E_CPU0_SB_DQ<31>      
                                  288      GND                     
                                  G1       GND                     
                                  G2       GND                     
                                  G3       GND                     
J10              SCONN288_ADR50001P003C01-SCONNA 1        P12V_S3_AUX_CPU0_NVDIMM 
                                  3        P3V3_AUX                
                                  4        I3C_SPD_DDREFGH_CPU0_LVC1_SCL
                                  5        I3C_SPD_DDREFGH_CPU0_LVC1_SDA
                                  6        GND                     
                                  7        M_E_CPU0_SA_DQ<0>       
                                  8        GND                     
                                  9        M_E_CPU0_SA_DQ<1>       
                                  10       GND                     
                                  11       M_E_CPU0_SA_DQS_DP<0>   
                                  12       M_E_CPU0_SA_DQS_DN<0>   
                                  13       GND                     
                                  14       M_E_CPU0_SA_DQ<4>       
                                  15       GND                     
                                  16       M_E_CPU0_SA_DQ<5>       
                                  17       GND                     
                                  18       M_E_CPU0_SA_DQ<8>       
                                  19       GND                     
                                  20       M_E_CPU0_SA_DQ<9>       
                                  21       GND                     
                                  22       M_E_CPU0_SA_DQS_DP<1>   
                                  23       M_E_CPU0_SA_DQS_DN<1>   
                                  24       GND                     
                                  25       M_E_CPU0_SA_DQ<12>      
                                  26       GND                     
                                  27       M_E_CPU0_SA_DQ<13>      
                                  28       GND                     
                                  29       M_E_CPU0_SA_DQ<16>      
                                  30       GND                     
                                  31       M_E_CPU0_SA_DQ<17>      
                                  32       GND                     
                                  33       M_E_CPU0_SA_DQS_DP<2>   
                                  34       M_E_CPU0_SA_DQS_DN<2>   
                                  35       GND                     
                                  36       M_E_CPU0_SA_DQ<20>      
                                  37       GND                     
                                  38       M_E_CPU0_SA_DQ<21>      
                                  39       GND                     
                                  40       M_E_CPU0_SA_DQ<24>      
                                  41       GND                     
                                  42       M_E_CPU0_SA_DQ<25>      
                                  43       GND                     
                                  44       M_E_CPU0_SA_DQS_DP<3>   
                                  45       M_E_CPU0_SA_DQS_DN<3>   
                                  46       GND                     
                                  47       M_E_CPU0_SA_DQ<28>      
                                  48       GND                     
                                  49       M_E_CPU0_SA_DQ<29>      
                                  50       GND                     
                                  51       M_E_CPU0_SA_CB<0>       
                                  52       GND                     
                                  53       M_E_CPU0_SA_CB<1>       
                                  54       GND                     
                                  55       M_E_CPU0_SA_DQS_DP<4>   
                                  56       M_E_CPU0_SA_DQS_DN<4>   
                                  57       GND                     
                                  58       M_E_CPU0_SA_CB<4>       
                                  59       GND                     
                                  60       M_E_CPU0_SA_CB<5>       
                                  61       GND                     
                                  62       M_E_CPU0_ALERT_N        
                                  63       GND                     
                                  64       M_E_CPU0_SA_CS_N<2>     
                                  65       GND                     
                                  66       M_E_CPU0_SA_CA<0>       
                                  67       GND                     
                                  68       M_E_CPU0_SA_CA<2>       
                                  69       GND                     
                                  70       M_E_CPU0_SA_CA<4>       
                                  71       GND                     
                                  72       M_E_CPU0_SA_CA<6>       
                                  73       GND                     
                                  74       M_E_CPU0_SA_PAR         
                                  75       GND                     
                                  76       M_E_CPU0_SB_CA<0>       
                                  77       GND                     
                                  78       M_E_CPU0_SB_CA<2>       
                                  79       GND                     
                                  80       M_E_CPU0_SB_CA<4>       
                                  81       GND                     
                                  82       M_E_CPU0_SB_CA<6>       
                                  83       GND                     
                                  84       M_E_CPU0_SB_CS_N<2>     
                                  85       GND                     
                                  86       M_E_CPU0_SA_RSP<1>      
                                  87       M_E_CPU0_SB_RSP<1>      
                                  88       GND                     
                                  89       M_E_CPU0_SB_CB<4>       
                                  90       GND                     
                                  91       M_E_CPU0_SB_CB<5>       
                                  92       GND                     
                                  93       M_E_CPU0_SB_DQS_DP<9>   
                                  94       M_E_CPU0_SB_DQS_DN<9>   
                                  95       GND                     
                                  96       M_E_CPU0_SB_CB<0>       
                                  97       GND                     
                                  98       M_E_CPU0_SB_CB<1>       
                                  99       GND                     
                                  100      M_E_CPU0_SB_DQ<0>       
                                  101      GND                     
                                  102      M_E_CPU0_SB_DQ<1>       
                                  103      GND                     
                                  104      M_E_CPU0_SB_DQS_DP<0>   
                                  105      M_E_CPU0_SB_DQS_DN<0>   
                                  106      GND                     
                                  107      M_E_CPU0_SB_DQ<4>       
                                  108      GND                     
                                  109      M_E_CPU0_SB_DQ<5>       
                                  110      GND                     
                                  111      M_E_CPU0_SB_DQ<8>       
                                  112      GND                     
                                  113      M_E_CPU0_SB_DQ<9>       
                                  114      GND                     
                                  115      M_E_CPU0_SB_DQS_DP<1>   
                                  116      M_E_CPU0_SB_DQS_DN<1>   
                                  117      GND                     
                                  118      M_E_CPU0_SB_DQ<12>      
                                  119      GND                     
                                  120      M_E_CPU0_SB_DQ<13>      
                                  121      GND                     
                                  122      M_E_CPU0_SB_DQ<16>      
                                  123      GND                     
                                  124      M_E_CPU0_SB_DQ<17>      
                                  125      GND                     
                                  126      M_E_CPU0_SB_DQS_DP<2>   
                                  127      M_E_CPU0_SB_DQS_DN<2>   
                                  128      GND                     
                                  129      M_E_CPU0_SB_DQ<20>      
                                  130      GND                     
                                  131      M_E_CPU0_SB_DQ<21>      
                                  132      GND                     
                                  133      M_E_CPU0_SB_DQ<24>      
                                  134      GND                     
                                  135      M_E_CPU0_SB_DQ<25>      
                                  136      GND                     
                                  137      M_E_CPU0_SB_DQS_DP<3>   
                                  138      M_E_CPU0_SB_DQS_DN<3>   
                                  139      GND                     
                                  140      M_E_CPU0_SB_DQ<28>      
                                  141      GND                     
                                  142      M_E_CPU0_SB_DQ<29>      
                                  143      GND                     
                                  145      P12V_S3_AUX_CPU0_NVDIMM 
                                  146      P12V_S3_AUX_CPU0_NVDIMM 
                                  147      PWRGD_CHE_CPU0_DIMM2    
                                  148      PD_CHE_CPU0_DIMM2_SAA   
                                  151      GND                     
                                  152      M_E_CPU0_SA_DQ<2>       
                                  153      GND                     
                                  154      M_E_CPU0_SA_DQ<3>       
                                  155      GND                     
                                  156      M_E_CPU0_SA_DQS_DN<5>   
                                  157      M_E_CPU0_SA_DQS_DP<5>   
                                  158      GND                     
                                  159      M_E_CPU0_SA_DQ<6>       
                                  160      GND                     
                                  161      M_E_CPU0_SA_DQ<7>       
                                  162      GND                     
                                  163      M_E_CPU0_SA_DQ<10>      
                                  164      GND                     
                                  165      M_E_CPU0_SA_DQ<11>      
                                  166      GND                     
                                  167      M_E_CPU0_SA_DQS_DN<6>   
                                  168      M_E_CPU0_SA_DQS_DP<6>   
                                  169      GND                     
                                  170      M_E_CPU0_SA_DQ<14>      
                                  171      GND                     
                                  172      M_E_CPU0_SA_DQ<15>      
                                  173      GND                     
                                  174      M_E_CPU0_SA_DQ<18>      
                                  175      GND                     
                                  176      M_E_CPU0_SA_DQ<19>      
                                  177      GND                     
                                  178      M_E_CPU0_SA_DQS_DN<7>   
                                  179      M_E_CPU0_SA_DQS_DP<7>   
                                  180      GND                     
                                  181      M_E_CPU0_SA_DQ<22>      
                                  182      GND                     
                                  183      M_E_CPU0_SA_DQ<23>      
                                  184      GND                     
                                  185      M_E_CPU0_SA_DQ<26>      
                                  186      GND                     
                                  187      M_E_CPU0_SA_DQ<27>      
                                  188      GND                     
                                  189      M_E_CPU0_SA_DQS_DN<8>   
                                  190      M_E_CPU0_SA_DQS_DP<8>   
                                  191      GND                     
                                  192      M_E_CPU0_SA_DQ<30>      
                                  193      GND                     
                                  194      M_E_CPU0_SA_DQ<31>      
                                  195      GND                     
                                  196      M_E_CPU0_SA_CB<2>       
                                  197      GND                     
                                  198      M_E_CPU0_SA_CB<3>       
                                  199      GND                     
                                  200      M_E_CPU0_SA_DQS_DN<9>   
                                  201      M_E_CPU0_SA_DQS_DP<9>   
                                  202      GND                     
                                  203      M_E_CPU0_SA_CB<6>       
                                  204      GND                     
                                  205      M_E_CPU0_SA_CB<7>       
                                  206      GND                     
                                  207      RST_M_EF_CPU0_FPGA_N    
                                  208      GND                     
                                  209      M_E_CPU0_SA_CS_N<3>     
                                  210      GND                     
                                  211      M_E_CPU0_SA_CA<1>       
                                  212      GND                     
                                  213      M_E_CPU0_SA_CA<3>       
                                  214      GND                     
                                  215      M_E_CPU0_SA_CA<5>       
                                  216      GND                     
                                  217      M_E_CPU0_CLK_DP<1>      
                                  218      M_E_CPU0_CLK_DN<1>      
                                  219      GND                     
                                  221      M_E_CPU0_SB_CA<1>       
                                  222      GND                     
                                  223      M_E_CPU0_SB_CA<3>       
                                  224      GND                     
                                  225      M_E_CPU0_SB_CA<5>       
                                  226      GND                     
                                  227      M_E_CPU0_SB_PAR         
                                  228      GND                     
                                  229      M_E_CPU0_SB_CS_N<3>     
                                  230      GND                     
                                  233      GND                     
                                  234      M_E_CPU0_SB_CB<6>       
                                  235      GND                     
                                  236      M_E_CPU0_SB_CB<7>       
                                  237      GND                     
                                  238      M_E_CPU0_SB_DQS_DN<4>   
                                  239      M_E_CPU0_SB_DQS_DP<4>   
                                  240      GND                     
                                  241      M_E_CPU0_SB_CB<2>       
                                  242      GND                     
                                  243      M_E_CPU0_SB_CB<3>       
                                  244      GND                     
                                  245      M_E_CPU0_SB_DQ<2>       
                                  246      GND                     
                                  247      M_E_CPU0_SB_DQ<3>       
                                  248      GND                     
                                  249      M_E_CPU0_SB_DQS_DN<5>   
                                  250      M_E_CPU0_SB_DQS_DP<5>   
                                  251      GND                     
                                  252      M_E_CPU0_SB_DQ<6>       
                                  253      GND                     
                                  254      M_E_CPU0_SB_DQ<7>       
                                  255      GND                     
                                  256      M_E_CPU0_SB_DQ<10>      
                                  257      GND                     
                                  258      M_E_CPU0_SB_DQ<11>      
                                  259      GND                     
                                  260      M_E_CPU0_SB_DQS_DN<6>   
                                  261      M_E_CPU0_SB_DQS_DP<6>   
                                  262      GND                     
                                  263      M_E_CPU0_SB_DQ<14>      
                                  264      GND                     
                                  265      M_E_CPU0_SB_DQ<15>      
                                  266      GND                     
                                  267      M_E_CPU0_SB_DQ<18>      
                                  268      GND                     
                                  269      M_E_CPU0_SB_DQ<19>      
                                  270      GND                     
                                  271      M_E_CPU0_SB_DQS_DN<7>   
                                  272      M_E_CPU0_SB_DQS_DP<7>   
                                  273      GND                     
                                  274      M_E_CPU0_SB_DQ<22>      
                                  275      GND                     
                                  276      M_E_CPU0_SB_DQ<23>      
                                  277      GND                     
                                  278      M_E_CPU0_SB_DQ<26>      
                                  279      GND                     
                                  280      M_E_CPU0_SB_DQ<27>      
                                  281      GND                     
                                  282      M_E_CPU0_SB_DQS_DN<8>   
                                  283      M_E_CPU0_SB_DQS_DP<8>   
                                  284      GND                     
                                  285      M_E_CPU0_SB_DQ<30>      
                                  286      GND                     
                                  287      M_E_CPU0_SB_DQ<31>      
                                  288      GND                     
                                  G1       GND                     
                                  G2       GND                     
                                  G3       GND                     
J11              SCONN288_ADR50001P013C01-SCONNA 1        P12V_S3_AUX_CPU0_NVDIMM 
                                  3        P3V3_AUX                
                                  4        I3C_SPD_DDREFGH_CPU0_LVC1_SCL
                                  5        I3C_SPD_DDREFGH_CPU0_LVC1_SDA
                                  6        GND                     
                                  7        M_F_CPU0_SA_DQ<0>       
                                  8        GND                     
                                  9        M_F_CPU0_SA_DQ<1>       
                                  10       GND                     
                                  11       M_F_CPU0_SA_DQS_DP<0>   
                                  12       M_F_CPU0_SA_DQS_DN<0>   
                                  13       GND                     
                                  14       M_F_CPU0_SA_DQ<4>       
                                  15       GND                     
                                  16       M_F_CPU0_SA_DQ<5>       
                                  17       GND                     
                                  18       M_F_CPU0_SA_DQ<8>       
                                  19       GND                     
                                  20       M_F_CPU0_SA_DQ<9>       
                                  21       GND                     
                                  22       M_F_CPU0_SA_DQS_DP<1>   
                                  23       M_F_CPU0_SA_DQS_DN<1>   
                                  24       GND                     
                                  25       M_F_CPU0_SA_DQ<12>      
                                  26       GND                     
                                  27       M_F_CPU0_SA_DQ<13>      
                                  28       GND                     
                                  29       M_F_CPU0_SA_DQ<16>      
                                  30       GND                     
                                  31       M_F_CPU0_SA_DQ<17>      
                                  32       GND                     
                                  33       M_F_CPU0_SA_DQS_DP<2>   
                                  34       M_F_CPU0_SA_DQS_DN<2>   
                                  35       GND                     
                                  36       M_F_CPU0_SA_DQ<20>      
                                  37       GND                     
                                  38       M_F_CPU0_SA_DQ<21>      
                                  39       GND                     
                                  40       M_F_CPU0_SA_DQ<24>      
                                  41       GND                     
                                  42       M_F_CPU0_SA_DQ<25>      
                                  43       GND                     
                                  44       M_F_CPU0_SA_DQS_DP<3>   
                                  45       M_F_CPU0_SA_DQS_DN<3>   
                                  46       GND                     
                                  47       M_F_CPU0_SA_DQ<28>      
                                  48       GND                     
                                  49       M_F_CPU0_SA_DQ<29>      
                                  50       GND                     
                                  51       M_F_CPU0_SA_CB<0>       
                                  52       GND                     
                                  53       M_F_CPU0_SA_CB<1>       
                                  54       GND                     
                                  55       M_F_CPU0_SA_DQS_DP<4>   
                                  56       M_F_CPU0_SA_DQS_DN<4>   
                                  57       GND                     
                                  58       M_F_CPU0_SA_CB<4>       
                                  59       GND                     
                                  60       M_F_CPU0_SA_CB<5>       
                                  61       GND                     
                                  62       M_F_CPU0_ALERT_N        
                                  63       GND                     
                                  64       M_F_CPU0_SA_CS_N<0>     
                                  65       GND                     
                                  66       M_F_CPU0_SA_CA<0>       
                                  67       GND                     
                                  68       M_F_CPU0_SA_CA<2>       
                                  69       GND                     
                                  70       M_F_CPU0_SA_CA<4>       
                                  71       GND                     
                                  72       M_F_CPU0_SA_CA<6>       
                                  73       GND                     
                                  74       M_F_CPU0_SA_PAR         
                                  75       GND                     
                                  76       M_F_CPU0_SB_CA<0>       
                                  77       GND                     
                                  78       M_F_CPU0_SB_CA<2>       
                                  79       GND                     
                                  80       M_F_CPU0_SB_CA<4>       
                                  81       GND                     
                                  82       M_F_CPU0_SB_CA<6>       
                                  83       GND                     
                                  84       M_F_CPU0_SB_CS_N<0>     
                                  85       GND                     
                                  86       M_F_CPU0_SA_RSP<0>      
                                  87       M_F_CPU0_SB_RSP<0>      
                                  88       GND                     
                                  89       M_F_CPU0_SB_CB<4>       
                                  90       GND                     
                                  91       M_F_CPU0_SB_CB<5>       
                                  92       GND                     
                                  93       M_F_CPU0_SB_DQS_DP<9>   
                                  94       M_F_CPU0_SB_DQS_DN<9>   
                                  95       GND                     
                                  96       M_F_CPU0_SB_CB<0>       
                                  97       GND                     
                                  98       M_F_CPU0_SB_CB<1>       
                                  99       GND                     
                                  100      M_F_CPU0_SB_DQ<0>       
                                  101      GND                     
                                  102      M_F_CPU0_SB_DQ<1>       
                                  103      GND                     
                                  104      M_F_CPU0_SB_DQS_DP<0>   
                                  105      M_F_CPU0_SB_DQS_DN<0>   
                                  106      GND                     
                                  107      M_F_CPU0_SB_DQ<4>       
                                  108      GND                     
                                  109      M_F_CPU0_SB_DQ<5>       
                                  110      GND                     
                                  111      M_F_CPU0_SB_DQ<8>       
                                  112      GND                     
                                  113      M_F_CPU0_SB_DQ<9>       
                                  114      GND                     
                                  115      M_F_CPU0_SB_DQS_DP<1>   
                                  116      M_F_CPU0_SB_DQS_DN<1>   
                                  117      GND                     
                                  118      M_F_CPU0_SB_DQ<12>      
                                  119      GND                     
                                  120      M_F_CPU0_SB_DQ<13>      
                                  121      GND                     
                                  122      M_F_CPU0_SB_DQ<16>      
                                  123      GND                     
                                  124      M_F_CPU0_SB_DQ<17>      
                                  125      GND                     
                                  126      M_F_CPU0_SB_DQS_DP<2>   
                                  127      M_F_CPU0_SB_DQS_DN<2>   
                                  128      GND                     
                                  129      M_F_CPU0_SB_DQ<20>      
                                  130      GND                     
                                  131      M_F_CPU0_SB_DQ<21>      
                                  132      GND                     
                                  133      M_F_CPU0_SB_DQ<24>      
                                  134      GND                     
                                  135      M_F_CPU0_SB_DQ<25>      
                                  136      GND                     
                                  137      M_F_CPU0_SB_DQS_DP<3>   
                                  138      M_F_CPU0_SB_DQS_DN<3>   
                                  139      GND                     
                                  140      M_F_CPU0_SB_DQ<28>      
                                  141      GND                     
                                  142      M_F_CPU0_SB_DQ<29>      
                                  143      GND                     
                                  145      P12V_S3_AUX_CPU0_NVDIMM 
                                  146      P12V_S3_AUX_CPU0_NVDIMM 
                                  147      PWRGD_CHF_CPU0_DIMM1    
                                  148      PD_CHF_CPU0_DIMM1_SAA   
                                  151      GND                     
                                  152      M_F_CPU0_SA_DQ<2>       
                                  153      GND                     
                                  154      M_F_CPU0_SA_DQ<3>       
                                  155      GND                     
                                  156      M_F_CPU0_SA_DQS_DN<5>   
                                  157      M_F_CPU0_SA_DQS_DP<5>   
                                  158      GND                     
                                  159      M_F_CPU0_SA_DQ<6>       
                                  160      GND                     
                                  161      M_F_CPU0_SA_DQ<7>       
                                  162      GND                     
                                  163      M_F_CPU0_SA_DQ<10>      
                                  164      GND                     
                                  165      M_F_CPU0_SA_DQ<11>      
                                  166      GND                     
                                  167      M_F_CPU0_SA_DQS_DN<6>   
                                  168      M_F_CPU0_SA_DQS_DP<6>   
                                  169      GND                     
                                  170      M_F_CPU0_SA_DQ<14>      
                                  171      GND                     
                                  172      M_F_CPU0_SA_DQ<15>      
                                  173      GND                     
                                  174      M_F_CPU0_SA_DQ<18>      
                                  175      GND                     
                                  176      M_F_CPU0_SA_DQ<19>      
                                  177      GND                     
                                  178      M_F_CPU0_SA_DQS_DN<7>   
                                  179      M_F_CPU0_SA_DQS_DP<7>   
                                  180      GND                     
                                  181      M_F_CPU0_SA_DQ<22>      
                                  182      GND                     
                                  183      M_F_CPU0_SA_DQ<23>      
                                  184      GND                     
                                  185      M_F_CPU0_SA_DQ<26>      
                                  186      GND                     
                                  187      M_F_CPU0_SA_DQ<27>      
                                  188      GND                     
                                  189      M_F_CPU0_SA_DQS_DN<8>   
                                  190      M_F_CPU0_SA_DQS_DP<8>   
                                  191      GND                     
                                  192      M_F_CPU0_SA_DQ<30>      
                                  193      GND                     
                                  194      M_F_CPU0_SA_DQ<31>      
                                  195      GND                     
                                  196      M_F_CPU0_SA_CB<2>       
                                  197      GND                     
                                  198      M_F_CPU0_SA_CB<3>       
                                  199      GND                     
                                  200      M_F_CPU0_SA_DQS_DN<9>   
                                  201      M_F_CPU0_SA_DQS_DP<9>   
                                  202      GND                     
                                  203      M_F_CPU0_SA_CB<6>       
                                  204      GND                     
                                  205      M_F_CPU0_SA_CB<7>       
                                  206      GND                     
                                  207      RST_M_EF_CPU0_FPGA_N    
                                  208      GND                     
                                  209      M_F_CPU0_SA_CS_N<1>     
                                  210      GND                     
                                  211      M_F_CPU0_SA_CA<1>       
                                  212      GND                     
                                  213      M_F_CPU0_SA_CA<3>       
                                  214      GND                     
                                  215      M_F_CPU0_SA_CA<5>       
                                  216      GND                     
                                  217      M_F_CPU0_CLK_DP<0>      
                                  218      M_F_CPU0_CLK_DN<0>      
                                  219      GND                     
                                  221      M_F_CPU0_SB_CA<1>       
                                  222      GND                     
                                  223      M_F_CPU0_SB_CA<3>       
                                  224      GND                     
                                  225      M_F_CPU0_SB_CA<5>       
                                  226      GND                     
                                  227      M_F_CPU0_SB_PAR         
                                  228      GND                     
                                  229      M_F_CPU0_SB_CS_N<1>     
                                  230      GND                     
                                  233      GND                     
                                  234      M_F_CPU0_SB_CB<6>       
                                  235      GND                     
                                  236      M_F_CPU0_SB_CB<7>       
                                  237      GND                     
                                  238      M_F_CPU0_SB_DQS_DN<4>   
                                  239      M_F_CPU0_SB_DQS_DP<4>   
                                  240      GND                     
                                  241      M_F_CPU0_SB_CB<2>       
                                  242      GND                     
                                  243      M_F_CPU0_SB_CB<3>       
                                  244      GND                     
                                  245      M_F_CPU0_SB_DQ<2>       
                                  246      GND                     
                                  247      M_F_CPU0_SB_DQ<3>       
                                  248      GND                     
                                  249      M_F_CPU0_SB_DQS_DN<5>   
                                  250      M_F_CPU0_SB_DQS_DP<5>   
                                  251      GND                     
                                  252      M_F_CPU0_SB_DQ<6>       
                                  253      GND                     
                                  254      M_F_CPU0_SB_DQ<7>       
                                  255      GND                     
                                  256      M_F_CPU0_SB_DQ<10>      
                                  257      GND                     
                                  258      M_F_CPU0_SB_DQ<11>      
                                  259      GND                     
                                  260      M_F_CPU0_SB_DQS_DN<6>   
                                  261      M_F_CPU0_SB_DQS_DP<6>   
                                  262      GND                     
                                  263      M_F_CPU0_SB_DQ<14>      
                                  264      GND                     
                                  265      M_F_CPU0_SB_DQ<15>      
                                  266      GND                     
                                  267      M_F_CPU0_SB_DQ<18>      
                                  268      GND                     
                                  269      M_F_CPU0_SB_DQ<19>      
                                  270      GND                     
                                  271      M_F_CPU0_SB_DQS_DN<7>   
                                  272      M_F_CPU0_SB_DQS_DP<7>   
                                  273      GND                     
                                  274      M_F_CPU0_SB_DQ<22>      
                                  275      GND                     
                                  276      M_F_CPU0_SB_DQ<23>      
                                  277      GND                     
                                  278      M_F_CPU0_SB_DQ<26>      
                                  279      GND                     
                                  280      M_F_CPU0_SB_DQ<27>      
                                  281      GND                     
                                  282      M_F_CPU0_SB_DQS_DN<8>   
                                  283      M_F_CPU0_SB_DQS_DP<8>   
                                  284      GND                     
                                  285      M_F_CPU0_SB_DQ<30>      
                                  286      GND                     
                                  287      M_F_CPU0_SB_DQ<31>      
                                  288      GND                     
                                  G1       GND                     
                                  G2       GND                     
                                  G3       GND                     
J12              SCONN288_ADR50001P003C01-SCONNA 1        P12V_S3_AUX_CPU0_NVDIMM 
                                  3        P3V3_AUX                
                                  4        I3C_SPD_DDREFGH_CPU0_LVC1_SCL
                                  5        I3C_SPD_DDREFGH_CPU0_LVC1_SDA
                                  6        GND                     
                                  7        M_F_CPU0_SA_DQ<0>       
                                  8        GND                     
                                  9        M_F_CPU0_SA_DQ<1>       
                                  10       GND                     
                                  11       M_F_CPU0_SA_DQS_DP<0>   
                                  12       M_F_CPU0_SA_DQS_DN<0>   
                                  13       GND                     
                                  14       M_F_CPU0_SA_DQ<4>       
                                  15       GND                     
                                  16       M_F_CPU0_SA_DQ<5>       
                                  17       GND                     
                                  18       M_F_CPU0_SA_DQ<8>       
                                  19       GND                     
                                  20       M_F_CPU0_SA_DQ<9>       
                                  21       GND                     
                                  22       M_F_CPU0_SA_DQS_DP<1>   
                                  23       M_F_CPU0_SA_DQS_DN<1>   
                                  24       GND                     
                                  25       M_F_CPU0_SA_DQ<12>      
                                  26       GND                     
                                  27       M_F_CPU0_SA_DQ<13>      
                                  28       GND                     
                                  29       M_F_CPU0_SA_DQ<16>      
                                  30       GND                     
                                  31       M_F_CPU0_SA_DQ<17>      
                                  32       GND                     
                                  33       M_F_CPU0_SA_DQS_DP<2>   
                                  34       M_F_CPU0_SA_DQS_DN<2>   
                                  35       GND                     
                                  36       M_F_CPU0_SA_DQ<20>      
                                  37       GND                     
                                  38       M_F_CPU0_SA_DQ<21>      
                                  39       GND                     
                                  40       M_F_CPU0_SA_DQ<24>      
                                  41       GND                     
                                  42       M_F_CPU0_SA_DQ<25>      
                                  43       GND                     
                                  44       M_F_CPU0_SA_DQS_DP<3>   
                                  45       M_F_CPU0_SA_DQS_DN<3>   
                                  46       GND                     
                                  47       M_F_CPU0_SA_DQ<28>      
                                  48       GND                     
                                  49       M_F_CPU0_SA_DQ<29>      
                                  50       GND                     
                                  51       M_F_CPU0_SA_CB<0>       
                                  52       GND                     
                                  53       M_F_CPU0_SA_CB<1>       
                                  54       GND                     
                                  55       M_F_CPU0_SA_DQS_DP<4>   
                                  56       M_F_CPU0_SA_DQS_DN<4>   
                                  57       GND                     
                                  58       M_F_CPU0_SA_CB<4>       
                                  59       GND                     
                                  60       M_F_CPU0_SA_CB<5>       
                                  61       GND                     
                                  62       M_F_CPU0_ALERT_N        
                                  63       GND                     
                                  64       M_F_CPU0_SA_CS_N<2>     
                                  65       GND                     
                                  66       M_F_CPU0_SA_CA<0>       
                                  67       GND                     
                                  68       M_F_CPU0_SA_CA<2>       
                                  69       GND                     
                                  70       M_F_CPU0_SA_CA<4>       
                                  71       GND                     
                                  72       M_F_CPU0_SA_CA<6>       
                                  73       GND                     
                                  74       M_F_CPU0_SA_PAR         
                                  75       GND                     
                                  76       M_F_CPU0_SB_CA<0>       
                                  77       GND                     
                                  78       M_F_CPU0_SB_CA<2>       
                                  79       GND                     
                                  80       M_F_CPU0_SB_CA<4>       
                                  81       GND                     
                                  82       M_F_CPU0_SB_CA<6>       
                                  83       GND                     
                                  84       M_F_CPU0_SB_CS_N<2>     
                                  85       GND                     
                                  86       M_F_CPU0_SA_RSP<1>      
                                  87       M_F_CPU0_SB_RSP<1>      
                                  88       GND                     
                                  89       M_F_CPU0_SB_CB<4>       
                                  90       GND                     
                                  91       M_F_CPU0_SB_CB<5>       
                                  92       GND                     
                                  93       M_F_CPU0_SB_DQS_DP<9>   
                                  94       M_F_CPU0_SB_DQS_DN<9>   
                                  95       GND                     
                                  96       M_F_CPU0_SB_CB<0>       
                                  97       GND                     
                                  98       M_F_CPU0_SB_CB<1>       
                                  99       GND                     
                                  100      M_F_CPU0_SB_DQ<0>       
                                  101      GND                     
                                  102      M_F_CPU0_SB_DQ<1>       
                                  103      GND                     
                                  104      M_F_CPU0_SB_DQS_DP<0>   
                                  105      M_F_CPU0_SB_DQS_DN<0>   
                                  106      GND                     
                                  107      M_F_CPU0_SB_DQ<4>       
                                  108      GND                     
                                  109      M_F_CPU0_SB_DQ<5>       
                                  110      GND                     
                                  111      M_F_CPU0_SB_DQ<8>       
                                  112      GND                     
                                  113      M_F_CPU0_SB_DQ<9>       
                                  114      GND                     
                                  115      M_F_CPU0_SB_DQS_DP<1>   
                                  116      M_F_CPU0_SB_DQS_DN<1>   
                                  117      GND                     
                                  118      M_F_CPU0_SB_DQ<12>      
                                  119      GND                     
                                  120      M_F_CPU0_SB_DQ<13>      
                                  121      GND                     
                                  122      M_F_CPU0_SB_DQ<16>      
                                  123      GND                     
                                  124      M_F_CPU0_SB_DQ<17>      
                                  125      GND                     
                                  126      M_F_CPU0_SB_DQS_DP<2>   
                                  127      M_F_CPU0_SB_DQS_DN<2>   
                                  128      GND                     
                                  129      M_F_CPU0_SB_DQ<20>      
                                  130      GND                     
                                  131      M_F_CPU0_SB_DQ<21>      
                                  132      GND                     
                                  133      M_F_CPU0_SB_DQ<24>      
                                  134      GND                     
                                  135      M_F_CPU0_SB_DQ<25>      
                                  136      GND                     
                                  137      M_F_CPU0_SB_DQS_DP<3>   
                                  138      M_F_CPU0_SB_DQS_DN<3>   
                                  139      GND                     
                                  140      M_F_CPU0_SB_DQ<28>      
                                  141      GND                     
                                  142      M_F_CPU0_SB_DQ<29>      
                                  143      GND                     
                                  145      P12V_S3_AUX_CPU0_NVDIMM 
                                  146      P12V_S3_AUX_CPU0_NVDIMM 
                                  147      PWRGD_CHF_CPU0_DIMM2    
                                  148      PD_CHF_CPU0_DIMM2_SAA   
                                  151      GND                     
                                  152      M_F_CPU0_SA_DQ<2>       
                                  153      GND                     
                                  154      M_F_CPU0_SA_DQ<3>       
                                  155      GND                     
                                  156      M_F_CPU0_SA_DQS_DN<5>   
                                  157      M_F_CPU0_SA_DQS_DP<5>   
                                  158      GND                     
                                  159      M_F_CPU0_SA_DQ<6>       
                                  160      GND                     
                                  161      M_F_CPU0_SA_DQ<7>       
                                  162      GND                     
                                  163      M_F_CPU0_SA_DQ<10>      
                                  164      GND                     
                                  165      M_F_CPU0_SA_DQ<11>      
                                  166      GND                     
                                  167      M_F_CPU0_SA_DQS_DN<6>   
                                  168      M_F_CPU0_SA_DQS_DP<6>   
                                  169      GND                     
                                  170      M_F_CPU0_SA_DQ<14>      
                                  171      GND                     
                                  172      M_F_CPU0_SA_DQ<15>      
                                  173      GND                     
                                  174      M_F_CPU0_SA_DQ<18>      
                                  175      GND                     
                                  176      M_F_CPU0_SA_DQ<19>      
                                  177      GND                     
                                  178      M_F_CPU0_SA_DQS_DN<7>   
                                  179      M_F_CPU0_SA_DQS_DP<7>   
                                  180      GND                     
                                  181      M_F_CPU0_SA_DQ<22>      
                                  182      GND                     
                                  183      M_F_CPU0_SA_DQ<23>      
                                  184      GND                     
                                  185      M_F_CPU0_SA_DQ<26>      
                                  186      GND                     
                                  187      M_F_CPU0_SA_DQ<27>      
                                  188      GND                     
                                  189      M_F_CPU0_SA_DQS_DN<8>   
                                  190      M_F_CPU0_SA_DQS_DP<8>   
                                  191      GND                     
                                  192      M_F_CPU0_SA_DQ<30>      
                                  193      GND                     
                                  194      M_F_CPU0_SA_DQ<31>      
                                  195      GND                     
                                  196      M_F_CPU0_SA_CB<2>       
                                  197      GND                     
                                  198      M_F_CPU0_SA_CB<3>       
                                  199      GND                     
                                  200      M_F_CPU0_SA_DQS_DN<9>   
                                  201      M_F_CPU0_SA_DQS_DP<9>   
                                  202      GND                     
                                  203      M_F_CPU0_SA_CB<6>       
                                  204      GND                     
                                  205      M_F_CPU0_SA_CB<7>       
                                  206      GND                     
                                  207      RST_M_EF_CPU0_FPGA_N    
                                  208      GND                     
                                  209      M_F_CPU0_SA_CS_N<3>     
                                  210      GND                     
                                  211      M_F_CPU0_SA_CA<1>       
                                  212      GND                     
                                  213      M_F_CPU0_SA_CA<3>       
                                  214      GND                     
                                  215      M_F_CPU0_SA_CA<5>       
                                  216      GND                     
                                  217      M_F_CPU0_CLK_DP<1>      
                                  218      M_F_CPU0_CLK_DN<1>      
                                  219      GND                     
                                  221      M_F_CPU0_SB_CA<1>       
                                  222      GND                     
                                  223      M_F_CPU0_SB_CA<3>       
                                  224      GND                     
                                  225      M_F_CPU0_SB_CA<5>       
                                  226      GND                     
                                  227      M_F_CPU0_SB_PAR         
                                  228      GND                     
                                  229      M_F_CPU0_SB_CS_N<3>     
                                  230      GND                     
                                  233      GND                     
                                  234      M_F_CPU0_SB_CB<6>       
                                  235      GND                     
                                  236      M_F_CPU0_SB_CB<7>       
                                  237      GND                     
                                  238      M_F_CPU0_SB_DQS_DN<4>   
                                  239      M_F_CPU0_SB_DQS_DP<4>   
                                  240      GND                     
                                  241      M_F_CPU0_SB_CB<2>       
                                  242      GND                     
                                  243      M_F_CPU0_SB_CB<3>       
                                  244      GND                     
                                  245      M_F_CPU0_SB_DQ<2>       
                                  246      GND                     
                                  247      M_F_CPU0_SB_DQ<3>       
                                  248      GND                     
                                  249      M_F_CPU0_SB_DQS_DN<5>   
                                  250      M_F_CPU0_SB_DQS_DP<5>   
                                  251      GND                     
                                  252      M_F_CPU0_SB_DQ<6>       
                                  253      GND                     
                                  254      M_F_CPU0_SB_DQ<7>       
                                  255      GND                     
                                  256      M_F_CPU0_SB_DQ<10>      
                                  257      GND                     
                                  258      M_F_CPU0_SB_DQ<11>      
                                  259      GND                     
                                  260      M_F_CPU0_SB_DQS_DN<6>   
                                  261      M_F_CPU0_SB_DQS_DP<6>   
                                  262      GND                     
                                  263      M_F_CPU0_SB_DQ<14>      
                                  264      GND                     
                                  265      M_F_CPU0_SB_DQ<15>      
                                  266      GND                     
                                  267      M_F_CPU0_SB_DQ<18>      
                                  268      GND                     
                                  269      M_F_CPU0_SB_DQ<19>      
                                  270      GND                     
                                  271      M_F_CPU0_SB_DQS_DN<7>   
                                  272      M_F_CPU0_SB_DQS_DP<7>   
                                  273      GND                     
                                  274      M_F_CPU0_SB_DQ<22>      
                                  275      GND                     
                                  276      M_F_CPU0_SB_DQ<23>      
                                  277      GND                     
                                  278      M_F_CPU0_SB_DQ<26>      
                                  279      GND                     
                                  280      M_F_CPU0_SB_DQ<27>      
                                  281      GND                     
                                  282      M_F_CPU0_SB_DQS_DN<8>   
                                  283      M_F_CPU0_SB_DQS_DP<8>   
                                  284      GND                     
                                  285      M_F_CPU0_SB_DQ<30>      
                                  286      GND                     
                                  287      M_F_CPU0_SB_DQ<31>      
                                  288      GND                     
                                  G1       GND                     
                                  G2       GND                     
                                  G3       GND                     
J13              SCONN288_ADR50001P013C01-SCONNA 1        P12V_S3_AUX_CPU0_NVDIMM 
                                  3        P3V3_AUX                
                                  4        I3C_SPD_DDREFGH_CPU0_LVC1_SCL
                                  5        I3C_SPD_DDREFGH_CPU0_LVC1_SDA
                                  6        GND                     
                                  7        M_G_CPU0_SA_DQ<0>       
                                  8        GND                     
                                  9        M_G_CPU0_SA_DQ<1>       
                                  10       GND                     
                                  11       M_G_CPU0_SA_DQS_DP<0>   
                                  12       M_G_CPU0_SA_DQS_DN<0>   
                                  13       GND                     
                                  14       M_G_CPU0_SA_DQ<4>       
                                  15       GND                     
                                  16       M_G_CPU0_SA_DQ<5>       
                                  17       GND                     
                                  18       M_G_CPU0_SA_DQ<8>       
                                  19       GND                     
                                  20       M_G_CPU0_SA_DQ<9>       
                                  21       GND                     
                                  22       M_G_CPU0_SA_DQS_DP<1>   
                                  23       M_G_CPU0_SA_DQS_DN<1>   
                                  24       GND                     
                                  25       M_G_CPU0_SA_DQ<12>      
                                  26       GND                     
                                  27       M_G_CPU0_SA_DQ<13>      
                                  28       GND                     
                                  29       M_G_CPU0_SA_DQ<16>      
                                  30       GND                     
                                  31       M_G_CPU0_SA_DQ<17>      
                                  32       GND                     
                                  33       M_G_CPU0_SA_DQS_DP<2>   
                                  34       M_G_CPU0_SA_DQS_DN<2>   
                                  35       GND                     
                                  36       M_G_CPU0_SA_DQ<20>      
                                  37       GND                     
                                  38       M_G_CPU0_SA_DQ<21>      
                                  39       GND                     
                                  40       M_G_CPU0_SA_DQ<24>      
                                  41       GND                     
                                  42       M_G_CPU0_SA_DQ<25>      
                                  43       GND                     
                                  44       M_G_CPU0_SA_DQS_DP<3>   
                                  45       M_G_CPU0_SA_DQS_DN<3>   
                                  46       GND                     
                                  47       M_G_CPU0_SA_DQ<28>      
                                  48       GND                     
                                  49       M_G_CPU0_SA_DQ<29>      
                                  50       GND                     
                                  51       M_G_CPU0_SA_CB<0>       
                                  52       GND                     
                                  53       M_G_CPU0_SA_CB<1>       
                                  54       GND                     
                                  55       M_G_CPU0_SA_DQS_DP<4>   
                                  56       M_G_CPU0_SA_DQS_DN<4>   
                                  57       GND                     
                                  58       M_G_CPU0_SA_CB<4>       
                                  59       GND                     
                                  60       M_G_CPU0_SA_CB<5>       
                                  61       GND                     
                                  62       M_G_CPU0_ALERT_N        
                                  63       GND                     
                                  64       M_G_CPU0_SA_CS_N<0>     
                                  65       GND                     
                                  66       M_G_CPU0_SA_CA<0>       
                                  67       GND                     
                                  68       M_G_CPU0_SA_CA<2>       
                                  69       GND                     
                                  70       M_G_CPU0_SA_CA<4>       
                                  71       GND                     
                                  72       M_G_CPU0_SA_CA<6>       
                                  73       GND                     
                                  74       M_G_CPU0_SA_PAR         
                                  75       GND                     
                                  76       M_G_CPU0_SB_CA<0>       
                                  77       GND                     
                                  78       M_G_CPU0_SB_CA<2>       
                                  79       GND                     
                                  80       M_G_CPU0_SB_CA<4>       
                                  81       GND                     
                                  82       M_G_CPU0_SB_CA<6>       
                                  83       GND                     
                                  84       M_G_CPU0_SB_CS_N<0>     
                                  85       GND                     
                                  86       M_G_CPU0_SA_RSP<0>      
                                  87       M_G_CPU0_SB_RSP<0>      
                                  88       GND                     
                                  89       M_G_CPU0_SB_CB<4>       
                                  90       GND                     
                                  91       M_G_CPU0_SB_CB<5>       
                                  92       GND                     
                                  93       M_G_CPU0_SB_DQS_DP<9>   
                                  94       M_G_CPU0_SB_DQS_DN<9>   
                                  95       GND                     
                                  96       M_G_CPU0_SB_CB<0>       
                                  97       GND                     
                                  98       M_G_CPU0_SB_CB<1>       
                                  99       GND                     
                                  100      M_G_CPU0_SB_DQ<0>       
                                  101      GND                     
                                  102      M_G_CPU0_SB_DQ<1>       
                                  103      GND                     
                                  104      M_G_CPU0_SB_DQS_DP<0>   
                                  105      M_G_CPU0_SB_DQS_DN<0>   
                                  106      GND                     
                                  107      M_G_CPU0_SB_DQ<4>       
                                  108      GND                     
                                  109      M_G_CPU0_SB_DQ<5>       
                                  110      GND                     
                                  111      M_G_CPU0_SB_DQ<8>       
                                  112      GND                     
                                  113      M_G_CPU0_SB_DQ<9>       
                                  114      GND                     
                                  115      M_G_CPU0_SB_DQS_DP<1>   
                                  116      M_G_CPU0_SB_DQS_DN<1>   
                                  117      GND                     
                                  118      M_G_CPU0_SB_DQ<12>      
                                  119      GND                     
                                  120      M_G_CPU0_SB_DQ<13>      
                                  121      GND                     
                                  122      M_G_CPU0_SB_DQ<16>      
                                  123      GND                     
                                  124      M_G_CPU0_SB_DQ<17>      
                                  125      GND                     
                                  126      M_G_CPU0_SB_DQS_DP<2>   
                                  127      M_G_CPU0_SB_DQS_DN<2>   
                                  128      GND                     
                                  129      M_G_CPU0_SB_DQ<20>      
                                  130      GND                     
                                  131      M_G_CPU0_SB_DQ<21>      
                                  132      GND                     
                                  133      M_G_CPU0_SB_DQ<24>      
                                  134      GND                     
                                  135      M_G_CPU0_SB_DQ<25>      
                                  136      GND                     
                                  137      M_G_CPU0_SB_DQS_DP<3>   
                                  138      M_G_CPU0_SB_DQS_DN<3>   
                                  139      GND                     
                                  140      M_G_CPU0_SB_DQ<28>      
                                  141      GND                     
                                  142      M_G_CPU0_SB_DQ<29>      
                                  143      GND                     
                                  145      P12V_S3_AUX_CPU0_NVDIMM 
                                  146      P12V_S3_AUX_CPU0_NVDIMM 
                                  147      PWRGD_CHG_CPU0_DIMM1    
                                  148      PD_CHG_CPU0_DIMM1_SAA   
                                  151      GND                     
                                  152      M_G_CPU0_SA_DQ<2>       
                                  153      GND                     
                                  154      M_G_CPU0_SA_DQ<3>       
                                  155      GND                     
                                  156      M_G_CPU0_SA_DQS_DN<5>   
                                  157      M_G_CPU0_SA_DQS_DP<5>   
                                  158      GND                     
                                  159      M_G_CPU0_SA_DQ<6>       
                                  160      GND                     
                                  161      M_G_CPU0_SA_DQ<7>       
                                  162      GND                     
                                  163      M_G_CPU0_SA_DQ<10>      
                                  164      GND                     
                                  165      M_G_CPU0_SA_DQ<11>      
                                  166      GND                     
                                  167      M_G_CPU0_SA_DQS_DN<6>   
                                  168      M_G_CPU0_SA_DQS_DP<6>   
                                  169      GND                     
                                  170      M_G_CPU0_SA_DQ<14>      
                                  171      GND                     
                                  172      M_G_CPU0_SA_DQ<15>      
                                  173      GND                     
                                  174      M_G_CPU0_SA_DQ<18>      
                                  175      GND                     
                                  176      M_G_CPU0_SA_DQ<19>      
                                  177      GND                     
                                  178      M_G_CPU0_SA_DQS_DN<7>   
                                  179      M_G_CPU0_SA_DQS_DP<7>   
                                  180      GND                     
                                  181      M_G_CPU0_SA_DQ<22>      
                                  182      GND                     
                                  183      M_G_CPU0_SA_DQ<23>      
                                  184      GND                     
                                  185      M_G_CPU0_SA_DQ<26>      
                                  186      GND                     
                                  187      M_G_CPU0_SA_DQ<27>      
                                  188      GND                     
                                  189      M_G_CPU0_SA_DQS_DN<8>   
                                  190      M_G_CPU0_SA_DQS_DP<8>   
                                  191      GND                     
                                  192      M_G_CPU0_SA_DQ<30>      
                                  193      GND                     
                                  194      M_G_CPU0_SA_DQ<31>      
                                  195      GND                     
                                  196      M_G_CPU0_SA_CB<2>       
                                  197      GND                     
                                  198      M_G_CPU0_SA_CB<3>       
                                  199      GND                     
                                  200      M_G_CPU0_SA_DQS_DN<9>   
                                  201      M_G_CPU0_SA_DQS_DP<9>   
                                  202      GND                     
                                  203      M_G_CPU0_SA_CB<6>       
                                  204      GND                     
                                  205      M_G_CPU0_SA_CB<7>       
                                  206      GND                     
                                  207      RST_M_GH_CPU0_FPGA_N    
                                  208      GND                     
                                  209      M_G_CPU0_SA_CS_N<1>     
                                  210      GND                     
                                  211      M_G_CPU0_SA_CA<1>       
                                  212      GND                     
                                  213      M_G_CPU0_SA_CA<3>       
                                  214      GND                     
                                  215      M_G_CPU0_SA_CA<5>       
                                  216      GND                     
                                  217      M_G_CPU0_CLK_DP<0>      
                                  218      M_G_CPU0_CLK_DN<0>      
                                  219      GND                     
                                  221      M_G_CPU0_SB_CA<1>       
                                  222      GND                     
                                  223      M_G_CPU0_SB_CA<3>       
                                  224      GND                     
                                  225      M_G_CPU0_SB_CA<5>       
                                  226      GND                     
                                  227      M_G_CPU0_SB_PAR         
                                  228      GND                     
                                  229      M_G_CPU0_SB_CS_N<1>     
                                  230      GND                     
                                  233      GND                     
                                  234      M_G_CPU0_SB_CB<6>       
                                  235      GND                     
                                  236      M_G_CPU0_SB_CB<7>       
                                  237      GND                     
                                  238      M_G_CPU0_SB_DQS_DN<4>   
                                  239      M_G_CPU0_SB_DQS_DP<4>   
                                  240      GND                     
                                  241      M_G_CPU0_SB_CB<2>       
                                  242      GND                     
                                  243      M_G_CPU0_SB_CB<3>       
                                  244      GND                     
                                  245      M_G_CPU0_SB_DQ<2>       
                                  246      GND                     
                                  247      M_G_CPU0_SB_DQ<3>       
                                  248      GND                     
                                  249      M_G_CPU0_SB_DQS_DN<5>   
                                  250      M_G_CPU0_SB_DQS_DP<5>   
                                  251      GND                     
                                  252      M_G_CPU0_SB_DQ<6>       
                                  253      GND                     
                                  254      M_G_CPU0_SB_DQ<7>       
                                  255      GND                     
                                  256      M_G_CPU0_SB_DQ<10>      
                                  257      GND                     
                                  258      M_G_CPU0_SB_DQ<11>      
                                  259      GND                     
                                  260      M_G_CPU0_SB_DQS_DN<6>   
                                  261      M_G_CPU0_SB_DQS_DP<6>   
                                  262      GND                     
                                  263      M_G_CPU0_SB_DQ<14>      
                                  264      GND                     
                                  265      M_G_CPU0_SB_DQ<15>      
                                  266      GND                     
                                  267      M_G_CPU0_SB_DQ<18>      
                                  268      GND                     
                                  269      M_G_CPU0_SB_DQ<19>      
                                  270      GND                     
                                  271      M_G_CPU0_SB_DQS_DN<7>   
                                  272      M_G_CPU0_SB_DQS_DP<7>   
                                  273      GND                     
                                  274      M_G_CPU0_SB_DQ<22>      
                                  275      GND                     
                                  276      M_G_CPU0_SB_DQ<23>      
                                  277      GND                     
                                  278      M_G_CPU0_SB_DQ<26>      
                                  279      GND                     
                                  280      M_G_CPU0_SB_DQ<27>      
                                  281      GND                     
                                  282      M_G_CPU0_SB_DQS_DN<8>   
                                  283      M_G_CPU0_SB_DQS_DP<8>   
                                  284      GND                     
                                  285      M_G_CPU0_SB_DQ<30>      
                                  286      GND                     
                                  287      M_G_CPU0_SB_DQ<31>      
                                  288      GND                     
                                  G1       GND                     
                                  G2       GND                     
                                  G3       GND                     
J14              SCONN288_ADR50001P003C01-SCONNA 1        P12V_S3_AUX_CPU0_NVDIMM 
                                  3        P3V3_AUX                
                                  4        I3C_SPD_DDREFGH_CPU0_LVC1_SCL
                                  5        I3C_SPD_DDREFGH_CPU0_LVC1_SDA
                                  6        GND                     
                                  7        M_G_CPU0_SA_DQ<0>       
                                  8        GND                     
                                  9        M_G_CPU0_SA_DQ<1>       
                                  10       GND                     
                                  11       M_G_CPU0_SA_DQS_DP<0>   
                                  12       M_G_CPU0_SA_DQS_DN<0>   
                                  13       GND                     
                                  14       M_G_CPU0_SA_DQ<4>       
                                  15       GND                     
                                  16       M_G_CPU0_SA_DQ<5>       
                                  17       GND                     
                                  18       M_G_CPU0_SA_DQ<8>       
                                  19       GND                     
                                  20       M_G_CPU0_SA_DQ<9>       
                                  21       GND                     
                                  22       M_G_CPU0_SA_DQS_DP<1>   
                                  23       M_G_CPU0_SA_DQS_DN<1>   
                                  24       GND                     
                                  25       M_G_CPU0_SA_DQ<12>      
                                  26       GND                     
                                  27       M_G_CPU0_SA_DQ<13>      
                                  28       GND                     
                                  29       M_G_CPU0_SA_DQ<16>      
                                  30       GND                     
                                  31       M_G_CPU0_SA_DQ<17>      
                                  32       GND                     
                                  33       M_G_CPU0_SA_DQS_DP<2>   
                                  34       M_G_CPU0_SA_DQS_DN<2>   
                                  35       GND                     
                                  36       M_G_CPU0_SA_DQ<20>      
                                  37       GND                     
                                  38       M_G_CPU0_SA_DQ<21>      
                                  39       GND                     
                                  40       M_G_CPU0_SA_DQ<24>      
                                  41       GND                     
                                  42       M_G_CPU0_SA_DQ<25>      
                                  43       GND                     
                                  44       M_G_CPU0_SA_DQS_DP<3>   
                                  45       M_G_CPU0_SA_DQS_DN<3>   
                                  46       GND                     
                                  47       M_G_CPU0_SA_DQ<28>      
                                  48       GND                     
                                  49       M_G_CPU0_SA_DQ<29>      
                                  50       GND                     
                                  51       M_G_CPU0_SA_CB<0>       
                                  52       GND                     
                                  53       M_G_CPU0_SA_CB<1>       
                                  54       GND                     
                                  55       M_G_CPU0_SA_DQS_DP<4>   
                                  56       M_G_CPU0_SA_DQS_DN<4>   
                                  57       GND                     
                                  58       M_G_CPU0_SA_CB<4>       
                                  59       GND                     
                                  60       M_G_CPU0_SA_CB<5>       
                                  61       GND                     
                                  62       M_G_CPU0_ALERT_N        
                                  63       GND                     
                                  64       M_G_CPU0_SA_CS_N<2>     
                                  65       GND                     
                                  66       M_G_CPU0_SA_CA<0>       
                                  67       GND                     
                                  68       M_G_CPU0_SA_CA<2>       
                                  69       GND                     
                                  70       M_G_CPU0_SA_CA<4>       
                                  71       GND                     
                                  72       M_G_CPU0_SA_CA<6>       
                                  73       GND                     
                                  74       M_G_CPU0_SA_PAR         
                                  75       GND                     
                                  76       M_G_CPU0_SB_CA<0>       
                                  77       GND                     
                                  78       M_G_CPU0_SB_CA<2>       
                                  79       GND                     
                                  80       M_G_CPU0_SB_CA<4>       
                                  81       GND                     
                                  82       M_G_CPU0_SB_CA<6>       
                                  83       GND                     
                                  84       M_G_CPU0_SB_CS_N<2>     
                                  85       GND                     
                                  86       M_G_CPU0_SA_RSP<1>      
                                  87       M_G_CPU0_SB_RSP<1>      
                                  88       GND                     
                                  89       M_G_CPU0_SB_CB<4>       
                                  90       GND                     
                                  91       M_G_CPU0_SB_CB<5>       
                                  92       GND                     
                                  93       M_G_CPU0_SB_DQS_DP<9>   
                                  94       M_G_CPU0_SB_DQS_DN<9>   
                                  95       GND                     
                                  96       M_G_CPU0_SB_CB<0>       
                                  97       GND                     
                                  98       M_G_CPU0_SB_CB<1>       
                                  99       GND                     
                                  100      M_G_CPU0_SB_DQ<0>       
                                  101      GND                     
                                  102      M_G_CPU0_SB_DQ<1>       
                                  103      GND                     
                                  104      M_G_CPU0_SB_DQS_DP<0>   
                                  105      M_G_CPU0_SB_DQS_DN<0>   
                                  106      GND                     
                                  107      M_G_CPU0_SB_DQ<4>       
                                  108      GND                     
                                  109      M_G_CPU0_SB_DQ<5>       
                                  110      GND                     
                                  111      M_G_CPU0_SB_DQ<8>       
                                  112      GND                     
                                  113      M_G_CPU0_SB_DQ<9>       
                                  114      GND                     
                                  115      M_G_CPU0_SB_DQS_DP<1>   
                                  116      M_G_CPU0_SB_DQS_DN<1>   
                                  117      GND                     
                                  118      M_G_CPU0_SB_DQ<12>      
                                  119      GND                     
                                  120      M_G_CPU0_SB_DQ<13>      
                                  121      GND                     
                                  122      M_G_CPU0_SB_DQ<16>      
                                  123      GND                     
                                  124      M_G_CPU0_SB_DQ<17>      
                                  125      GND                     
                                  126      M_G_CPU0_SB_DQS_DP<2>   
                                  127      M_G_CPU0_SB_DQS_DN<2>   
                                  128      GND                     
                                  129      M_G_CPU0_SB_DQ<20>      
                                  130      GND                     
                                  131      M_G_CPU0_SB_DQ<21>      
                                  132      GND                     
                                  133      M_G_CPU0_SB_DQ<24>      
                                  134      GND                     
                                  135      M_G_CPU0_SB_DQ<25>      
                                  136      GND                     
                                  137      M_G_CPU0_SB_DQS_DP<3>   
                                  138      M_G_CPU0_SB_DQS_DN<3>   
                                  139      GND                     
                                  140      M_G_CPU0_SB_DQ<28>      
                                  141      GND                     
                                  142      M_G_CPU0_SB_DQ<29>      
                                  143      GND                     
                                  145      P12V_S3_AUX_CPU0_NVDIMM 
                                  146      P12V_S3_AUX_CPU0_NVDIMM 
                                  147      PWRGD_CHG_CPU0_DIMM2    
                                  148      PD_CHG_CPU0_DIMM2_SAA   
                                  151      GND                     
                                  152      M_G_CPU0_SA_DQ<2>       
                                  153      GND                     
                                  154      M_G_CPU0_SA_DQ<3>       
                                  155      GND                     
                                  156      M_G_CPU0_SA_DQS_DN<5>   
                                  157      M_G_CPU0_SA_DQS_DP<5>   
                                  158      GND                     
                                  159      M_G_CPU0_SA_DQ<6>       
                                  160      GND                     
                                  161      M_G_CPU0_SA_DQ<7>       
                                  162      GND                     
                                  163      M_G_CPU0_SA_DQ<10>      
                                  164      GND                     
                                  165      M_G_CPU0_SA_DQ<11>      
                                  166      GND                     
                                  167      M_G_CPU0_SA_DQS_DN<6>   
                                  168      M_G_CPU0_SA_DQS_DP<6>   
                                  169      GND                     
                                  170      M_G_CPU0_SA_DQ<14>      
                                  171      GND                     
                                  172      M_G_CPU0_SA_DQ<15>      
                                  173      GND                     
                                  174      M_G_CPU0_SA_DQ<18>      
                                  175      GND                     
                                  176      M_G_CPU0_SA_DQ<19>      
                                  177      GND                     
                                  178      M_G_CPU0_SA_DQS_DN<7>   
                                  179      M_G_CPU0_SA_DQS_DP<7>   
                                  180      GND                     
                                  181      M_G_CPU0_SA_DQ<22>      
                                  182      GND                     
                                  183      M_G_CPU0_SA_DQ<23>      
                                  184      GND                     
                                  185      M_G_CPU0_SA_DQ<26>      
                                  186      GND                     
                                  187      M_G_CPU0_SA_DQ<27>      
                                  188      GND                     
                                  189      M_G_CPU0_SA_DQS_DN<8>   
                                  190      M_G_CPU0_SA_DQS_DP<8>   
                                  191      GND                     
                                  192      M_G_CPU0_SA_DQ<30>      
                                  193      GND                     
                                  194      M_G_CPU0_SA_DQ<31>      
                                  195      GND                     
                                  196      M_G_CPU0_SA_CB<2>       
                                  197      GND                     
                                  198      M_G_CPU0_SA_CB<3>       
                                  199      GND                     
                                  200      M_G_CPU0_SA_DQS_DN<9>   
                                  201      M_G_CPU0_SA_DQS_DP<9>   
                                  202      GND                     
                                  203      M_G_CPU0_SA_CB<6>       
                                  204      GND                     
                                  205      M_G_CPU0_SA_CB<7>       
                                  206      GND                     
                                  207      RST_M_GH_CPU0_FPGA_N    
                                  208      GND                     
                                  209      M_G_CPU0_SA_CS_N<3>     
                                  210      GND                     
                                  211      M_G_CPU0_SA_CA<1>       
                                  212      GND                     
                                  213      M_G_CPU0_SA_CA<3>       
                                  214      GND                     
                                  215      M_G_CPU0_SA_CA<5>       
                                  216      GND                     
                                  217      M_G_CPU0_CLK_DP<1>      
                                  218      M_G_CPU0_CLK_DN<1>      
                                  219      GND                     
                                  221      M_G_CPU0_SB_CA<1>       
                                  222      GND                     
                                  223      M_G_CPU0_SB_CA<3>       
                                  224      GND                     
                                  225      M_G_CPU0_SB_CA<5>       
                                  226      GND                     
                                  227      M_G_CPU0_SB_PAR         
                                  228      GND                     
                                  229      M_G_CPU0_SB_CS_N<3>     
                                  230      GND                     
                                  233      GND                     
                                  234      M_G_CPU0_SB_CB<6>       
                                  235      GND                     
                                  236      M_G_CPU0_SB_CB<7>       
                                  237      GND                     
                                  238      M_G_CPU0_SB_DQS_DN<4>   
                                  239      M_G_CPU0_SB_DQS_DP<4>   
                                  240      GND                     
                                  241      M_G_CPU0_SB_CB<2>       
                                  242      GND                     
                                  243      M_G_CPU0_SB_CB<3>       
                                  244      GND                     
                                  245      M_G_CPU0_SB_DQ<2>       
                                  246      GND                     
                                  247      M_G_CPU0_SB_DQ<3>       
                                  248      GND                     
                                  249      M_G_CPU0_SB_DQS_DN<5>   
                                  250      M_G_CPU0_SB_DQS_DP<5>   
                                  251      GND                     
                                  252      M_G_CPU0_SB_DQ<6>       
                                  253      GND                     
                                  254      M_G_CPU0_SB_DQ<7>       
                                  255      GND                     
                                  256      M_G_CPU0_SB_DQ<10>      
                                  257      GND                     
                                  258      M_G_CPU0_SB_DQ<11>      
                                  259      GND                     
                                  260      M_G_CPU0_SB_DQS_DN<6>   
                                  261      M_G_CPU0_SB_DQS_DP<6>   
                                  262      GND                     
                                  263      M_G_CPU0_SB_DQ<14>      
                                  264      GND                     
                                  265      M_G_CPU0_SB_DQ<15>      
                                  266      GND                     
                                  267      M_G_CPU0_SB_DQ<18>      
                                  268      GND                     
                                  269      M_G_CPU0_SB_DQ<19>      
                                  270      GND                     
                                  271      M_G_CPU0_SB_DQS_DN<7>   
                                  272      M_G_CPU0_SB_DQS_DP<7>   
                                  273      GND                     
                                  274      M_G_CPU0_SB_DQ<22>      
                                  275      GND                     
                                  276      M_G_CPU0_SB_DQ<23>      
                                  277      GND                     
                                  278      M_G_CPU0_SB_DQ<26>      
                                  279      GND                     
                                  280      M_G_CPU0_SB_DQ<27>      
                                  281      GND                     
                                  282      M_G_CPU0_SB_DQS_DN<8>   
                                  283      M_G_CPU0_SB_DQS_DP<8>   
                                  284      GND                     
                                  285      M_G_CPU0_SB_DQ<30>      
                                  286      GND                     
                                  287      M_G_CPU0_SB_DQ<31>      
                                  288      GND                     
                                  G1       GND                     
                                  G2       GND                     
                                  G3       GND                     
J15              SCONN288_ADR50001P013C01-SCONNA 1        P12V_S3_AUX_CPU0_NVDIMM 
                                  3        P3V3_AUX                
                                  4        I3C_SPD_DDREFGH_CPU0_LVC1_SCL
                                  5        I3C_SPD_DDREFGH_CPU0_LVC1_SDA
                                  6        GND                     
                                  7        M_H_CPU0_SA_DQ<0>       
                                  8        GND                     
                                  9        M_H_CPU0_SA_DQ<1>       
                                  10       GND                     
                                  11       M_H_CPU0_SA_DQS_DP<0>   
                                  12       M_H_CPU0_SA_DQS_DN<0>   
                                  13       GND                     
                                  14       M_H_CPU0_SA_DQ<4>       
                                  15       GND                     
                                  16       M_H_CPU0_SA_DQ<5>       
                                  17       GND                     
                                  18       M_H_CPU0_SA_DQ<8>       
                                  19       GND                     
                                  20       M_H_CPU0_SA_DQ<9>       
                                  21       GND                     
                                  22       M_H_CPU0_SA_DQS_DP<1>   
                                  23       M_H_CPU0_SA_DQS_DN<1>   
                                  24       GND                     
                                  25       M_H_CPU0_SA_DQ<12>      
                                  26       GND                     
                                  27       M_H_CPU0_SA_DQ<13>      
                                  28       GND                     
                                  29       M_H_CPU0_SA_DQ<16>      
                                  30       GND                     
                                  31       M_H_CPU0_SA_DQ<17>      
                                  32       GND                     
                                  33       M_H_CPU0_SA_DQS_DP<2>   
                                  34       M_H_CPU0_SA_DQS_DN<2>   
                                  35       GND                     
                                  36       M_H_CPU0_SA_DQ<20>      
                                  37       GND                     
                                  38       M_H_CPU0_SA_DQ<21>      
                                  39       GND                     
                                  40       M_H_CPU0_SA_DQ<24>      
                                  41       GND                     
                                  42       M_H_CPU0_SA_DQ<25>      
                                  43       GND                     
                                  44       M_H_CPU0_SA_DQS_DP<3>   
                                  45       M_H_CPU0_SA_DQS_DN<3>   
                                  46       GND                     
                                  47       M_H_CPU0_SA_DQ<28>      
                                  48       GND                     
                                  49       M_H_CPU0_SA_DQ<29>      
                                  50       GND                     
                                  51       M_H_CPU0_SA_CB<0>       
                                  52       GND                     
                                  53       M_H_CPU0_SA_CB<1>       
                                  54       GND                     
                                  55       M_H_CPU0_SA_DQS_DP<4>   
                                  56       M_H_CPU0_SA_DQS_DN<4>   
                                  57       GND                     
                                  58       M_H_CPU0_SA_CB<4>       
                                  59       GND                     
                                  60       M_H_CPU0_SA_CB<5>       
                                  61       GND                     
                                  62       M_H_CPU0_ALERT_N        
                                  63       GND                     
                                  64       M_H_CPU0_SA_CS_N<0>     
                                  65       GND                     
                                  66       M_H_CPU0_SA_CA<0>       
                                  67       GND                     
                                  68       M_H_CPU0_SA_CA<2>       
                                  69       GND                     
                                  70       M_H_CPU0_SA_CA<4>       
                                  71       GND                     
                                  72       M_H_CPU0_SA_CA<6>       
                                  73       GND                     
                                  74       M_H_CPU0_SA_PAR         
                                  75       GND                     
                                  76       M_H_CPU0_SB_CA<0>       
                                  77       GND                     
                                  78       M_H_CPU0_SB_CA<2>       
                                  79       GND                     
                                  80       M_H_CPU0_SB_CA<4>       
                                  81       GND                     
                                  82       M_H_CPU0_SB_CA<6>       
                                  83       GND                     
                                  84       M_H_CPU0_SB_CS_N<0>     
                                  85       GND                     
                                  86       M_H_CPU0_SA_RSP<0>      
                                  87       M_H_CPU0_SB_RSP<0>      
                                  88       GND                     
                                  89       M_H_CPU0_SB_CB<4>       
                                  90       GND                     
                                  91       M_H_CPU0_SB_CB<5>       
                                  92       GND                     
                                  93       M_H_CPU0_SB_DQS_DP<9>   
                                  94       M_H_CPU0_SB_DQS_DN<9>   
                                  95       GND                     
                                  96       M_H_CPU0_SB_CB<0>       
                                  97       GND                     
                                  98       M_H_CPU0_SB_CB<1>       
                                  99       GND                     
                                  100      M_H_CPU0_SB_DQ<0>       
                                  101      GND                     
                                  102      M_H_CPU0_SB_DQ<1>       
                                  103      GND                     
                                  104      M_H_CPU0_SB_DQS_DP<0>   
                                  105      M_H_CPU0_SB_DQS_DN<0>   
                                  106      GND                     
                                  107      M_H_CPU0_SB_DQ<4>       
                                  108      GND                     
                                  109      M_H_CPU0_SB_DQ<5>       
                                  110      GND                     
                                  111      M_H_CPU0_SB_DQ<8>       
                                  112      GND                     
                                  113      M_H_CPU0_SB_DQ<9>       
                                  114      GND                     
                                  115      M_H_CPU0_SB_DQS_DP<1>   
                                  116      M_H_CPU0_SB_DQS_DN<1>   
                                  117      GND                     
                                  118      M_H_CPU0_SB_DQ<12>      
                                  119      GND                     
                                  120      M_H_CPU0_SB_DQ<13>      
                                  121      GND                     
                                  122      M_H_CPU0_SB_DQ<16>      
                                  123      GND                     
                                  124      M_H_CPU0_SB_DQ<17>      
                                  125      GND                     
                                  126      M_H_CPU0_SB_DQS_DP<2>   
                                  127      M_H_CPU0_SB_DQS_DN<2>   
                                  128      GND                     
                                  129      M_H_CPU0_SB_DQ<20>      
                                  130      GND                     
                                  131      M_H_CPU0_SB_DQ<21>      
                                  132      GND                     
                                  133      M_H_CPU0_SB_DQ<24>      
                                  134      GND                     
                                  135      M_H_CPU0_SB_DQ<25>      
                                  136      GND                     
                                  137      M_H_CPU0_SB_DQS_DP<3>   
                                  138      M_H_CPU0_SB_DQS_DN<3>   
                                  139      GND                     
                                  140      M_H_CPU0_SB_DQ<28>      
                                  141      GND                     
                                  142      M_H_CPU0_SB_DQ<29>      
                                  143      GND                     
                                  145      P12V_S3_AUX_CPU0_NVDIMM 
                                  146      P12V_S3_AUX_CPU0_NVDIMM 
                                  147      PWRGD_CHH_CPU0_DIMM1    
                                  148      PD_CHH_CPU0_DIMM1_SAA   
                                  151      GND                     
                                  152      M_H_CPU0_SA_DQ<2>       
                                  153      GND                     
                                  154      M_H_CPU0_SA_DQ<3>       
                                  155      GND                     
                                  156      M_H_CPU0_SA_DQS_DN<5>   
                                  157      M_H_CPU0_SA_DQS_DP<5>   
                                  158      GND                     
                                  159      M_H_CPU0_SA_DQ<6>       
                                  160      GND                     
                                  161      M_H_CPU0_SA_DQ<7>       
                                  162      GND                     
                                  163      M_H_CPU0_SA_DQ<10>      
                                  164      GND                     
                                  165      M_H_CPU0_SA_DQ<11>      
                                  166      GND                     
                                  167      M_H_CPU0_SA_DQS_DN<6>   
                                  168      M_H_CPU0_SA_DQS_DP<6>   
                                  169      GND                     
                                  170      M_H_CPU0_SA_DQ<14>      
                                  171      GND                     
                                  172      M_H_CPU0_SA_DQ<15>      
                                  173      GND                     
                                  174      M_H_CPU0_SA_DQ<18>      
                                  175      GND                     
                                  176      M_H_CPU0_SA_DQ<19>      
                                  177      GND                     
                                  178      M_H_CPU0_SA_DQS_DN<7>   
                                  179      M_H_CPU0_SA_DQS_DP<7>   
                                  180      GND                     
                                  181      M_H_CPU0_SA_DQ<22>      
                                  182      GND                     
                                  183      M_H_CPU0_SA_DQ<23>      
                                  184      GND                     
                                  185      M_H_CPU0_SA_DQ<26>      
                                  186      GND                     
                                  187      M_H_CPU0_SA_DQ<27>      
                                  188      GND                     
                                  189      M_H_CPU0_SA_DQS_DN<8>   
                                  190      M_H_CPU0_SA_DQS_DP<8>   
                                  191      GND                     
                                  192      M_H_CPU0_SA_DQ<30>      
                                  193      GND                     
                                  194      M_H_CPU0_SA_DQ<31>      
                                  195      GND                     
                                  196      M_H_CPU0_SA_CB<2>       
                                  197      GND                     
                                  198      M_H_CPU0_SA_CB<3>       
                                  199      GND                     
                                  200      M_H_CPU0_SA_DQS_DN<9>   
                                  201      M_H_CPU0_SA_DQS_DP<9>   
                                  202      GND                     
                                  203      M_H_CPU0_SA_CB<6>       
                                  204      GND                     
                                  205      M_H_CPU0_SA_CB<7>       
                                  206      GND                     
                                  207      RST_M_GH_CPU0_FPGA_N    
                                  208      GND                     
                                  209      M_H_CPU0_SA_CS_N<1>     
                                  210      GND                     
                                  211      M_H_CPU0_SA_CA<1>       
                                  212      GND                     
                                  213      M_H_CPU0_SA_CA<3>       
                                  214      GND                     
                                  215      M_H_CPU0_SA_CA<5>       
                                  216      GND                     
                                  217      M_H_CPU0_CLK_DP<0>      
                                  218      M_H_CPU0_CLK_DN<0>      
                                  219      GND                     
                                  221      M_H_CPU0_SB_CA<1>       
                                  222      GND                     
                                  223      M_H_CPU0_SB_CA<3>       
                                  224      GND                     
                                  225      M_H_CPU0_SB_CA<5>       
                                  226      GND                     
                                  227      M_H_CPU0_SB_PAR         
                                  228      GND                     
                                  229      M_H_CPU0_SB_CS_N<1>     
                                  230      GND                     
                                  233      GND                     
                                  234      M_H_CPU0_SB_CB<6>       
                                  235      GND                     
                                  236      M_H_CPU0_SB_CB<7>       
                                  237      GND                     
                                  238      M_H_CPU0_SB_DQS_DN<4>   
                                  239      M_H_CPU0_SB_DQS_DP<4>   
                                  240      GND                     
                                  241      M_H_CPU0_SB_CB<2>       
                                  242      GND                     
                                  243      M_H_CPU0_SB_CB<3>       
                                  244      GND                     
                                  245      M_H_CPU0_SB_DQ<2>       
                                  246      GND                     
                                  247      M_H_CPU0_SB_DQ<3>       
                                  248      GND                     
                                  249      M_H_CPU0_SB_DQS_DN<5>   
                                  250      M_H_CPU0_SB_DQS_DP<5>   
                                  251      GND                     
                                  252      M_H_CPU0_SB_DQ<6>       
                                  253      GND                     
                                  254      M_H_CPU0_SB_DQ<7>       
                                  255      GND                     
                                  256      M_H_CPU0_SB_DQ<10>      
                                  257      GND                     
                                  258      M_H_CPU0_SB_DQ<11>      
                                  259      GND                     
                                  260      M_H_CPU0_SB_DQS_DN<6>   
                                  261      M_H_CPU0_SB_DQS_DP<6>   
                                  262      GND                     
                                  263      M_H_CPU0_SB_DQ<14>      
                                  264      GND                     
                                  265      M_H_CPU0_SB_DQ<15>      
                                  266      GND                     
                                  267      M_H_CPU0_SB_DQ<18>      
                                  268      GND                     
                                  269      M_H_CPU0_SB_DQ<19>      
                                  270      GND                     
                                  271      M_H_CPU0_SB_DQS_DN<7>   
                                  272      M_H_CPU0_SB_DQS_DP<7>   
                                  273      GND                     
                                  274      M_H_CPU0_SB_DQ<22>      
                                  275      GND                     
                                  276      M_H_CPU0_SB_DQ<23>      
                                  277      GND                     
                                  278      M_H_CPU0_SB_DQ<26>      
                                  279      GND                     
                                  280      M_H_CPU0_SB_DQ<27>      
                                  281      GND                     
                                  282      M_H_CPU0_SB_DQS_DN<8>   
                                  283      M_H_CPU0_SB_DQS_DP<8>   
                                  284      GND                     
                                  285      M_H_CPU0_SB_DQ<30>      
                                  286      GND                     
                                  287      M_H_CPU0_SB_DQ<31>      
                                  288      GND                     
                                  G1       GND                     
                                  G2       GND                     
                                  G3       GND                     
J16              SCONN288_ADR50001P003C01-SCONNA 1        P12V_S3_AUX_CPU0_NVDIMM 
                                  3        P3V3_AUX                
                                  4        I3C_SPD_DDREFGH_CPU0_LVC1_SCL
                                  5        I3C_SPD_DDREFGH_CPU0_LVC1_SDA
                                  6        GND                     
                                  7        M_H_CPU0_SA_DQ<0>       
                                  8        GND                     
                                  9        M_H_CPU0_SA_DQ<1>       
                                  10       GND                     
                                  11       M_H_CPU0_SA_DQS_DP<0>   
                                  12       M_H_CPU0_SA_DQS_DN<0>   
                                  13       GND                     
                                  14       M_H_CPU0_SA_DQ<4>       
                                  15       GND                     
                                  16       M_H_CPU0_SA_DQ<5>       
                                  17       GND                     
                                  18       M_H_CPU0_SA_DQ<8>       
                                  19       GND                     
                                  20       M_H_CPU0_SA_DQ<9>       
                                  21       GND                     
                                  22       M_H_CPU0_SA_DQS_DP<1>   
                                  23       M_H_CPU0_SA_DQS_DN<1>   
                                  24       GND                     
                                  25       M_H_CPU0_SA_DQ<12>      
                                  26       GND                     
                                  27       M_H_CPU0_SA_DQ<13>      
                                  28       GND                     
                                  29       M_H_CPU0_SA_DQ<16>      
                                  30       GND                     
                                  31       M_H_CPU0_SA_DQ<17>      
                                  32       GND                     
                                  33       M_H_CPU0_SA_DQS_DP<2>   
                                  34       M_H_CPU0_SA_DQS_DN<2>   
                                  35       GND                     
                                  36       M_H_CPU0_SA_DQ<20>      
                                  37       GND                     
                                  38       M_H_CPU0_SA_DQ<21>      
                                  39       GND                     
                                  40       M_H_CPU0_SA_DQ<24>      
                                  41       GND                     
                                  42       M_H_CPU0_SA_DQ<25>      
                                  43       GND                     
                                  44       M_H_CPU0_SA_DQS_DP<3>   
                                  45       M_H_CPU0_SA_DQS_DN<3>   
                                  46       GND                     
                                  47       M_H_CPU0_SA_DQ<28>      
                                  48       GND                     
                                  49       M_H_CPU0_SA_DQ<29>      
                                  50       GND                     
                                  51       M_H_CPU0_SA_CB<0>       
                                  52       GND                     
                                  53       M_H_CPU0_SA_CB<1>       
                                  54       GND                     
                                  55       M_H_CPU0_SA_DQS_DP<4>   
                                  56       M_H_CPU0_SA_DQS_DN<4>   
                                  57       GND                     
                                  58       M_H_CPU0_SA_CB<4>       
                                  59       GND                     
                                  60       M_H_CPU0_SA_CB<5>       
                                  61       GND                     
                                  62       M_H_CPU0_ALERT_N        
                                  63       GND                     
                                  64       M_H_CPU0_SA_CS_N<2>     
                                  65       GND                     
                                  66       M_H_CPU0_SA_CA<0>       
                                  67       GND                     
                                  68       M_H_CPU0_SA_CA<2>       
                                  69       GND                     
                                  70       M_H_CPU0_SA_CA<4>       
                                  71       GND                     
                                  72       M_H_CPU0_SA_CA<6>       
                                  73       GND                     
                                  74       M_H_CPU0_SA_PAR         
                                  75       GND                     
                                  76       M_H_CPU0_SB_CA<0>       
                                  77       GND                     
                                  78       M_H_CPU0_SB_CA<2>       
                                  79       GND                     
                                  80       M_H_CPU0_SB_CA<4>       
                                  81       GND                     
                                  82       M_H_CPU0_SB_CA<6>       
                                  83       GND                     
                                  84       M_H_CPU0_SB_CS_N<2>     
                                  85       GND                     
                                  86       M_H_CPU0_SA_RSP<1>      
                                  87       M_H_CPU0_SB_RSP<1>      
                                  88       GND                     
                                  89       M_H_CPU0_SB_CB<4>       
                                  90       GND                     
                                  91       M_H_CPU0_SB_CB<5>       
                                  92       GND                     
                                  93       M_H_CPU0_SB_DQS_DP<9>   
                                  94       M_H_CPU0_SB_DQS_DN<9>   
                                  95       GND                     
                                  96       M_H_CPU0_SB_CB<0>       
                                  97       GND                     
                                  98       M_H_CPU0_SB_CB<1>       
                                  99       GND                     
                                  100      M_H_CPU0_SB_DQ<0>       
                                  101      GND                     
                                  102      M_H_CPU0_SB_DQ<1>       
                                  103      GND                     
                                  104      M_H_CPU0_SB_DQS_DP<0>   
                                  105      M_H_CPU0_SB_DQS_DN<0>   
                                  106      GND                     
                                  107      M_H_CPU0_SB_DQ<4>       
                                  108      GND                     
                                  109      M_H_CPU0_SB_DQ<5>       
                                  110      GND                     
                                  111      M_H_CPU0_SB_DQ<8>       
                                  112      GND                     
                                  113      M_H_CPU0_SB_DQ<9>       
                                  114      GND                     
                                  115      M_H_CPU0_SB_DQS_DP<1>   
                                  116      M_H_CPU0_SB_DQS_DN<1>   
                                  117      GND                     
                                  118      M_H_CPU0_SB_DQ<12>      
                                  119      GND                     
                                  120      M_H_CPU0_SB_DQ<13>      
                                  121      GND                     
                                  122      M_H_CPU0_SB_DQ<16>      
                                  123      GND                     
                                  124      M_H_CPU0_SB_DQ<17>      
                                  125      GND                     
                                  126      M_H_CPU0_SB_DQS_DP<2>   
                                  127      M_H_CPU0_SB_DQS_DN<2>   
                                  128      GND                     
                                  129      M_H_CPU0_SB_DQ<20>      
                                  130      GND                     
                                  131      M_H_CPU0_SB_DQ<21>      
                                  132      GND                     
                                  133      M_H_CPU0_SB_DQ<24>      
                                  134      GND                     
                                  135      M_H_CPU0_SB_DQ<25>      
                                  136      GND                     
                                  137      M_H_CPU0_SB_DQS_DP<3>   
                                  138      M_H_CPU0_SB_DQS_DN<3>   
                                  139      GND                     
                                  140      M_H_CPU0_SB_DQ<28>      
                                  141      GND                     
                                  142      M_H_CPU0_SB_DQ<29>      
                                  143      GND                     
                                  145      P12V_S3_AUX_CPU0_NVDIMM 
                                  146      P12V_S3_AUX_CPU0_NVDIMM 
                                  147      PWRGD_CHH_CPU0_DIMM2    
                                  148      PD_CHH_CPU0_DIMM2_SAA   
                                  151      GND                     
                                  152      M_H_CPU0_SA_DQ<2>       
                                  153      GND                     
                                  154      M_H_CPU0_SA_DQ<3>       
                                  155      GND                     
                                  156      M_H_CPU0_SA_DQS_DN<5>   
                                  157      M_H_CPU0_SA_DQS_DP<5>   
                                  158      GND                     
                                  159      M_H_CPU0_SA_DQ<6>       
                                  160      GND                     
                                  161      M_H_CPU0_SA_DQ<7>       
                                  162      GND                     
                                  163      M_H_CPU0_SA_DQ<10>      
                                  164      GND                     
                                  165      M_H_CPU0_SA_DQ<11>      
                                  166      GND                     
                                  167      M_H_CPU0_SA_DQS_DN<6>   
                                  168      M_H_CPU0_SA_DQS_DP<6>   
                                  169      GND                     
                                  170      M_H_CPU0_SA_DQ<14>      
                                  171      GND                     
                                  172      M_H_CPU0_SA_DQ<15>      
                                  173      GND                     
                                  174      M_H_CPU0_SA_DQ<18>      
                                  175      GND                     
                                  176      M_H_CPU0_SA_DQ<19>      
                                  177      GND                     
                                  178      M_H_CPU0_SA_DQS_DN<7>   
                                  179      M_H_CPU0_SA_DQS_DP<7>   
                                  180      GND                     
                                  181      M_H_CPU0_SA_DQ<22>      
                                  182      GND                     
                                  183      M_H_CPU0_SA_DQ<23>      
                                  184      GND                     
                                  185      M_H_CPU0_SA_DQ<26>      
                                  186      GND                     
                                  187      M_H_CPU0_SA_DQ<27>      
                                  188      GND                     
                                  189      M_H_CPU0_SA_DQS_DN<8>   
                                  190      M_H_CPU0_SA_DQS_DP<8>   
                                  191      GND                     
                                  192      M_H_CPU0_SA_DQ<30>      
                                  193      GND                     
                                  194      M_H_CPU0_SA_DQ<31>      
                                  195      GND                     
                                  196      M_H_CPU0_SA_CB<2>       
                                  197      GND                     
                                  198      M_H_CPU0_SA_CB<3>       
                                  199      GND                     
                                  200      M_H_CPU0_SA_DQS_DN<9>   
                                  201      M_H_CPU0_SA_DQS_DP<9>   
                                  202      GND                     
                                  203      M_H_CPU0_SA_CB<6>       
                                  204      GND                     
                                  205      M_H_CPU0_SA_CB<7>       
                                  206      GND                     
                                  207      RST_M_GH_CPU0_FPGA_N    
                                  208      GND                     
                                  209      M_H_CPU0_SA_CS_N<3>     
                                  210      GND                     
                                  211      M_H_CPU0_SA_CA<1>       
                                  212      GND                     
                                  213      M_H_CPU0_SA_CA<3>       
                                  214      GND                     
                                  215      M_H_CPU0_SA_CA<5>       
                                  216      GND                     
                                  217      M_H_CPU0_CLK_DP<1>      
                                  218      M_H_CPU0_CLK_DN<1>      
                                  219      GND                     
                                  221      M_H_CPU0_SB_CA<1>       
                                  222      GND                     
                                  223      M_H_CPU0_SB_CA<3>       
                                  224      GND                     
                                  225      M_H_CPU0_SB_CA<5>       
                                  226      GND                     
                                  227      M_H_CPU0_SB_PAR         
                                  228      GND                     
                                  229      M_H_CPU0_SB_CS_N<3>     
                                  230      GND                     
                                  233      GND                     
                                  234      M_H_CPU0_SB_CB<6>       
                                  235      GND                     
                                  236      M_H_CPU0_SB_CB<7>       
                                  237      GND                     
                                  238      M_H_CPU0_SB_DQS_DN<4>   
                                  239      M_H_CPU0_SB_DQS_DP<4>   
                                  240      GND                     
                                  241      M_H_CPU0_SB_CB<2>       
                                  242      GND                     
                                  243      M_H_CPU0_SB_CB<3>       
                                  244      GND                     
                                  245      M_H_CPU0_SB_DQ<2>       
                                  246      GND                     
                                  247      M_H_CPU0_SB_DQ<3>       
                                  248      GND                     
                                  249      M_H_CPU0_SB_DQS_DN<5>   
                                  250      M_H_CPU0_SB_DQS_DP<5>   
                                  251      GND                     
                                  252      M_H_CPU0_SB_DQ<6>       
                                  253      GND                     
                                  254      M_H_CPU0_SB_DQ<7>       
                                  255      GND                     
                                  256      M_H_CPU0_SB_DQ<10>      
                                  257      GND                     
                                  258      M_H_CPU0_SB_DQ<11>      
                                  259      GND                     
                                  260      M_H_CPU0_SB_DQS_DN<6>   
                                  261      M_H_CPU0_SB_DQS_DP<6>   
                                  262      GND                     
                                  263      M_H_CPU0_SB_DQ<14>      
                                  264      GND                     
                                  265      M_H_CPU0_SB_DQ<15>      
                                  266      GND                     
                                  267      M_H_CPU0_SB_DQ<18>      
                                  268      GND                     
                                  269      M_H_CPU0_SB_DQ<19>      
                                  270      GND                     
                                  271      M_H_CPU0_SB_DQS_DN<7>   
                                  272      M_H_CPU0_SB_DQS_DP<7>   
                                  273      GND                     
                                  274      M_H_CPU0_SB_DQ<22>      
                                  275      GND                     
                                  276      M_H_CPU0_SB_DQ<23>      
                                  277      GND                     
                                  278      M_H_CPU0_SB_DQ<26>      
                                  279      GND                     
                                  280      M_H_CPU0_SB_DQ<27>      
                                  281      GND                     
                                  282      M_H_CPU0_SB_DQS_DN<8>   
                                  283      M_H_CPU0_SB_DQS_DP<8>   
                                  284      GND                     
                                  285      M_H_CPU0_SB_DQ<30>      
                                  286      GND                     
                                  287      M_H_CPU0_SB_DQ<31>      
                                  288      GND                     
                                  G1       GND                     
                                  G2       GND                     
                                  G3       GND                     
J17              SCONN288_ADR50001P013C01-SCONNA 1        P12V_S3_AUX_CPU1_NVDIMM 
                                  3        P3V3_AUX                
                                  4        I3C_SPD_DDRABCD_CPU1_LVC1_SCL
                                  5        I3C_SPD_DDRABCD_CPU1_LVC1_SDA
                                  6        GND                     
                                  7        M_A_CPU1_SA_DQ<0>       
                                  8        GND                     
                                  9        M_A_CPU1_SA_DQ<1>       
                                  10       GND                     
                                  11       M_A_CPU1_SA_DQS_DP<0>   
                                  12       M_A_CPU1_SA_DQS_DN<0>   
                                  13       GND                     
                                  14       M_A_CPU1_SA_DQ<4>       
                                  15       GND                     
                                  16       M_A_CPU1_SA_DQ<5>       
                                  17       GND                     
                                  18       M_A_CPU1_SA_DQ<8>       
                                  19       GND                     
                                  20       M_A_CPU1_SA_DQ<9>       
                                  21       GND                     
                                  22       M_A_CPU1_SA_DQS_DP<1>   
                                  23       M_A_CPU1_SA_DQS_DN<1>   
                                  24       GND                     
                                  25       M_A_CPU1_SA_DQ<12>      
                                  26       GND                     
                                  27       M_A_CPU1_SA_DQ<13>      
                                  28       GND                     
                                  29       M_A_CPU1_SA_DQ<16>      
                                  30       GND                     
                                  31       M_A_CPU1_SA_DQ<17>      
                                  32       GND                     
                                  33       M_A_CPU1_SA_DQS_DP<2>   
                                  34       M_A_CPU1_SA_DQS_DN<2>   
                                  35       GND                     
                                  36       M_A_CPU1_SA_DQ<20>      
                                  37       GND                     
                                  38       M_A_CPU1_SA_DQ<21>      
                                  39       GND                     
                                  40       M_A_CPU1_SA_DQ<24>      
                                  41       GND                     
                                  42       M_A_CPU1_SA_DQ<25>      
                                  43       GND                     
                                  44       M_A_CPU1_SA_DQS_DP<3>   
                                  45       M_A_CPU1_SA_DQS_DN<3>   
                                  46       GND                     
                                  47       M_A_CPU1_SA_DQ<28>      
                                  48       GND                     
                                  49       M_A_CPU1_SA_DQ<29>      
                                  50       GND                     
                                  51       M_A_CPU1_SA_CB<0>       
                                  52       GND                     
                                  53       M_A_CPU1_SA_CB<1>       
                                  54       GND                     
                                  55       M_A_CPU1_SA_DQS_DP<4>   
                                  56       M_A_CPU1_SA_DQS_DN<4>   
                                  57       GND                     
                                  58       M_A_CPU1_SA_CB<4>       
                                  59       GND                     
                                  60       M_A_CPU1_SA_CB<5>       
                                  61       GND                     
                                  62       M_A_CPU1_ALERT_N        
                                  63       GND                     
                                  64       M_A_CPU1_SA_CS_N<0>     
                                  65       GND                     
                                  66       M_A_CPU1_SA_CA<0>       
                                  67       GND                     
                                  68       M_A_CPU1_SA_CA<2>       
                                  69       GND                     
                                  70       M_A_CPU1_SA_CA<4>       
                                  71       GND                     
                                  72       M_A_CPU1_SA_CA<6>       
                                  73       GND                     
                                  74       M_A_CPU1_SA_PAR         
                                  75       GND                     
                                  76       M_A_CPU1_SB_CA<0>       
                                  77       GND                     
                                  78       M_A_CPU1_SB_CA<2>       
                                  79       GND                     
                                  80       M_A_CPU1_SB_CA<4>       
                                  81       GND                     
                                  82       M_A_CPU1_SB_CA<6>       
                                  83       GND                     
                                  84       M_A_CPU1_SB_CS_N<0>     
                                  85       GND                     
                                  86       M_A_CPU1_SA_RSP<0>      
                                  87       M_A_CPU1_SB_RSP<0>      
                                  88       GND                     
                                  89       M_A_CPU1_SB_CB<4>       
                                  90       GND                     
                                  91       M_A_CPU1_SB_CB<5>       
                                  92       GND                     
                                  93       M_A_CPU1_SB_DQS_DP<9>   
                                  94       M_A_CPU1_SB_DQS_DN<9>   
                                  95       GND                     
                                  96       M_A_CPU1_SB_CB<0>       
                                  97       GND                     
                                  98       M_A_CPU1_SB_CB<1>       
                                  99       GND                     
                                  100      M_A_CPU1_SB_DQ<0>       
                                  101      GND                     
                                  102      M_A_CPU1_SB_DQ<1>       
                                  103      GND                     
                                  104      M_A_CPU1_SB_DQS_DP<0>   
                                  105      M_A_CPU1_SB_DQS_DN<0>   
                                  106      GND                     
                                  107      M_A_CPU1_SB_DQ<4>       
                                  108      GND                     
                                  109      M_A_CPU1_SB_DQ<5>       
                                  110      GND                     
                                  111      M_A_CPU1_SB_DQ<8>       
                                  112      GND                     
                                  113      M_A_CPU1_SB_DQ<9>       
                                  114      GND                     
                                  115      M_A_CPU1_SB_DQS_DP<1>   
                                  116      M_A_CPU1_SB_DQS_DN<1>   
                                  117      GND                     
                                  118      M_A_CPU1_SB_DQ<12>      
                                  119      GND                     
                                  120      M_A_CPU1_SB_DQ<13>      
                                  121      GND                     
                                  122      M_A_CPU1_SB_DQ<16>      
                                  123      GND                     
                                  124      M_A_CPU1_SB_DQ<17>      
                                  125      GND                     
                                  126      M_A_CPU1_SB_DQS_DP<2>   
                                  127      M_A_CPU1_SB_DQS_DN<2>   
                                  128      GND                     
                                  129      M_A_CPU1_SB_DQ<20>      
                                  130      GND                     
                                  131      M_A_CPU1_SB_DQ<21>      
                                  132      GND                     
                                  133      M_A_CPU1_SB_DQ<24>      
                                  134      GND                     
                                  135      M_A_CPU1_SB_DQ<25>      
                                  136      GND                     
                                  137      M_A_CPU1_SB_DQS_DP<3>   
                                  138      M_A_CPU1_SB_DQS_DN<3>   
                                  139      GND                     
                                  140      M_A_CPU1_SB_DQ<28>      
                                  141      GND                     
                                  142      M_A_CPU1_SB_DQ<29>      
                                  143      GND                     
                                  145      P12V_S3_AUX_CPU1_NVDIMM 
                                  146      P12V_S3_AUX_CPU1_NVDIMM 
                                  147      PWRGD_CHA_CPU1_DIMM1    
                                  148      PD_CHA_CPU1_DIMM1_SAA   
                                  151      GND                     
                                  152      M_A_CPU1_SA_DQ<2>       
                                  153      GND                     
                                  154      M_A_CPU1_SA_DQ<3>       
                                  155      GND                     
                                  156      M_A_CPU1_SA_DQS_DN<5>   
                                  157      M_A_CPU1_SA_DQS_DP<5>   
                                  158      GND                     
                                  159      M_A_CPU1_SA_DQ<6>       
                                  160      GND                     
                                  161      M_A_CPU1_SA_DQ<7>       
                                  162      GND                     
                                  163      M_A_CPU1_SA_DQ<10>      
                                  164      GND                     
                                  165      M_A_CPU1_SA_DQ<11>      
                                  166      GND                     
                                  167      M_A_CPU1_SA_DQS_DN<6>   
                                  168      M_A_CPU1_SA_DQS_DP<6>   
                                  169      GND                     
                                  170      M_A_CPU1_SA_DQ<14>      
                                  171      GND                     
                                  172      M_A_CPU1_SA_DQ<15>      
                                  173      GND                     
                                  174      M_A_CPU1_SA_DQ<18>      
                                  175      GND                     
                                  176      M_A_CPU1_SA_DQ<19>      
                                  177      GND                     
                                  178      M_A_CPU1_SA_DQS_DN<7>   
                                  179      M_A_CPU1_SA_DQS_DP<7>   
                                  180      GND                     
                                  181      M_A_CPU1_SA_DQ<22>      
                                  182      GND                     
                                  183      M_A_CPU1_SA_DQ<23>      
                                  184      GND                     
                                  185      M_A_CPU1_SA_DQ<26>      
                                  186      GND                     
                                  187      M_A_CPU1_SA_DQ<27>      
                                  188      GND                     
                                  189      M_A_CPU1_SA_DQS_DN<8>   
                                  190      M_A_CPU1_SA_DQS_DP<8>   
                                  191      GND                     
                                  192      M_A_CPU1_SA_DQ<30>      
                                  193      GND                     
                                  194      M_A_CPU1_SA_DQ<31>      
                                  195      GND                     
                                  196      M_A_CPU1_SA_CB<2>       
                                  197      GND                     
                                  198      M_A_CPU1_SA_CB<3>       
                                  199      GND                     
                                  200      M_A_CPU1_SA_DQS_DN<9>   
                                  201      M_A_CPU1_SA_DQS_DP<9>   
                                  202      GND                     
                                  203      M_A_CPU1_SA_CB<6>       
                                  204      GND                     
                                  205      M_A_CPU1_SA_CB<7>       
                                  206      GND                     
                                  207      RST_M_AB_CPU1_FPGA_N    
                                  208      GND                     
                                  209      M_A_CPU1_SA_CS_N<1>     
                                  210      GND                     
                                  211      M_A_CPU1_SA_CA<1>       
                                  212      GND                     
                                  213      M_A_CPU1_SA_CA<3>       
                                  214      GND                     
                                  215      M_A_CPU1_SA_CA<5>       
                                  216      GND                     
                                  217      M_A_CPU1_CLK_DP<0>      
                                  218      M_A_CPU1_CLK_DN<0>      
                                  219      GND                     
                                  221      M_A_CPU1_SB_CA<1>       
                                  222      GND                     
                                  223      M_A_CPU1_SB_CA<3>       
                                  224      GND                     
                                  225      M_A_CPU1_SB_CA<5>       
                                  226      GND                     
                                  227      M_A_CPU1_SB_PAR         
                                  228      GND                     
                                  229      M_A_CPU1_SB_CS_N<1>     
                                  230      GND                     
                                  233      GND                     
                                  234      M_A_CPU1_SB_CB<6>       
                                  235      GND                     
                                  236      M_A_CPU1_SB_CB<7>       
                                  237      GND                     
                                  238      M_A_CPU1_SB_DQS_DN<4>   
                                  239      M_A_CPU1_SB_DQS_DP<4>   
                                  240      GND                     
                                  241      M_A_CPU1_SB_CB<2>       
                                  242      GND                     
                                  243      M_A_CPU1_SB_CB<3>       
                                  244      GND                     
                                  245      M_A_CPU1_SB_DQ<2>       
                                  246      GND                     
                                  247      M_A_CPU1_SB_DQ<3>       
                                  248      GND                     
                                  249      M_A_CPU1_SB_DQS_DN<5>   
                                  250      M_A_CPU1_SB_DQS_DP<5>   
                                  251      GND                     
                                  252      M_A_CPU1_SB_DQ<6>       
                                  253      GND                     
                                  254      M_A_CPU1_SB_DQ<7>       
                                  255      GND                     
                                  256      M_A_CPU1_SB_DQ<10>      
                                  257      GND                     
                                  258      M_A_CPU1_SB_DQ<11>      
                                  259      GND                     
                                  260      M_A_CPU1_SB_DQS_DN<6>   
                                  261      M_A_CPU1_SB_DQS_DP<6>   
                                  262      GND                     
                                  263      M_A_CPU1_SB_DQ<14>      
                                  264      GND                     
                                  265      M_A_CPU1_SB_DQ<15>      
                                  266      GND                     
                                  267      M_A_CPU1_SB_DQ<18>      
                                  268      GND                     
                                  269      M_A_CPU1_SB_DQ<19>      
                                  270      GND                     
                                  271      M_A_CPU1_SB_DQS_DN<7>   
                                  272      M_A_CPU1_SB_DQS_DP<7>   
                                  273      GND                     
                                  274      M_A_CPU1_SB_DQ<22>      
                                  275      GND                     
                                  276      M_A_CPU1_SB_DQ<23>      
                                  277      GND                     
                                  278      M_A_CPU1_SB_DQ<26>      
                                  279      GND                     
                                  280      M_A_CPU1_SB_DQ<27>      
                                  281      GND                     
                                  282      M_A_CPU1_SB_DQS_DN<8>   
                                  283      M_A_CPU1_SB_DQS_DP<8>   
                                  284      GND                     
                                  285      M_A_CPU1_SB_DQ<30>      
                                  286      GND                     
                                  287      M_A_CPU1_SB_DQ<31>      
                                  288      GND                     
                                  G1       GND                     
                                  G2       GND                     
                                  G3       GND                     
J18              SCONN288_ADR50001P003C01-SCONNA 1        P12V_S3_AUX_CPU1_NVDIMM 
                                  3        P3V3_AUX                
                                  4        I3C_SPD_DDRABCD_CPU1_LVC1_SCL
                                  5        I3C_SPD_DDRABCD_CPU1_LVC1_SDA
                                  6        GND                     
                                  7        M_A_CPU1_SA_DQ<0>       
                                  8        GND                     
                                  9        M_A_CPU1_SA_DQ<1>       
                                  10       GND                     
                                  11       M_A_CPU1_SA_DQS_DP<0>   
                                  12       M_A_CPU1_SA_DQS_DN<0>   
                                  13       GND                     
                                  14       M_A_CPU1_SA_DQ<4>       
                                  15       GND                     
                                  16       M_A_CPU1_SA_DQ<5>       
                                  17       GND                     
                                  18       M_A_CPU1_SA_DQ<8>       
                                  19       GND                     
                                  20       M_A_CPU1_SA_DQ<9>       
                                  21       GND                     
                                  22       M_A_CPU1_SA_DQS_DP<1>   
                                  23       M_A_CPU1_SA_DQS_DN<1>   
                                  24       GND                     
                                  25       M_A_CPU1_SA_DQ<12>      
                                  26       GND                     
                                  27       M_A_CPU1_SA_DQ<13>      
                                  28       GND                     
                                  29       M_A_CPU1_SA_DQ<16>      
                                  30       GND                     
                                  31       M_A_CPU1_SA_DQ<17>      
                                  32       GND                     
                                  33       M_A_CPU1_SA_DQS_DP<2>   
                                  34       M_A_CPU1_SA_DQS_DN<2>   
                                  35       GND                     
                                  36       M_A_CPU1_SA_DQ<20>      
                                  37       GND                     
                                  38       M_A_CPU1_SA_DQ<21>      
                                  39       GND                     
                                  40       M_A_CPU1_SA_DQ<24>      
                                  41       GND                     
                                  42       M_A_CPU1_SA_DQ<25>      
                                  43       GND                     
                                  44       M_A_CPU1_SA_DQS_DP<3>   
                                  45       M_A_CPU1_SA_DQS_DN<3>   
                                  46       GND                     
                                  47       M_A_CPU1_SA_DQ<28>      
                                  48       GND                     
                                  49       M_A_CPU1_SA_DQ<29>      
                                  50       GND                     
                                  51       M_A_CPU1_SA_CB<0>       
                                  52       GND                     
                                  53       M_A_CPU1_SA_CB<1>       
                                  54       GND                     
                                  55       M_A_CPU1_SA_DQS_DP<4>   
                                  56       M_A_CPU1_SA_DQS_DN<4>   
                                  57       GND                     
                                  58       M_A_CPU1_SA_CB<4>       
                                  59       GND                     
                                  60       M_A_CPU1_SA_CB<5>       
                                  61       GND                     
                                  62       M_A_CPU1_ALERT_N        
                                  63       GND                     
                                  64       M_A_CPU1_SA_CS_N<2>     
                                  65       GND                     
                                  66       M_A_CPU1_SA_CA<0>       
                                  67       GND                     
                                  68       M_A_CPU1_SA_CA<2>       
                                  69       GND                     
                                  70       M_A_CPU1_SA_CA<4>       
                                  71       GND                     
                                  72       M_A_CPU1_SA_CA<6>       
                                  73       GND                     
                                  74       M_A_CPU1_SA_PAR         
                                  75       GND                     
                                  76       M_A_CPU1_SB_CA<0>       
                                  77       GND                     
                                  78       M_A_CPU1_SB_CA<2>       
                                  79       GND                     
                                  80       M_A_CPU1_SB_CA<4>       
                                  81       GND                     
                                  82       M_A_CPU1_SB_CA<6>       
                                  83       GND                     
                                  84       M_A_CPU1_SB_CS_N<2>     
                                  85       GND                     
                                  86       M_A_CPU1_SA_RSP<1>      
                                  87       M_A_CPU1_SB_RSP<1>      
                                  88       GND                     
                                  89       M_A_CPU1_SB_CB<4>       
                                  90       GND                     
                                  91       M_A_CPU1_SB_CB<5>       
                                  92       GND                     
                                  93       M_A_CPU1_SB_DQS_DP<9>   
                                  94       M_A_CPU1_SB_DQS_DN<9>   
                                  95       GND                     
                                  96       M_A_CPU1_SB_CB<0>       
                                  97       GND                     
                                  98       M_A_CPU1_SB_CB<1>       
                                  99       GND                     
                                  100      M_A_CPU1_SB_DQ<0>       
                                  101      GND                     
                                  102      M_A_CPU1_SB_DQ<1>       
                                  103      GND                     
                                  104      M_A_CPU1_SB_DQS_DP<0>   
                                  105      M_A_CPU1_SB_DQS_DN<0>   
                                  106      GND                     
                                  107      M_A_CPU1_SB_DQ<4>       
                                  108      GND                     
                                  109      M_A_CPU1_SB_DQ<5>       
                                  110      GND                     
                                  111      M_A_CPU1_SB_DQ<8>       
                                  112      GND                     
                                  113      M_A_CPU1_SB_DQ<9>       
                                  114      GND                     
                                  115      M_A_CPU1_SB_DQS_DP<1>   
                                  116      M_A_CPU1_SB_DQS_DN<1>   
                                  117      GND                     
                                  118      M_A_CPU1_SB_DQ<12>      
                                  119      GND                     
                                  120      M_A_CPU1_SB_DQ<13>      
                                  121      GND                     
                                  122      M_A_CPU1_SB_DQ<16>      
                                  123      GND                     
                                  124      M_A_CPU1_SB_DQ<17>      
                                  125      GND                     
                                  126      M_A_CPU1_SB_DQS_DP<2>   
                                  127      M_A_CPU1_SB_DQS_DN<2>   
                                  128      GND                     
                                  129      M_A_CPU1_SB_DQ<20>      
                                  130      GND                     
                                  131      M_A_CPU1_SB_DQ<21>      
                                  132      GND                     
                                  133      M_A_CPU1_SB_DQ<24>      
                                  134      GND                     
                                  135      M_A_CPU1_SB_DQ<25>      
                                  136      GND                     
                                  137      M_A_CPU1_SB_DQS_DP<3>   
                                  138      M_A_CPU1_SB_DQS_DN<3>   
                                  139      GND                     
                                  140      M_A_CPU1_SB_DQ<28>      
                                  141      GND                     
                                  142      M_A_CPU1_SB_DQ<29>      
                                  143      GND                     
                                  145      P12V_S3_AUX_CPU1_NVDIMM 
                                  146      P12V_S3_AUX_CPU1_NVDIMM 
                                  147      PWRGD_CHA_CPU1_DIMM2    
                                  148      PD_CHA_CPU1_DIMM2_SAA   
                                  151      GND                     
                                  152      M_A_CPU1_SA_DQ<2>       
                                  153      GND                     
                                  154      M_A_CPU1_SA_DQ<3>       
                                  155      GND                     
                                  156      M_A_CPU1_SA_DQS_DN<5>   
                                  157      M_A_CPU1_SA_DQS_DP<5>   
                                  158      GND                     
                                  159      M_A_CPU1_SA_DQ<6>       
                                  160      GND                     
                                  161      M_A_CPU1_SA_DQ<7>       
                                  162      GND                     
                                  163      M_A_CPU1_SA_DQ<10>      
                                  164      GND                     
                                  165      M_A_CPU1_SA_DQ<11>      
                                  166      GND                     
                                  167      M_A_CPU1_SA_DQS_DN<6>   
                                  168      M_A_CPU1_SA_DQS_DP<6>   
                                  169      GND                     
                                  170      M_A_CPU1_SA_DQ<14>      
                                  171      GND                     
                                  172      M_A_CPU1_SA_DQ<15>      
                                  173      GND                     
                                  174      M_A_CPU1_SA_DQ<18>      
                                  175      GND                     
                                  176      M_A_CPU1_SA_DQ<19>      
                                  177      GND                     
                                  178      M_A_CPU1_SA_DQS_DN<7>   
                                  179      M_A_CPU1_SA_DQS_DP<7>   
                                  180      GND                     
                                  181      M_A_CPU1_SA_DQ<22>      
                                  182      GND                     
                                  183      M_A_CPU1_SA_DQ<23>      
                                  184      GND                     
                                  185      M_A_CPU1_SA_DQ<26>      
                                  186      GND                     
                                  187      M_A_CPU1_SA_DQ<27>      
                                  188      GND                     
                                  189      M_A_CPU1_SA_DQS_DN<8>   
                                  190      M_A_CPU1_SA_DQS_DP<8>   
                                  191      GND                     
                                  192      M_A_CPU1_SA_DQ<30>      
                                  193      GND                     
                                  194      M_A_CPU1_SA_DQ<31>      
                                  195      GND                     
                                  196      M_A_CPU1_SA_CB<2>       
                                  197      GND                     
                                  198      M_A_CPU1_SA_CB<3>       
                                  199      GND                     
                                  200      M_A_CPU1_SA_DQS_DN<9>   
                                  201      M_A_CPU1_SA_DQS_DP<9>   
                                  202      GND                     
                                  203      M_A_CPU1_SA_CB<6>       
                                  204      GND                     
                                  205      M_A_CPU1_SA_CB<7>       
                                  206      GND                     
                                  207      RST_M_AB_CPU1_FPGA_N    
                                  208      GND                     
                                  209      M_A_CPU1_SA_CS_N<3>     
                                  210      GND                     
                                  211      M_A_CPU1_SA_CA<1>       
                                  212      GND                     
                                  213      M_A_CPU1_SA_CA<3>       
                                  214      GND                     
                                  215      M_A_CPU1_SA_CA<5>       
                                  216      GND                     
                                  217      M_A_CPU1_CLK_DP<1>      
                                  218      M_A_CPU1_CLK_DN<1>      
                                  219      GND                     
                                  221      M_A_CPU1_SB_CA<1>       
                                  222      GND                     
                                  223      M_A_CPU1_SB_CA<3>       
                                  224      GND                     
                                  225      M_A_CPU1_SB_CA<5>       
                                  226      GND                     
                                  227      M_A_CPU1_SB_PAR         
                                  228      GND                     
                                  229      M_A_CPU1_SB_CS_N<3>     
                                  230      GND                     
                                  233      GND                     
                                  234      M_A_CPU1_SB_CB<6>       
                                  235      GND                     
                                  236      M_A_CPU1_SB_CB<7>       
                                  237      GND                     
                                  238      M_A_CPU1_SB_DQS_DN<4>   
                                  239      M_A_CPU1_SB_DQS_DP<4>   
                                  240      GND                     
                                  241      M_A_CPU1_SB_CB<2>       
                                  242      GND                     
                                  243      M_A_CPU1_SB_CB<3>       
                                  244      GND                     
                                  245      M_A_CPU1_SB_DQ<2>       
                                  246      GND                     
                                  247      M_A_CPU1_SB_DQ<3>       
                                  248      GND                     
                                  249      M_A_CPU1_SB_DQS_DN<5>   
                                  250      M_A_CPU1_SB_DQS_DP<5>   
                                  251      GND                     
                                  252      M_A_CPU1_SB_DQ<6>       
                                  253      GND                     
                                  254      M_A_CPU1_SB_DQ<7>       
                                  255      GND                     
                                  256      M_A_CPU1_SB_DQ<10>      
                                  257      GND                     
                                  258      M_A_CPU1_SB_DQ<11>      
                                  259      GND                     
                                  260      M_A_CPU1_SB_DQS_DN<6>   
                                  261      M_A_CPU1_SB_DQS_DP<6>   
                                  262      GND                     
                                  263      M_A_CPU1_SB_DQ<14>      
                                  264      GND                     
                                  265      M_A_CPU1_SB_DQ<15>      
                                  266      GND                     
                                  267      M_A_CPU1_SB_DQ<18>      
                                  268      GND                     
                                  269      M_A_CPU1_SB_DQ<19>      
                                  270      GND                     
                                  271      M_A_CPU1_SB_DQS_DN<7>   
                                  272      M_A_CPU1_SB_DQS_DP<7>   
                                  273      GND                     
                                  274      M_A_CPU1_SB_DQ<22>      
                                  275      GND                     
                                  276      M_A_CPU1_SB_DQ<23>      
                                  277      GND                     
                                  278      M_A_CPU1_SB_DQ<26>      
                                  279      GND                     
                                  280      M_A_CPU1_SB_DQ<27>      
                                  281      GND                     
                                  282      M_A_CPU1_SB_DQS_DN<8>   
                                  283      M_A_CPU1_SB_DQS_DP<8>   
                                  284      GND                     
                                  285      M_A_CPU1_SB_DQ<30>      
                                  286      GND                     
                                  287      M_A_CPU1_SB_DQ<31>      
                                  288      GND                     
                                  G1       GND                     
                                  G2       GND                     
                                  G3       GND                     
J19              SCONN288_ADR50001P013C01-SCONNA 1        P12V_S3_AUX_CPU1_NVDIMM 
                                  3        P3V3_AUX                
                                  4        I3C_SPD_DDRABCD_CPU1_LVC1_SCL
                                  5        I3C_SPD_DDRABCD_CPU1_LVC1_SDA
                                  6        GND                     
                                  7        M_B_CPU1_SA_DQ<0>       
                                  8        GND                     
                                  9        M_B_CPU1_SA_DQ<1>       
                                  10       GND                     
                                  11       M_B_CPU1_SA_DQS_DP<0>   
                                  12       M_B_CPU1_SA_DQS_DN<0>   
                                  13       GND                     
                                  14       M_B_CPU1_SA_DQ<4>       
                                  15       GND                     
                                  16       M_B_CPU1_SA_DQ<5>       
                                  17       GND                     
                                  18       M_B_CPU1_SA_DQ<8>       
                                  19       GND                     
                                  20       M_B_CPU1_SA_DQ<9>       
                                  21       GND                     
                                  22       M_B_CPU1_SA_DQS_DP<1>   
                                  23       M_B_CPU1_SA_DQS_DN<1>   
                                  24       GND                     
                                  25       M_B_CPU1_SA_DQ<12>      
                                  26       GND                     
                                  27       M_B_CPU1_SA_DQ<13>      
                                  28       GND                     
                                  29       M_B_CPU1_SA_DQ<16>      
                                  30       GND                     
                                  31       M_B_CPU1_SA_DQ<17>      
                                  32       GND                     
                                  33       M_B_CPU1_SA_DQS_DP<2>   
                                  34       M_B_CPU1_SA_DQS_DN<2>   
                                  35       GND                     
                                  36       M_B_CPU1_SA_DQ<20>      
                                  37       GND                     
                                  38       M_B_CPU1_SA_DQ<21>      
                                  39       GND                     
                                  40       M_B_CPU1_SA_DQ<24>      
                                  41       GND                     
                                  42       M_B_CPU1_SA_DQ<25>      
                                  43       GND                     
                                  44       M_B_CPU1_SA_DQS_DP<3>   
                                  45       M_B_CPU1_SA_DQS_DN<3>   
                                  46       GND                     
                                  47       M_B_CPU1_SA_DQ<28>      
                                  48       GND                     
                                  49       M_B_CPU1_SA_DQ<29>      
                                  50       GND                     
                                  51       M_B_CPU1_SA_CB<0>       
                                  52       GND                     
                                  53       M_B_CPU1_SA_CB<1>       
                                  54       GND                     
                                  55       M_B_CPU1_SA_DQS_DP<4>   
                                  56       M_B_CPU1_SA_DQS_DN<4>   
                                  57       GND                     
                                  58       M_B_CPU1_SA_CB<4>       
                                  59       GND                     
                                  60       M_B_CPU1_SA_CB<5>       
                                  61       GND                     
                                  62       M_B_CPU1_ALERT_N        
                                  63       GND                     
                                  64       M_B_CPU1_SA_CS_N<0>     
                                  65       GND                     
                                  66       M_B_CPU1_SA_CA<0>       
                                  67       GND                     
                                  68       M_B_CPU1_SA_CA<2>       
                                  69       GND                     
                                  70       M_B_CPU1_SA_CA<4>       
                                  71       GND                     
                                  72       M_B_CPU1_SA_CA<6>       
                                  73       GND                     
                                  74       M_B_CPU1_SA_PAR         
                                  75       GND                     
                                  76       M_B_CPU1_SB_CA<0>       
                                  77       GND                     
                                  78       M_B_CPU1_SB_CA<2>       
                                  79       GND                     
                                  80       M_B_CPU1_SB_CA<4>       
                                  81       GND                     
                                  82       M_B_CPU1_SB_CA<6>       
                                  83       GND                     
                                  84       M_B_CPU1_SB_CS_N<0>     
                                  85       GND                     
                                  86       M_B_CPU1_SA_RSP<0>      
                                  87       M_B_CPU1_SB_RSP<0>      
                                  88       GND                     
                                  89       M_B_CPU1_SB_CB<4>       
                                  90       GND                     
                                  91       M_B_CPU1_SB_CB<5>       
                                  92       GND                     
                                  93       M_B_CPU1_SB_DQS_DP<9>   
                                  94       M_B_CPU1_SB_DQS_DN<9>   
                                  95       GND                     
                                  96       M_B_CPU1_SB_CB<0>       
                                  97       GND                     
                                  98       M_B_CPU1_SB_CB<1>       
                                  99       GND                     
                                  100      M_B_CPU1_SB_DQ<0>       
                                  101      GND                     
                                  102      M_B_CPU1_SB_DQ<1>       
                                  103      GND                     
                                  104      M_B_CPU1_SB_DQS_DP<0>   
                                  105      M_B_CPU1_SB_DQS_DN<0>   
                                  106      GND                     
                                  107      M_B_CPU1_SB_DQ<4>       
                                  108      GND                     
                                  109      M_B_CPU1_SB_DQ<5>       
                                  110      GND                     
                                  111      M_B_CPU1_SB_DQ<8>       
                                  112      GND                     
                                  113      M_B_CPU1_SB_DQ<9>       
                                  114      GND                     
                                  115      M_B_CPU1_SB_DQS_DP<1>   
                                  116      M_B_CPU1_SB_DQS_DN<1>   
                                  117      GND                     
                                  118      M_B_CPU1_SB_DQ<12>      
                                  119      GND                     
                                  120      M_B_CPU1_SB_DQ<13>      
                                  121      GND                     
                                  122      M_B_CPU1_SB_DQ<16>      
                                  123      GND                     
                                  124      M_B_CPU1_SB_DQ<17>      
                                  125      GND                     
                                  126      M_B_CPU1_SB_DQS_DP<2>   
                                  127      M_B_CPU1_SB_DQS_DN<2>   
                                  128      GND                     
                                  129      M_B_CPU1_SB_DQ<20>      
                                  130      GND                     
                                  131      M_B_CPU1_SB_DQ<21>      
                                  132      GND                     
                                  133      M_B_CPU1_SB_DQ<24>      
                                  134      GND                     
                                  135      M_B_CPU1_SB_DQ<25>      
                                  136      GND                     
                                  137      M_B_CPU1_SB_DQS_DP<3>   
                                  138      M_B_CPU1_SB_DQS_DN<3>   
                                  139      GND                     
                                  140      M_B_CPU1_SB_DQ<28>      
                                  141      GND                     
                                  142      M_B_CPU1_SB_DQ<29>      
                                  143      GND                     
                                  145      P12V_S3_AUX_CPU1_NVDIMM 
                                  146      P12V_S3_AUX_CPU1_NVDIMM 
                                  147      PWRGD_CHB_CPU1_DIMM1    
                                  148      PD_CHB_CPU1_DIMM1_SAA   
                                  151      GND                     
                                  152      M_B_CPU1_SA_DQ<2>       
                                  153      GND                     
                                  154      M_B_CPU1_SA_DQ<3>       
                                  155      GND                     
                                  156      M_B_CPU1_SA_DQS_DN<5>   
                                  157      M_B_CPU1_SA_DQS_DP<5>   
                                  158      GND                     
                                  159      M_B_CPU1_SA_DQ<6>       
                                  160      GND                     
                                  161      M_B_CPU1_SA_DQ<7>       
                                  162      GND                     
                                  163      M_B_CPU1_SA_DQ<10>      
                                  164      GND                     
                                  165      M_B_CPU1_SA_DQ<11>      
                                  166      GND                     
                                  167      M_B_CPU1_SA_DQS_DN<6>   
                                  168      M_B_CPU1_SA_DQS_DP<6>   
                                  169      GND                     
                                  170      M_B_CPU1_SA_DQ<14>      
                                  171      GND                     
                                  172      M_B_CPU1_SA_DQ<15>      
                                  173      GND                     
                                  174      M_B_CPU1_SA_DQ<18>      
                                  175      GND                     
                                  176      M_B_CPU1_SA_DQ<19>      
                                  177      GND                     
                                  178      M_B_CPU1_SA_DQS_DN<7>   
                                  179      M_B_CPU1_SA_DQS_DP<7>   
                                  180      GND                     
                                  181      M_B_CPU1_SA_DQ<22>      
                                  182      GND                     
                                  183      M_B_CPU1_SA_DQ<23>      
                                  184      GND                     
                                  185      M_B_CPU1_SA_DQ<26>      
                                  186      GND                     
                                  187      M_B_CPU1_SA_DQ<27>      
                                  188      GND                     
                                  189      M_B_CPU1_SA_DQS_DN<8>   
                                  190      M_B_CPU1_SA_DQS_DP<8>   
                                  191      GND                     
                                  192      M_B_CPU1_SA_DQ<30>      
                                  193      GND                     
                                  194      M_B_CPU1_SA_DQ<31>      
                                  195      GND                     
                                  196      M_B_CPU1_SA_CB<2>       
                                  197      GND                     
                                  198      M_B_CPU1_SA_CB<3>       
                                  199      GND                     
                                  200      M_B_CPU1_SA_DQS_DN<9>   
                                  201      M_B_CPU1_SA_DQS_DP<9>   
                                  202      GND                     
                                  203      M_B_CPU1_SA_CB<6>       
                                  204      GND                     
                                  205      M_B_CPU1_SA_CB<7>       
                                  206      GND                     
                                  207      RST_M_AB_CPU1_FPGA_N    
                                  208      GND                     
                                  209      M_B_CPU1_SA_CS_N<1>     
                                  210      GND                     
                                  211      M_B_CPU1_SA_CA<1>       
                                  212      GND                     
                                  213      M_B_CPU1_SA_CA<3>       
                                  214      GND                     
                                  215      M_B_CPU1_SA_CA<5>       
                                  216      GND                     
                                  217      M_B_CPU1_CLK_DP<0>      
                                  218      M_B_CPU1_CLK_DN<0>      
                                  219      GND                     
                                  221      M_B_CPU1_SB_CA<1>       
                                  222      GND                     
                                  223      M_B_CPU1_SB_CA<3>       
                                  224      GND                     
                                  225      M_B_CPU1_SB_CA<5>       
                                  226      GND                     
                                  227      M_B_CPU1_SB_PAR         
                                  228      GND                     
                                  229      M_B_CPU1_SB_CS_N<1>     
                                  230      GND                     
                                  233      GND                     
                                  234      M_B_CPU1_SB_CB<6>       
                                  235      GND                     
                                  236      M_B_CPU1_SB_CB<7>       
                                  237      GND                     
                                  238      M_B_CPU1_SB_DQS_DN<4>   
                                  239      M_B_CPU1_SB_DQS_DP<4>   
                                  240      GND                     
                                  241      M_B_CPU1_SB_CB<2>       
                                  242      GND                     
                                  243      M_B_CPU1_SB_CB<3>       
                                  244      GND                     
                                  245      M_B_CPU1_SB_DQ<2>       
                                  246      GND                     
                                  247      M_B_CPU1_SB_DQ<3>       
                                  248      GND                     
                                  249      M_B_CPU1_SB_DQS_DN<5>   
                                  250      M_B_CPU1_SB_DQS_DP<5>   
                                  251      GND                     
                                  252      M_B_CPU1_SB_DQ<6>       
                                  253      GND                     
                                  254      M_B_CPU1_SB_DQ<7>       
                                  255      GND                     
                                  256      M_B_CPU1_SB_DQ<10>      
                                  257      GND                     
                                  258      M_B_CPU1_SB_DQ<11>      
                                  259      GND                     
                                  260      M_B_CPU1_SB_DQS_DN<6>   
                                  261      M_B_CPU1_SB_DQS_DP<6>   
                                  262      GND                     
                                  263      M_B_CPU1_SB_DQ<14>      
                                  264      GND                     
                                  265      M_B_CPU1_SB_DQ<15>      
                                  266      GND                     
                                  267      M_B_CPU1_SB_DQ<18>      
                                  268      GND                     
                                  269      M_B_CPU1_SB_DQ<19>      
                                  270      GND                     
                                  271      M_B_CPU1_SB_DQS_DN<7>   
                                  272      M_B_CPU1_SB_DQS_DP<7>   
                                  273      GND                     
                                  274      M_B_CPU1_SB_DQ<22>      
                                  275      GND                     
                                  276      M_B_CPU1_SB_DQ<23>      
                                  277      GND                     
                                  278      M_B_CPU1_SB_DQ<26>      
                                  279      GND                     
                                  280      M_B_CPU1_SB_DQ<27>      
                                  281      GND                     
                                  282      M_B_CPU1_SB_DQS_DN<8>   
                                  283      M_B_CPU1_SB_DQS_DP<8>   
                                  284      GND                     
                                  285      M_B_CPU1_SB_DQ<30>      
                                  286      GND                     
                                  287      M_B_CPU1_SB_DQ<31>      
                                  288      GND                     
                                  G1       GND                     
                                  G2       GND                     
                                  G3       GND                     
J20              SCONN288_ADR50001P003C01-SCONNA 1        P12V_S3_AUX_CPU1_NVDIMM 
                                  3        P3V3_AUX                
                                  4        I3C_SPD_DDRABCD_CPU1_LVC1_SCL
                                  5        I3C_SPD_DDRABCD_CPU1_LVC1_SDA
                                  6        GND                     
                                  7        M_B_CPU1_SA_DQ<0>       
                                  8        GND                     
                                  9        M_B_CPU1_SA_DQ<1>       
                                  10       GND                     
                                  11       M_B_CPU1_SA_DQS_DP<0>   
                                  12       M_B_CPU1_SA_DQS_DN<0>   
                                  13       GND                     
                                  14       M_B_CPU1_SA_DQ<4>       
                                  15       GND                     
                                  16       M_B_CPU1_SA_DQ<5>       
                                  17       GND                     
                                  18       M_B_CPU1_SA_DQ<8>       
                                  19       GND                     
                                  20       M_B_CPU1_SA_DQ<9>       
                                  21       GND                     
                                  22       M_B_CPU1_SA_DQS_DP<1>   
                                  23       M_B_CPU1_SA_DQS_DN<1>   
                                  24       GND                     
                                  25       M_B_CPU1_SA_DQ<12>      
                                  26       GND                     
                                  27       M_B_CPU1_SA_DQ<13>      
                                  28       GND                     
                                  29       M_B_CPU1_SA_DQ<16>      
                                  30       GND                     
                                  31       M_B_CPU1_SA_DQ<17>      
                                  32       GND                     
                                  33       M_B_CPU1_SA_DQS_DP<2>   
                                  34       M_B_CPU1_SA_DQS_DN<2>   
                                  35       GND                     
                                  36       M_B_CPU1_SA_DQ<20>      
                                  37       GND                     
                                  38       M_B_CPU1_SA_DQ<21>      
                                  39       GND                     
                                  40       M_B_CPU1_SA_DQ<24>      
                                  41       GND                     
                                  42       M_B_CPU1_SA_DQ<25>      
                                  43       GND                     
                                  44       M_B_CPU1_SA_DQS_DP<3>   
                                  45       M_B_CPU1_SA_DQS_DN<3>   
                                  46       GND                     
                                  47       M_B_CPU1_SA_DQ<28>      
                                  48       GND                     
                                  49       M_B_CPU1_SA_DQ<29>      
                                  50       GND                     
                                  51       M_B_CPU1_SA_CB<0>       
                                  52       GND                     
                                  53       M_B_CPU1_SA_CB<1>       
                                  54       GND                     
                                  55       M_B_CPU1_SA_DQS_DP<4>   
                                  56       M_B_CPU1_SA_DQS_DN<4>   
                                  57       GND                     
                                  58       M_B_CPU1_SA_CB<4>       
                                  59       GND                     
                                  60       M_B_CPU1_SA_CB<5>       
                                  61       GND                     
                                  62       M_B_CPU1_ALERT_N        
                                  63       GND                     
                                  64       M_B_CPU1_SA_CS_N<2>     
                                  65       GND                     
                                  66       M_B_CPU1_SA_CA<0>       
                                  67       GND                     
                                  68       M_B_CPU1_SA_CA<2>       
                                  69       GND                     
                                  70       M_B_CPU1_SA_CA<4>       
                                  71       GND                     
                                  72       M_B_CPU1_SA_CA<6>       
                                  73       GND                     
                                  74       M_B_CPU1_SA_PAR         
                                  75       GND                     
                                  76       M_B_CPU1_SB_CA<0>       
                                  77       GND                     
                                  78       M_B_CPU1_SB_CA<2>       
                                  79       GND                     
                                  80       M_B_CPU1_SB_CA<4>       
                                  81       GND                     
                                  82       M_B_CPU1_SB_CA<6>       
                                  83       GND                     
                                  84       M_B_CPU1_SB_CS_N<2>     
                                  85       GND                     
                                  86       M_B_CPU1_SA_RSP<1>      
                                  87       M_B_CPU1_SB_RSP<1>      
                                  88       GND                     
                                  89       M_B_CPU1_SB_CB<4>       
                                  90       GND                     
                                  91       M_B_CPU1_SB_CB<5>       
                                  92       GND                     
                                  93       M_B_CPU1_SB_DQS_DP<9>   
                                  94       M_B_CPU1_SB_DQS_DN<9>   
                                  95       GND                     
                                  96       M_B_CPU1_SB_CB<0>       
                                  97       GND                     
                                  98       M_B_CPU1_SB_CB<1>       
                                  99       GND                     
                                  100      M_B_CPU1_SB_DQ<0>       
                                  101      GND                     
                                  102      M_B_CPU1_SB_DQ<1>       
                                  103      GND                     
                                  104      M_B_CPU1_SB_DQS_DP<0>   
                                  105      M_B_CPU1_SB_DQS_DN<0>   
                                  106      GND                     
                                  107      M_B_CPU1_SB_DQ<4>       
                                  108      GND                     
                                  109      M_B_CPU1_SB_DQ<5>       
                                  110      GND                     
                                  111      M_B_CPU1_SB_DQ<8>       
                                  112      GND                     
                                  113      M_B_CPU1_SB_DQ<9>       
                                  114      GND                     
                                  115      M_B_CPU1_SB_DQS_DP<1>   
                                  116      M_B_CPU1_SB_DQS_DN<1>   
                                  117      GND                     
                                  118      M_B_CPU1_SB_DQ<12>      
                                  119      GND                     
                                  120      M_B_CPU1_SB_DQ<13>      
                                  121      GND                     
                                  122      M_B_CPU1_SB_DQ<16>      
                                  123      GND                     
                                  124      M_B_CPU1_SB_DQ<17>      
                                  125      GND                     
                                  126      M_B_CPU1_SB_DQS_DP<2>   
                                  127      M_B_CPU1_SB_DQS_DN<2>   
                                  128      GND                     
                                  129      M_B_CPU1_SB_DQ<20>      
                                  130      GND                     
                                  131      M_B_CPU1_SB_DQ<21>      
                                  132      GND                     
                                  133      M_B_CPU1_SB_DQ<24>      
                                  134      GND                     
                                  135      M_B_CPU1_SB_DQ<25>      
                                  136      GND                     
                                  137      M_B_CPU1_SB_DQS_DP<3>   
                                  138      M_B_CPU1_SB_DQS_DN<3>   
                                  139      GND                     
                                  140      M_B_CPU1_SB_DQ<28>      
                                  141      GND                     
                                  142      M_B_CPU1_SB_DQ<29>      
                                  143      GND                     
                                  145      P12V_S3_AUX_CPU1_NVDIMM 
                                  146      P12V_S3_AUX_CPU1_NVDIMM 
                                  147      PWRGD_CHB_CPU1_DIMM2    
                                  148      PD_CHB_CPU1_DIMM2_SAA   
                                  151      GND                     
                                  152      M_B_CPU1_SA_DQ<2>       
                                  153      GND                     
                                  154      M_B_CPU1_SA_DQ<3>       
                                  155      GND                     
                                  156      M_B_CPU1_SA_DQS_DN<5>   
                                  157      M_B_CPU1_SA_DQS_DP<5>   
                                  158      GND                     
                                  159      M_B_CPU1_SA_DQ<6>       
                                  160      GND                     
                                  161      M_B_CPU1_SA_DQ<7>       
                                  162      GND                     
                                  163      M_B_CPU1_SA_DQ<10>      
                                  164      GND                     
                                  165      M_B_CPU1_SA_DQ<11>      
                                  166      GND                     
                                  167      M_B_CPU1_SA_DQS_DN<6>   
                                  168      M_B_CPU1_SA_DQS_DP<6>   
                                  169      GND                     
                                  170      M_B_CPU1_SA_DQ<14>      
                                  171      GND                     
                                  172      M_B_CPU1_SA_DQ<15>      
                                  173      GND                     
                                  174      M_B_CPU1_SA_DQ<18>      
                                  175      GND                     
                                  176      M_B_CPU1_SA_DQ<19>      
                                  177      GND                     
                                  178      M_B_CPU1_SA_DQS_DN<7>   
                                  179      M_B_CPU1_SA_DQS_DP<7>   
                                  180      GND                     
                                  181      M_B_CPU1_SA_DQ<22>      
                                  182      GND                     
                                  183      M_B_CPU1_SA_DQ<23>      
                                  184      GND                     
                                  185      M_B_CPU1_SA_DQ<26>      
                                  186      GND                     
                                  187      M_B_CPU1_SA_DQ<27>      
                                  188      GND                     
                                  189      M_B_CPU1_SA_DQS_DN<8>   
                                  190      M_B_CPU1_SA_DQS_DP<8>   
                                  191      GND                     
                                  192      M_B_CPU1_SA_DQ<30>      
                                  193      GND                     
                                  194      M_B_CPU1_SA_DQ<31>      
                                  195      GND                     
                                  196      M_B_CPU1_SA_CB<2>       
                                  197      GND                     
                                  198      M_B_CPU1_SA_CB<3>       
                                  199      GND                     
                                  200      M_B_CPU1_SA_DQS_DN<9>   
                                  201      M_B_CPU1_SA_DQS_DP<9>   
                                  202      GND                     
                                  203      M_B_CPU1_SA_CB<6>       
                                  204      GND                     
                                  205      M_B_CPU1_SA_CB<7>       
                                  206      GND                     
                                  207      RST_M_AB_CPU1_FPGA_N    
                                  208      GND                     
                                  209      M_B_CPU1_SA_CS_N<3>     
                                  210      GND                     
                                  211      M_B_CPU1_SA_CA<1>       
                                  212      GND                     
                                  213      M_B_CPU1_SA_CA<3>       
                                  214      GND                     
                                  215      M_B_CPU1_SA_CA<5>       
                                  216      GND                     
                                  217      M_B_CPU1_CLK_DP<1>      
                                  218      M_B_CPU1_CLK_DN<1>      
                                  219      GND                     
                                  221      M_B_CPU1_SB_CA<1>       
                                  222      GND                     
                                  223      M_B_CPU1_SB_CA<3>       
                                  224      GND                     
                                  225      M_B_CPU1_SB_CA<5>       
                                  226      GND                     
                                  227      M_B_CPU1_SB_PAR         
                                  228      GND                     
                                  229      M_B_CPU1_SB_CS_N<3>     
                                  230      GND                     
                                  233      GND                     
                                  234      M_B_CPU1_SB_CB<6>       
                                  235      GND                     
                                  236      M_B_CPU1_SB_CB<7>       
                                  237      GND                     
                                  238      M_B_CPU1_SB_DQS_DN<4>   
                                  239      M_B_CPU1_SB_DQS_DP<4>   
                                  240      GND                     
                                  241      M_B_CPU1_SB_CB<2>       
                                  242      GND                     
                                  243      M_B_CPU1_SB_CB<3>       
                                  244      GND                     
                                  245      M_B_CPU1_SB_DQ<2>       
                                  246      GND                     
                                  247      M_B_CPU1_SB_DQ<3>       
                                  248      GND                     
                                  249      M_B_CPU1_SB_DQS_DN<5>   
                                  250      M_B_CPU1_SB_DQS_DP<5>   
                                  251      GND                     
                                  252      M_B_CPU1_SB_DQ<6>       
                                  253      GND                     
                                  254      M_B_CPU1_SB_DQ<7>       
                                  255      GND                     
                                  256      M_B_CPU1_SB_DQ<10>      
                                  257      GND                     
                                  258      M_B_CPU1_SB_DQ<11>      
                                  259      GND                     
                                  260      M_B_CPU1_SB_DQS_DN<6>   
                                  261      M_B_CPU1_SB_DQS_DP<6>   
                                  262      GND                     
                                  263      M_B_CPU1_SB_DQ<14>      
                                  264      GND                     
                                  265      M_B_CPU1_SB_DQ<15>      
                                  266      GND                     
                                  267      M_B_CPU1_SB_DQ<18>      
                                  268      GND                     
                                  269      M_B_CPU1_SB_DQ<19>      
                                  270      GND                     
                                  271      M_B_CPU1_SB_DQS_DN<7>   
                                  272      M_B_CPU1_SB_DQS_DP<7>   
                                  273      GND                     
                                  274      M_B_CPU1_SB_DQ<22>      
                                  275      GND                     
                                  276      M_B_CPU1_SB_DQ<23>      
                                  277      GND                     
                                  278      M_B_CPU1_SB_DQ<26>      
                                  279      GND                     
                                  280      M_B_CPU1_SB_DQ<27>      
                                  281      GND                     
                                  282      M_B_CPU1_SB_DQS_DN<8>   
                                  283      M_B_CPU1_SB_DQS_DP<8>   
                                  284      GND                     
                                  285      M_B_CPU1_SB_DQ<30>      
                                  286      GND                     
                                  287      M_B_CPU1_SB_DQ<31>      
                                  288      GND                     
                                  G1       GND                     
                                  G2       GND                     
                                  G3       GND                     
J21              SCONN288_ADR50001P013C01-SCONNA 1        P12V_S3_AUX_CPU1_NVDIMM 
                                  3        P3V3_AUX                
                                  4        I3C_SPD_DDRABCD_CPU1_LVC1_SCL
                                  5        I3C_SPD_DDRABCD_CPU1_LVC1_SDA
                                  6        GND                     
                                  7        M_C_CPU1_SA_DQ<0>       
                                  8        GND                     
                                  9        M_C_CPU1_SA_DQ<1>       
                                  10       GND                     
                                  11       M_C_CPU1_SA_DQS_DP<0>   
                                  12       M_C_CPU1_SA_DQS_DN<0>   
                                  13       GND                     
                                  14       M_C_CPU1_SA_DQ<4>       
                                  15       GND                     
                                  16       M_C_CPU1_SA_DQ<5>       
                                  17       GND                     
                                  18       M_C_CPU1_SA_DQ<8>       
                                  19       GND                     
                                  20       M_C_CPU1_SA_DQ<9>       
                                  21       GND                     
                                  22       M_C_CPU1_SA_DQS_DP<1>   
                                  23       M_C_CPU1_SA_DQS_DN<1>   
                                  24       GND                     
                                  25       M_C_CPU1_SA_DQ<12>      
                                  26       GND                     
                                  27       M_C_CPU1_SA_DQ<13>      
                                  28       GND                     
                                  29       M_C_CPU1_SA_DQ<16>      
                                  30       GND                     
                                  31       M_C_CPU1_SA_DQ<17>      
                                  32       GND                     
                                  33       M_C_CPU1_SA_DQS_DP<2>   
                                  34       M_C_CPU1_SA_DQS_DN<2>   
                                  35       GND                     
                                  36       M_C_CPU1_SA_DQ<20>      
                                  37       GND                     
                                  38       M_C_CPU1_SA_DQ<21>      
                                  39       GND                     
                                  40       M_C_CPU1_SA_DQ<24>      
                                  41       GND                     
                                  42       M_C_CPU1_SA_DQ<25>      
                                  43       GND                     
                                  44       M_C_CPU1_SA_DQS_DP<3>   
                                  45       M_C_CPU1_SA_DQS_DN<3>   
                                  46       GND                     
                                  47       M_C_CPU1_SA_DQ<28>      
                                  48       GND                     
                                  49       M_C_CPU1_SA_DQ<29>      
                                  50       GND                     
                                  51       M_C_CPU1_SA_CB<0>       
                                  52       GND                     
                                  53       M_C_CPU1_SA_CB<1>       
                                  54       GND                     
                                  55       M_C_CPU1_SA_DQS_DP<4>   
                                  56       M_C_CPU1_SA_DQS_DN<4>   
                                  57       GND                     
                                  58       M_C_CPU1_SA_CB<4>       
                                  59       GND                     
                                  60       M_C_CPU1_SA_CB<5>       
                                  61       GND                     
                                  62       M_C_CPU1_ALERT_N        
                                  63       GND                     
                                  64       M_C_CPU1_SA_CS_N<0>     
                                  65       GND                     
                                  66       M_C_CPU1_SA_CA<0>       
                                  67       GND                     
                                  68       M_C_CPU1_SA_CA<2>       
                                  69       GND                     
                                  70       M_C_CPU1_SA_CA<4>       
                                  71       GND                     
                                  72       M_C_CPU1_SA_CA<6>       
                                  73       GND                     
                                  74       M_C_CPU1_SA_PAR         
                                  75       GND                     
                                  76       M_C_CPU1_SB_CA<0>       
                                  77       GND                     
                                  78       M_C_CPU1_SB_CA<2>       
                                  79       GND                     
                                  80       M_C_CPU1_SB_CA<4>       
                                  81       GND                     
                                  82       M_C_CPU1_SB_CA<6>       
                                  83       GND                     
                                  84       M_C_CPU1_SB_CS_N<0>     
                                  85       GND                     
                                  86       M_C_CPU1_SA_RSP<0>      
                                  87       M_C_CPU1_SB_RSP<0>      
                                  88       GND                     
                                  89       M_C_CPU1_SB_CB<4>       
                                  90       GND                     
                                  91       M_C_CPU1_SB_CB<5>       
                                  92       GND                     
                                  93       M_C_CPU1_SB_DQS_DP<9>   
                                  94       M_C_CPU1_SB_DQS_DN<9>   
                                  95       GND                     
                                  96       M_C_CPU1_SB_CB<0>       
                                  97       GND                     
                                  98       M_C_CPU1_SB_CB<1>       
                                  99       GND                     
                                  100      M_C_CPU1_SB_DQ<0>       
                                  101      GND                     
                                  102      M_C_CPU1_SB_DQ<1>       
                                  103      GND                     
                                  104      M_C_CPU1_SB_DQS_DP<0>   
                                  105      M_C_CPU1_SB_DQS_DN<0>   
                                  106      GND                     
                                  107      M_C_CPU1_SB_DQ<4>       
                                  108      GND                     
                                  109      M_C_CPU1_SB_DQ<5>       
                                  110      GND                     
                                  111      M_C_CPU1_SB_DQ<8>       
                                  112      GND                     
                                  113      M_C_CPU1_SB_DQ<9>       
                                  114      GND                     
                                  115      M_C_CPU1_SB_DQS_DP<1>   
                                  116      M_C_CPU1_SB_DQS_DN<1>   
                                  117      GND                     
                                  118      M_C_CPU1_SB_DQ<12>      
                                  119      GND                     
                                  120      M_C_CPU1_SB_DQ<13>      
                                  121      GND                     
                                  122      M_C_CPU1_SB_DQ<16>      
                                  123      GND                     
                                  124      M_C_CPU1_SB_DQ<17>      
                                  125      GND                     
                                  126      M_C_CPU1_SB_DQS_DP<2>   
                                  127      M_C_CPU1_SB_DQS_DN<2>   
                                  128      GND                     
                                  129      M_C_CPU1_SB_DQ<20>      
                                  130      GND                     
                                  131      M_C_CPU1_SB_DQ<21>      
                                  132      GND                     
                                  133      M_C_CPU1_SB_DQ<24>      
                                  134      GND                     
                                  135      M_C_CPU1_SB_DQ<25>      
                                  136      GND                     
                                  137      M_C_CPU1_SB_DQS_DP<3>   
                                  138      M_C_CPU1_SB_DQS_DN<3>   
                                  139      GND                     
                                  140      M_C_CPU1_SB_DQ<28>      
                                  141      GND                     
                                  142      M_C_CPU1_SB_DQ<29>      
                                  143      GND                     
                                  145      P12V_S3_AUX_CPU1_NVDIMM 
                                  146      P12V_S3_AUX_CPU1_NVDIMM 
                                  147      PWRGD_CHC_CPU1_DIMM1    
                                  148      PD_CHC_CPU1_DIMM1_SAA   
                                  151      GND                     
                                  152      M_C_CPU1_SA_DQ<2>       
                                  153      GND                     
                                  154      M_C_CPU1_SA_DQ<3>       
                                  155      GND                     
                                  156      M_C_CPU1_SA_DQS_DN<5>   
                                  157      M_C_CPU1_SA_DQS_DP<5>   
                                  158      GND                     
                                  159      M_C_CPU1_SA_DQ<6>       
                                  160      GND                     
                                  161      M_C_CPU1_SA_DQ<7>       
                                  162      GND                     
                                  163      M_C_CPU1_SA_DQ<10>      
                                  164      GND                     
                                  165      M_C_CPU1_SA_DQ<11>      
                                  166      GND                     
                                  167      M_C_CPU1_SA_DQS_DN<6>   
                                  168      M_C_CPU1_SA_DQS_DP<6>   
                                  169      GND                     
                                  170      M_C_CPU1_SA_DQ<14>      
                                  171      GND                     
                                  172      M_C_CPU1_SA_DQ<15>      
                                  173      GND                     
                                  174      M_C_CPU1_SA_DQ<18>      
                                  175      GND                     
                                  176      M_C_CPU1_SA_DQ<19>      
                                  177      GND                     
                                  178      M_C_CPU1_SA_DQS_DN<7>   
                                  179      M_C_CPU1_SA_DQS_DP<7>   
                                  180      GND                     
                                  181      M_C_CPU1_SA_DQ<22>      
                                  182      GND                     
                                  183      M_C_CPU1_SA_DQ<23>      
                                  184      GND                     
                                  185      M_C_CPU1_SA_DQ<26>      
                                  186      GND                     
                                  187      M_C_CPU1_SA_DQ<27>      
                                  188      GND                     
                                  189      M_C_CPU1_SA_DQS_DN<8>   
                                  190      M_C_CPU1_SA_DQS_DP<8>   
                                  191      GND                     
                                  192      M_C_CPU1_SA_DQ<30>      
                                  193      GND                     
                                  194      M_C_CPU1_SA_DQ<31>      
                                  195      GND                     
                                  196      M_C_CPU1_SA_CB<2>       
                                  197      GND                     
                                  198      M_C_CPU1_SA_CB<3>       
                                  199      GND                     
                                  200      M_C_CPU1_SA_DQS_DN<9>   
                                  201      M_C_CPU1_SA_DQS_DP<9>   
                                  202      GND                     
                                  203      M_C_CPU1_SA_CB<6>       
                                  204      GND                     
                                  205      M_C_CPU1_SA_CB<7>       
                                  206      GND                     
                                  207      RST_M_CD_CPU1_FPGA_N    
                                  208      GND                     
                                  209      M_C_CPU1_SA_CS_N<1>     
                                  210      GND                     
                                  211      M_C_CPU1_SA_CA<1>       
                                  212      GND                     
                                  213      M_C_CPU1_SA_CA<3>       
                                  214      GND                     
                                  215      M_C_CPU1_SA_CA<5>       
                                  216      GND                     
                                  217      M_C_CPU1_CLK_DP<0>      
                                  218      M_C_CPU1_CLK_DN<0>      
                                  219      GND                     
                                  221      M_C_CPU1_SB_CA<1>       
                                  222      GND                     
                                  223      M_C_CPU1_SB_CA<3>       
                                  224      GND                     
                                  225      M_C_CPU1_SB_CA<5>       
                                  226      GND                     
                                  227      M_C_CPU1_SB_PAR         
                                  228      GND                     
                                  229      M_C_CPU1_SB_CS_N<1>     
                                  230      GND                     
                                  233      GND                     
                                  234      M_C_CPU1_SB_CB<6>       
                                  235      GND                     
                                  236      M_C_CPU1_SB_CB<7>       
                                  237      GND                     
                                  238      M_C_CPU1_SB_DQS_DN<4>   
                                  239      M_C_CPU1_SB_DQS_DP<4>   
                                  240      GND                     
                                  241      M_C_CPU1_SB_CB<2>       
                                  242      GND                     
                                  243      M_C_CPU1_SB_CB<3>       
                                  244      GND                     
                                  245      M_C_CPU1_SB_DQ<2>       
                                  246      GND                     
                                  247      M_C_CPU1_SB_DQ<3>       
                                  248      GND                     
                                  249      M_C_CPU1_SB_DQS_DN<5>   
                                  250      M_C_CPU1_SB_DQS_DP<5>   
                                  251      GND                     
                                  252      M_C_CPU1_SB_DQ<6>       
                                  253      GND                     
                                  254      M_C_CPU1_SB_DQ<7>       
                                  255      GND                     
                                  256      M_C_CPU1_SB_DQ<10>      
                                  257      GND                     
                                  258      M_C_CPU1_SB_DQ<11>      
                                  259      GND                     
                                  260      M_C_CPU1_SB_DQS_DN<6>   
                                  261      M_C_CPU1_SB_DQS_DP<6>   
                                  262      GND                     
                                  263      M_C_CPU1_SB_DQ<14>      
                                  264      GND                     
                                  265      M_C_CPU1_SB_DQ<15>      
                                  266      GND                     
                                  267      M_C_CPU1_SB_DQ<18>      
                                  268      GND                     
                                  269      M_C_CPU1_SB_DQ<19>      
                                  270      GND                     
                                  271      M_C_CPU1_SB_DQS_DN<7>   
                                  272      M_C_CPU1_SB_DQS_DP<7>   
                                  273      GND                     
                                  274      M_C_CPU1_SB_DQ<22>      
                                  275      GND                     
                                  276      M_C_CPU1_SB_DQ<23>      
                                  277      GND                     
                                  278      M_C_CPU1_SB_DQ<26>      
                                  279      GND                     
                                  280      M_C_CPU1_SB_DQ<27>      
                                  281      GND                     
                                  282      M_C_CPU1_SB_DQS_DN<8>   
                                  283      M_C_CPU1_SB_DQS_DP<8>   
                                  284      GND                     
                                  285      M_C_CPU1_SB_DQ<30>      
                                  286      GND                     
                                  287      M_C_CPU1_SB_DQ<31>      
                                  288      GND                     
                                  G1       GND                     
                                  G2       GND                     
                                  G3       GND                     
J22              SCONN288_ADR50001P003C01-SCONNA 1        P12V_S3_AUX_CPU1_NVDIMM 
                                  3        P3V3_AUX                
                                  4        I3C_SPD_DDRABCD_CPU1_LVC1_SCL
                                  5        I3C_SPD_DDRABCD_CPU1_LVC1_SDA
                                  6        GND                     
                                  7        M_C_CPU1_SA_DQ<0>       
                                  8        GND                     
                                  9        M_C_CPU1_SA_DQ<1>       
                                  10       GND                     
                                  11       M_C_CPU1_SA_DQS_DP<0>   
                                  12       M_C_CPU1_SA_DQS_DN<0>   
                                  13       GND                     
                                  14       M_C_CPU1_SA_DQ<4>       
                                  15       GND                     
                                  16       M_C_CPU1_SA_DQ<5>       
                                  17       GND                     
                                  18       M_C_CPU1_SA_DQ<8>       
                                  19       GND                     
                                  20       M_C_CPU1_SA_DQ<9>       
                                  21       GND                     
                                  22       M_C_CPU1_SA_DQS_DP<1>   
                                  23       M_C_CPU1_SA_DQS_DN<1>   
                                  24       GND                     
                                  25       M_C_CPU1_SA_DQ<12>      
                                  26       GND                     
                                  27       M_C_CPU1_SA_DQ<13>      
                                  28       GND                     
                                  29       M_C_CPU1_SA_DQ<16>      
                                  30       GND                     
                                  31       M_C_CPU1_SA_DQ<17>      
                                  32       GND                     
                                  33       M_C_CPU1_SA_DQS_DP<2>   
                                  34       M_C_CPU1_SA_DQS_DN<2>   
                                  35       GND                     
                                  36       M_C_CPU1_SA_DQ<20>      
                                  37       GND                     
                                  38       M_C_CPU1_SA_DQ<21>      
                                  39       GND                     
                                  40       M_C_CPU1_SA_DQ<24>      
                                  41       GND                     
                                  42       M_C_CPU1_SA_DQ<25>      
                                  43       GND                     
                                  44       M_C_CPU1_SA_DQS_DP<3>   
                                  45       M_C_CPU1_SA_DQS_DN<3>   
                                  46       GND                     
                                  47       M_C_CPU1_SA_DQ<28>      
                                  48       GND                     
                                  49       M_C_CPU1_SA_DQ<29>      
                                  50       GND                     
                                  51       M_C_CPU1_SA_CB<0>       
                                  52       GND                     
                                  53       M_C_CPU1_SA_CB<1>       
                                  54       GND                     
                                  55       M_C_CPU1_SA_DQS_DP<4>   
                                  56       M_C_CPU1_SA_DQS_DN<4>   
                                  57       GND                     
                                  58       M_C_CPU1_SA_CB<4>       
                                  59       GND                     
                                  60       M_C_CPU1_SA_CB<5>       
                                  61       GND                     
                                  62       M_C_CPU1_ALERT_N        
                                  63       GND                     
                                  64       M_C_CPU1_SA_CS_N<2>     
                                  65       GND                     
                                  66       M_C_CPU1_SA_CA<0>       
                                  67       GND                     
                                  68       M_C_CPU1_SA_CA<2>       
                                  69       GND                     
                                  70       M_C_CPU1_SA_CA<4>       
                                  71       GND                     
                                  72       M_C_CPU1_SA_CA<6>       
                                  73       GND                     
                                  74       M_C_CPU1_SA_PAR         
                                  75       GND                     
                                  76       M_C_CPU1_SB_CA<0>       
                                  77       GND                     
                                  78       M_C_CPU1_SB_CA<2>       
                                  79       GND                     
                                  80       M_C_CPU1_SB_CA<4>       
                                  81       GND                     
                                  82       M_C_CPU1_SB_CA<6>       
                                  83       GND                     
                                  84       M_C_CPU1_SB_CS_N<2>     
                                  85       GND                     
                                  86       M_C_CPU1_SA_RSP<1>      
                                  87       M_C_CPU1_SB_RSP<1>      
                                  88       GND                     
                                  89       M_C_CPU1_SB_CB<4>       
                                  90       GND                     
                                  91       M_C_CPU1_SB_CB<5>       
                                  92       GND                     
                                  93       M_C_CPU1_SB_DQS_DP<9>   
                                  94       M_C_CPU1_SB_DQS_DN<9>   
                                  95       GND                     
                                  96       M_C_CPU1_SB_CB<0>       
                                  97       GND                     
                                  98       M_C_CPU1_SB_CB<1>       
                                  99       GND                     
                                  100      M_C_CPU1_SB_DQ<0>       
                                  101      GND                     
                                  102      M_C_CPU1_SB_DQ<1>       
                                  103      GND                     
                                  104      M_C_CPU1_SB_DQS_DP<0>   
                                  105      M_C_CPU1_SB_DQS_DN<0>   
                                  106      GND                     
                                  107      M_C_CPU1_SB_DQ<4>       
                                  108      GND                     
                                  109      M_C_CPU1_SB_DQ<5>       
                                  110      GND                     
                                  111      M_C_CPU1_SB_DQ<8>       
                                  112      GND                     
                                  113      M_C_CPU1_SB_DQ<9>       
                                  114      GND                     
                                  115      M_C_CPU1_SB_DQS_DP<1>   
                                  116      M_C_CPU1_SB_DQS_DN<1>   
                                  117      GND                     
                                  118      M_C_CPU1_SB_DQ<12>      
                                  119      GND                     
                                  120      M_C_CPU1_SB_DQ<13>      
                                  121      GND                     
                                  122      M_C_CPU1_SB_DQ<16>      
                                  123      GND                     
                                  124      M_C_CPU1_SB_DQ<17>      
                                  125      GND                     
                                  126      M_C_CPU1_SB_DQS_DP<2>   
                                  127      M_C_CPU1_SB_DQS_DN<2>   
                                  128      GND                     
                                  129      M_C_CPU1_SB_DQ<20>      
                                  130      GND                     
                                  131      M_C_CPU1_SB_DQ<21>      
                                  132      GND                     
                                  133      M_C_CPU1_SB_DQ<24>      
                                  134      GND                     
                                  135      M_C_CPU1_SB_DQ<25>      
                                  136      GND                     
                                  137      M_C_CPU1_SB_DQS_DP<3>   
                                  138      M_C_CPU1_SB_DQS_DN<3>   
                                  139      GND                     
                                  140      M_C_CPU1_SB_DQ<28>      
                                  141      GND                     
                                  142      M_C_CPU1_SB_DQ<29>      
                                  143      GND                     
                                  145      P12V_S3_AUX_CPU1_NVDIMM 
                                  146      P12V_S3_AUX_CPU1_NVDIMM 
                                  147      PWRGD_CHC_CPU1_DIMM2    
                                  148      PD_CHC_CPU1_DIMM2_SAA   
                                  151      GND                     
                                  152      M_C_CPU1_SA_DQ<2>       
                                  153      GND                     
                                  154      M_C_CPU1_SA_DQ<3>       
                                  155      GND                     
                                  156      M_C_CPU1_SA_DQS_DN<5>   
                                  157      M_C_CPU1_SA_DQS_DP<5>   
                                  158      GND                     
                                  159      M_C_CPU1_SA_DQ<6>       
                                  160      GND                     
                                  161      M_C_CPU1_SA_DQ<7>       
                                  162      GND                     
                                  163      M_C_CPU1_SA_DQ<10>      
                                  164      GND                     
                                  165      M_C_CPU1_SA_DQ<11>      
                                  166      GND                     
                                  167      M_C_CPU1_SA_DQS_DN<6>   
                                  168      M_C_CPU1_SA_DQS_DP<6>   
                                  169      GND                     
                                  170      M_C_CPU1_SA_DQ<14>      
                                  171      GND                     
                                  172      M_C_CPU1_SA_DQ<15>      
                                  173      GND                     
                                  174      M_C_CPU1_SA_DQ<18>      
                                  175      GND                     
                                  176      M_C_CPU1_SA_DQ<19>      
                                  177      GND                     
                                  178      M_C_CPU1_SA_DQS_DN<7>   
                                  179      M_C_CPU1_SA_DQS_DP<7>   
                                  180      GND                     
                                  181      M_C_CPU1_SA_DQ<22>      
                                  182      GND                     
                                  183      M_C_CPU1_SA_DQ<23>      
                                  184      GND                     
                                  185      M_C_CPU1_SA_DQ<26>      
                                  186      GND                     
                                  187      M_C_CPU1_SA_DQ<27>      
                                  188      GND                     
                                  189      M_C_CPU1_SA_DQS_DN<8>   
                                  190      M_C_CPU1_SA_DQS_DP<8>   
                                  191      GND                     
                                  192      M_C_CPU1_SA_DQ<30>      
                                  193      GND                     
                                  194      M_C_CPU1_SA_DQ<31>      
                                  195      GND                     
                                  196      M_C_CPU1_SA_CB<2>       
                                  197      GND                     
                                  198      M_C_CPU1_SA_CB<3>       
                                  199      GND                     
                                  200      M_C_CPU1_SA_DQS_DN<9>   
                                  201      M_C_CPU1_SA_DQS_DP<9>   
                                  202      GND                     
                                  203      M_C_CPU1_SA_CB<6>       
                                  204      GND                     
                                  205      M_C_CPU1_SA_CB<7>       
                                  206      GND                     
                                  207      RST_M_CD_CPU1_FPGA_N    
                                  208      GND                     
                                  209      M_C_CPU1_SA_CS_N<3>     
                                  210      GND                     
                                  211      M_C_CPU1_SA_CA<1>       
                                  212      GND                     
                                  213      M_C_CPU1_SA_CA<3>       
                                  214      GND                     
                                  215      M_C_CPU1_SA_CA<5>       
                                  216      GND                     
                                  217      M_C_CPU1_CLK_DP<1>      
                                  218      M_C_CPU1_CLK_DN<1>      
                                  219      GND                     
                                  221      M_C_CPU1_SB_CA<1>       
                                  222      GND                     
                                  223      M_C_CPU1_SB_CA<3>       
                                  224      GND                     
                                  225      M_C_CPU1_SB_CA<5>       
                                  226      GND                     
                                  227      M_C_CPU1_SB_PAR         
                                  228      GND                     
                                  229      M_C_CPU1_SB_CS_N<3>     
                                  230      GND                     
                                  233      GND                     
                                  234      M_C_CPU1_SB_CB<6>       
                                  235      GND                     
                                  236      M_C_CPU1_SB_CB<7>       
                                  237      GND                     
                                  238      M_C_CPU1_SB_DQS_DN<4>   
                                  239      M_C_CPU1_SB_DQS_DP<4>   
                                  240      GND                     
                                  241      M_C_CPU1_SB_CB<2>       
                                  242      GND                     
                                  243      M_C_CPU1_SB_CB<3>       
                                  244      GND                     
                                  245      M_C_CPU1_SB_DQ<2>       
                                  246      GND                     
                                  247      M_C_CPU1_SB_DQ<3>       
                                  248      GND                     
                                  249      M_C_CPU1_SB_DQS_DN<5>   
                                  250      M_C_CPU1_SB_DQS_DP<5>   
                                  251      GND                     
                                  252      M_C_CPU1_SB_DQ<6>       
                                  253      GND                     
                                  254      M_C_CPU1_SB_DQ<7>       
                                  255      GND                     
                                  256      M_C_CPU1_SB_DQ<10>      
                                  257      GND                     
                                  258      M_C_CPU1_SB_DQ<11>      
                                  259      GND                     
                                  260      M_C_CPU1_SB_DQS_DN<6>   
                                  261      M_C_CPU1_SB_DQS_DP<6>   
                                  262      GND                     
                                  263      M_C_CPU1_SB_DQ<14>      
                                  264      GND                     
                                  265      M_C_CPU1_SB_DQ<15>      
                                  266      GND                     
                                  267      M_C_CPU1_SB_DQ<18>      
                                  268      GND                     
                                  269      M_C_CPU1_SB_DQ<19>      
                                  270      GND                     
                                  271      M_C_CPU1_SB_DQS_DN<7>   
                                  272      M_C_CPU1_SB_DQS_DP<7>   
                                  273      GND                     
                                  274      M_C_CPU1_SB_DQ<22>      
                                  275      GND                     
                                  276      M_C_CPU1_SB_DQ<23>      
                                  277      GND                     
                                  278      M_C_CPU1_SB_DQ<26>      
                                  279      GND                     
                                  280      M_C_CPU1_SB_DQ<27>      
                                  281      GND                     
                                  282      M_C_CPU1_SB_DQS_DN<8>   
                                  283      M_C_CPU1_SB_DQS_DP<8>   
                                  284      GND                     
                                  285      M_C_CPU1_SB_DQ<30>      
                                  286      GND                     
                                  287      M_C_CPU1_SB_DQ<31>      
                                  288      GND                     
                                  G1       GND                     
                                  G2       GND                     
                                  G3       GND                     
J23              SCONN288_ADR50001P013C01-SCONNA 1        P12V_S3_AUX_CPU1_NVDIMM 
                                  3        P3V3_AUX                
                                  4        I3C_SPD_DDRABCD_CPU1_LVC1_SCL
                                  5        I3C_SPD_DDRABCD_CPU1_LVC1_SDA
                                  6        GND                     
                                  7        M_D_CPU1_SA_DQ<0>       
                                  8        GND                     
                                  9        M_D_CPU1_SA_DQ<1>       
                                  10       GND                     
                                  11       M_D_CPU1_SA_DQS_DP<0>   
                                  12       M_D_CPU1_SA_DQS_DN<0>   
                                  13       GND                     
                                  14       M_D_CPU1_SA_DQ<4>       
                                  15       GND                     
                                  16       M_D_CPU1_SA_DQ<5>       
                                  17       GND                     
                                  18       M_D_CPU1_SA_DQ<8>       
                                  19       GND                     
                                  20       M_D_CPU1_SA_DQ<9>       
                                  21       GND                     
                                  22       M_D_CPU1_SA_DQS_DP<1>   
                                  23       M_D_CPU1_SA_DQS_DN<1>   
                                  24       GND                     
                                  25       M_D_CPU1_SA_DQ<12>      
                                  26       GND                     
                                  27       M_D_CPU1_SA_DQ<13>      
                                  28       GND                     
                                  29       M_D_CPU1_SA_DQ<16>      
                                  30       GND                     
                                  31       M_D_CPU1_SA_DQ<17>      
                                  32       GND                     
                                  33       M_D_CPU1_SA_DQS_DP<2>   
                                  34       M_D_CPU1_SA_DQS_DN<2>   
                                  35       GND                     
                                  36       M_D_CPU1_SA_DQ<20>      
                                  37       GND                     
                                  38       M_D_CPU1_SA_DQ<21>      
                                  39       GND                     
                                  40       M_D_CPU1_SA_DQ<24>      
                                  41       GND                     
                                  42       M_D_CPU1_SA_DQ<25>      
                                  43       GND                     
                                  44       M_D_CPU1_SA_DQS_DP<3>   
                                  45       M_D_CPU1_SA_DQS_DN<3>   
                                  46       GND                     
                                  47       M_D_CPU1_SA_DQ<28>      
                                  48       GND                     
                                  49       M_D_CPU1_SA_DQ<29>      
                                  50       GND                     
                                  51       M_D_CPU1_SA_CB<0>       
                                  52       GND                     
                                  53       M_D_CPU1_SA_CB<1>       
                                  54       GND                     
                                  55       M_D_CPU1_SA_DQS_DP<4>   
                                  56       M_D_CPU1_SA_DQS_DN<4>   
                                  57       GND                     
                                  58       M_D_CPU1_SA_CB<4>       
                                  59       GND                     
                                  60       M_D_CPU1_SA_CB<5>       
                                  61       GND                     
                                  62       M_D_CPU1_ALERT_N        
                                  63       GND                     
                                  64       M_D_CPU1_SA_CS_N<0>     
                                  65       GND                     
                                  66       M_D_CPU1_SA_CA<0>       
                                  67       GND                     
                                  68       M_D_CPU1_SA_CA<2>       
                                  69       GND                     
                                  70       M_D_CPU1_SA_CA<4>       
                                  71       GND                     
                                  72       M_D_CPU1_SA_CA<6>       
                                  73       GND                     
                                  74       M_D_CPU1_SA_PAR         
                                  75       GND                     
                                  76       M_D_CPU1_SB_CA<0>       
                                  77       GND                     
                                  78       M_D_CPU1_SB_CA<2>       
                                  79       GND                     
                                  80       M_D_CPU1_SB_CA<4>       
                                  81       GND                     
                                  82       M_D_CPU1_SB_CA<6>       
                                  83       GND                     
                                  84       M_D_CPU1_SB_CS_N<0>     
                                  85       GND                     
                                  86       M_D_CPU1_SA_RSP<0>      
                                  87       M_D_CPU1_SB_RSP<0>      
                                  88       GND                     
                                  89       M_D_CPU1_SB_CB<4>       
                                  90       GND                     
                                  91       M_D_CPU1_SB_CB<5>       
                                  92       GND                     
                                  93       M_D_CPU1_SB_DQS_DP<9>   
                                  94       M_D_CPU1_SB_DQS_DN<9>   
                                  95       GND                     
                                  96       M_D_CPU1_SB_CB<0>       
                                  97       GND                     
                                  98       M_D_CPU1_SB_CB<1>       
                                  99       GND                     
                                  100      M_D_CPU1_SB_DQ<0>       
                                  101      GND                     
                                  102      M_D_CPU1_SB_DQ<1>       
                                  103      GND                     
                                  104      M_D_CPU1_SB_DQS_DP<0>   
                                  105      M_D_CPU1_SB_DQS_DN<0>   
                                  106      GND                     
                                  107      M_D_CPU1_SB_DQ<4>       
                                  108      GND                     
                                  109      M_D_CPU1_SB_DQ<5>       
                                  110      GND                     
                                  111      M_D_CPU1_SB_DQ<8>       
                                  112      GND                     
                                  113      M_D_CPU1_SB_DQ<9>       
                                  114      GND                     
                                  115      M_D_CPU1_SB_DQS_DP<1>   
                                  116      M_D_CPU1_SB_DQS_DN<1>   
                                  117      GND                     
                                  118      M_D_CPU1_SB_DQ<12>      
                                  119      GND                     
                                  120      M_D_CPU1_SB_DQ<13>      
                                  121      GND                     
                                  122      M_D_CPU1_SB_DQ<16>      
                                  123      GND                     
                                  124      M_D_CPU1_SB_DQ<17>      
                                  125      GND                     
                                  126      M_D_CPU1_SB_DQS_DP<2>   
                                  127      M_D_CPU1_SB_DQS_DN<2>   
                                  128      GND                     
                                  129      M_D_CPU1_SB_DQ<20>      
                                  130      GND                     
                                  131      M_D_CPU1_SB_DQ<21>      
                                  132      GND                     
                                  133      M_D_CPU1_SB_DQ<24>      
                                  134      GND                     
                                  135      M_D_CPU1_SB_DQ<25>      
                                  136      GND                     
                                  137      M_D_CPU1_SB_DQS_DP<3>   
                                  138      M_D_CPU1_SB_DQS_DN<3>   
                                  139      GND                     
                                  140      M_D_CPU1_SB_DQ<28>      
                                  141      GND                     
                                  142      M_D_CPU1_SB_DQ<29>      
                                  143      GND                     
                                  145      P12V_S3_AUX_CPU1_NVDIMM 
                                  146      P12V_S3_AUX_CPU1_NVDIMM 
                                  147      PWRGD_CHD_CPU1_DIMM1    
                                  148      PD_CHD_CPU1_DIMM1_SAA   
                                  151      GND                     
                                  152      M_D_CPU1_SA_DQ<2>       
                                  153      GND                     
                                  154      M_D_CPU1_SA_DQ<3>       
                                  155      GND                     
                                  156      M_D_CPU1_SA_DQS_DN<5>   
                                  157      M_D_CPU1_SA_DQS_DP<5>   
                                  158      GND                     
                                  159      M_D_CPU1_SA_DQ<6>       
                                  160      GND                     
                                  161      M_D_CPU1_SA_DQ<7>       
                                  162      GND                     
                                  163      M_D_CPU1_SA_DQ<10>      
                                  164      GND                     
                                  165      M_D_CPU1_SA_DQ<11>      
                                  166      GND                     
                                  167      M_D_CPU1_SA_DQS_DN<6>   
                                  168      M_D_CPU1_SA_DQS_DP<6>   
                                  169      GND                     
                                  170      M_D_CPU1_SA_DQ<14>      
                                  171      GND                     
                                  172      M_D_CPU1_SA_DQ<15>      
                                  173      GND                     
                                  174      M_D_CPU1_SA_DQ<18>      
                                  175      GND                     
                                  176      M_D_CPU1_SA_DQ<19>      
                                  177      GND                     
                                  178      M_D_CPU1_SA_DQS_DN<7>   
                                  179      M_D_CPU1_SA_DQS_DP<7>   
                                  180      GND                     
                                  181      M_D_CPU1_SA_DQ<22>      
                                  182      GND                     
                                  183      M_D_CPU1_SA_DQ<23>      
                                  184      GND                     
                                  185      M_D_CPU1_SA_DQ<26>      
                                  186      GND                     
                                  187      M_D_CPU1_SA_DQ<27>      
                                  188      GND                     
                                  189      M_D_CPU1_SA_DQS_DN<8>   
                                  190      M_D_CPU1_SA_DQS_DP<8>   
                                  191      GND                     
                                  192      M_D_CPU1_SA_DQ<30>      
                                  193      GND                     
                                  194      M_D_CPU1_SA_DQ<31>      
                                  195      GND                     
                                  196      M_D_CPU1_SA_CB<2>       
                                  197      GND                     
                                  198      M_D_CPU1_SA_CB<3>       
                                  199      GND                     
                                  200      M_D_CPU1_SA_DQS_DN<9>   
                                  201      M_D_CPU1_SA_DQS_DP<9>   
                                  202      GND                     
                                  203      M_D_CPU1_SA_CB<6>       
                                  204      GND                     
                                  205      M_D_CPU1_SA_CB<7>       
                                  206      GND                     
                                  207      RST_M_CD_CPU1_FPGA_N    
                                  208      GND                     
                                  209      M_D_CPU1_SA_CS_N<1>     
                                  210      GND                     
                                  211      M_D_CPU1_SA_CA<1>       
                                  212      GND                     
                                  213      M_D_CPU1_SA_CA<3>       
                                  214      GND                     
                                  215      M_D_CPU1_SA_CA<5>       
                                  216      GND                     
                                  217      M_D_CPU1_CLK_DP<0>      
                                  218      M_D_CPU1_CLK_DN<0>      
                                  219      GND                     
                                  221      M_D_CPU1_SB_CA<1>       
                                  222      GND                     
                                  223      M_D_CPU1_SB_CA<3>       
                                  224      GND                     
                                  225      M_D_CPU1_SB_CA<5>       
                                  226      GND                     
                                  227      M_D_CPU1_SB_PAR         
                                  228      GND                     
                                  229      M_D_CPU1_SB_CS_N<1>     
                                  230      GND                     
                                  233      GND                     
                                  234      M_D_CPU1_SB_CB<6>       
                                  235      GND                     
                                  236      M_D_CPU1_SB_CB<7>       
                                  237      GND                     
                                  238      M_D_CPU1_SB_DQS_DN<4>   
                                  239      M_D_CPU1_SB_DQS_DP<4>   
                                  240      GND                     
                                  241      M_D_CPU1_SB_CB<2>       
                                  242      GND                     
                                  243      M_D_CPU1_SB_CB<3>       
                                  244      GND                     
                                  245      M_D_CPU1_SB_DQ<2>       
                                  246      GND                     
                                  247      M_D_CPU1_SB_DQ<3>       
                                  248      GND                     
                                  249      M_D_CPU1_SB_DQS_DN<5>   
                                  250      M_D_CPU1_SB_DQS_DP<5>   
                                  251      GND                     
                                  252      M_D_CPU1_SB_DQ<6>       
                                  253      GND                     
                                  254      M_D_CPU1_SB_DQ<7>       
                                  255      GND                     
                                  256      M_D_CPU1_SB_DQ<10>      
                                  257      GND                     
                                  258      M_D_CPU1_SB_DQ<11>      
                                  259      GND                     
                                  260      M_D_CPU1_SB_DQS_DN<6>   
                                  261      M_D_CPU1_SB_DQS_DP<6>   
                                  262      GND                     
                                  263      M_D_CPU1_SB_DQ<14>      
                                  264      GND                     
                                  265      M_D_CPU1_SB_DQ<15>      
                                  266      GND                     
                                  267      M_D_CPU1_SB_DQ<18>      
                                  268      GND                     
                                  269      M_D_CPU1_SB_DQ<19>      
                                  270      GND                     
                                  271      M_D_CPU1_SB_DQS_DN<7>   
                                  272      M_D_CPU1_SB_DQS_DP<7>   
                                  273      GND                     
                                  274      M_D_CPU1_SB_DQ<22>      
                                  275      GND                     
                                  276      M_D_CPU1_SB_DQ<23>      
                                  277      GND                     
                                  278      M_D_CPU1_SB_DQ<26>      
                                  279      GND                     
                                  280      M_D_CPU1_SB_DQ<27>      
                                  281      GND                     
                                  282      M_D_CPU1_SB_DQS_DN<8>   
                                  283      M_D_CPU1_SB_DQS_DP<8>   
                                  284      GND                     
                                  285      M_D_CPU1_SB_DQ<30>      
                                  286      GND                     
                                  287      M_D_CPU1_SB_DQ<31>      
                                  288      GND                     
                                  G1       GND                     
                                  G2       GND                     
                                  G3       GND                     
J24              SCONN288_ADR50001P003C01-SCONNA 1        P12V_S3_AUX_CPU1_NVDIMM 
                                  3        P3V3_AUX                
                                  4        I3C_SPD_DDRABCD_CPU1_LVC1_SCL
                                  5        I3C_SPD_DDRABCD_CPU1_LVC1_SDA
                                  6        GND                     
                                  7        M_D_CPU1_SA_DQ<0>       
                                  8        GND                     
                                  9        M_D_CPU1_SA_DQ<1>       
                                  10       GND                     
                                  11       M_D_CPU1_SA_DQS_DP<0>   
                                  12       M_D_CPU1_SA_DQS_DN<0>   
                                  13       GND                     
                                  14       M_D_CPU1_SA_DQ<4>       
                                  15       GND                     
                                  16       M_D_CPU1_SA_DQ<5>       
                                  17       GND                     
                                  18       M_D_CPU1_SA_DQ<8>       
                                  19       GND                     
                                  20       M_D_CPU1_SA_DQ<9>       
                                  21       GND                     
                                  22       M_D_CPU1_SA_DQS_DP<1>   
                                  23       M_D_CPU1_SA_DQS_DN<1>   
                                  24       GND                     
                                  25       M_D_CPU1_SA_DQ<12>      
                                  26       GND                     
                                  27       M_D_CPU1_SA_DQ<13>      
                                  28       GND                     
                                  29       M_D_CPU1_SA_DQ<16>      
                                  30       GND                     
                                  31       M_D_CPU1_SA_DQ<17>      
                                  32       GND                     
                                  33       M_D_CPU1_SA_DQS_DP<2>   
                                  34       M_D_CPU1_SA_DQS_DN<2>   
                                  35       GND                     
                                  36       M_D_CPU1_SA_DQ<20>      
                                  37       GND                     
                                  38       M_D_CPU1_SA_DQ<21>      
                                  39       GND                     
                                  40       M_D_CPU1_SA_DQ<24>      
                                  41       GND                     
                                  42       M_D_CPU1_SA_DQ<25>      
                                  43       GND                     
                                  44       M_D_CPU1_SA_DQS_DP<3>   
                                  45       M_D_CPU1_SA_DQS_DN<3>   
                                  46       GND                     
                                  47       M_D_CPU1_SA_DQ<28>      
                                  48       GND                     
                                  49       M_D_CPU1_SA_DQ<29>      
                                  50       GND                     
                                  51       M_D_CPU1_SA_CB<0>       
                                  52       GND                     
                                  53       M_D_CPU1_SA_CB<1>       
                                  54       GND                     
                                  55       M_D_CPU1_SA_DQS_DP<4>   
                                  56       M_D_CPU1_SA_DQS_DN<4>   
                                  57       GND                     
                                  58       M_D_CPU1_SA_CB<4>       
                                  59       GND                     
                                  60       M_D_CPU1_SA_CB<5>       
                                  61       GND                     
                                  62       M_D_CPU1_ALERT_N        
                                  63       GND                     
                                  64       M_D_CPU1_SA_CS_N<2>     
                                  65       GND                     
                                  66       M_D_CPU1_SA_CA<0>       
                                  67       GND                     
                                  68       M_D_CPU1_SA_CA<2>       
                                  69       GND                     
                                  70       M_D_CPU1_SA_CA<4>       
                                  71       GND                     
                                  72       M_D_CPU1_SA_CA<6>       
                                  73       GND                     
                                  74       M_D_CPU1_SA_PAR         
                                  75       GND                     
                                  76       M_D_CPU1_SB_CA<0>       
                                  77       GND                     
                                  78       M_D_CPU1_SB_CA<2>       
                                  79       GND                     
                                  80       M_D_CPU1_SB_CA<4>       
                                  81       GND                     
                                  82       M_D_CPU1_SB_CA<6>       
                                  83       GND                     
                                  84       M_D_CPU1_SB_CS_N<2>     
                                  85       GND                     
                                  86       M_D_CPU1_SA_RSP<1>      
                                  87       M_D_CPU1_SB_RSP<1>      
                                  88       GND                     
                                  89       M_D_CPU1_SB_CB<4>       
                                  90       GND                     
                                  91       M_D_CPU1_SB_CB<5>       
                                  92       GND                     
                                  93       M_D_CPU1_SB_DQS_DP<9>   
                                  94       M_D_CPU1_SB_DQS_DN<9>   
                                  95       GND                     
                                  96       M_D_CPU1_SB_CB<0>       
                                  97       GND                     
                                  98       M_D_CPU1_SB_CB<1>       
                                  99       GND                     
                                  100      M_D_CPU1_SB_DQ<0>       
                                  101      GND                     
                                  102      M_D_CPU1_SB_DQ<1>       
                                  103      GND                     
                                  104      M_D_CPU1_SB_DQS_DP<0>   
                                  105      M_D_CPU1_SB_DQS_DN<0>   
                                  106      GND                     
                                  107      M_D_CPU1_SB_DQ<4>       
                                  108      GND                     
                                  109      M_D_CPU1_SB_DQ<5>       
                                  110      GND                     
                                  111      M_D_CPU1_SB_DQ<8>       
                                  112      GND                     
                                  113      M_D_CPU1_SB_DQ<9>       
                                  114      GND                     
                                  115      M_D_CPU1_SB_DQS_DP<1>   
                                  116      M_D_CPU1_SB_DQS_DN<1>   
                                  117      GND                     
                                  118      M_D_CPU1_SB_DQ<12>      
                                  119      GND                     
                                  120      M_D_CPU1_SB_DQ<13>      
                                  121      GND                     
                                  122      M_D_CPU1_SB_DQ<16>      
                                  123      GND                     
                                  124      M_D_CPU1_SB_DQ<17>      
                                  125      GND                     
                                  126      M_D_CPU1_SB_DQS_DP<2>   
                                  127      M_D_CPU1_SB_DQS_DN<2>   
                                  128      GND                     
                                  129      M_D_CPU1_SB_DQ<20>      
                                  130      GND                     
                                  131      M_D_CPU1_SB_DQ<21>      
                                  132      GND                     
                                  133      M_D_CPU1_SB_DQ<24>      
                                  134      GND                     
                                  135      M_D_CPU1_SB_DQ<25>      
                                  136      GND                     
                                  137      M_D_CPU1_SB_DQS_DP<3>   
                                  138      M_D_CPU1_SB_DQS_DN<3>   
                                  139      GND                     
                                  140      M_D_CPU1_SB_DQ<28>      
                                  141      GND                     
                                  142      M_D_CPU1_SB_DQ<29>      
                                  143      GND                     
                                  145      P12V_S3_AUX_CPU1_NVDIMM 
                                  146      P12V_S3_AUX_CPU1_NVDIMM 
                                  147      PWRGD_CHD_CPU1_DIMM2    
                                  148      PD_CHD_CPU1_DIMM2_SAA   
                                  151      GND                     
                                  152      M_D_CPU1_SA_DQ<2>       
                                  153      GND                     
                                  154      M_D_CPU1_SA_DQ<3>       
                                  155      GND                     
                                  156      M_D_CPU1_SA_DQS_DN<5>   
                                  157      M_D_CPU1_SA_DQS_DP<5>   
                                  158      GND                     
                                  159      M_D_CPU1_SA_DQ<6>       
                                  160      GND                     
                                  161      M_D_CPU1_SA_DQ<7>       
                                  162      GND                     
                                  163      M_D_CPU1_SA_DQ<10>      
                                  164      GND                     
                                  165      M_D_CPU1_SA_DQ<11>      
                                  166      GND                     
                                  167      M_D_CPU1_SA_DQS_DN<6>   
                                  168      M_D_CPU1_SA_DQS_DP<6>   
                                  169      GND                     
                                  170      M_D_CPU1_SA_DQ<14>      
                                  171      GND                     
                                  172      M_D_CPU1_SA_DQ<15>      
                                  173      GND                     
                                  174      M_D_CPU1_SA_DQ<18>      
                                  175      GND                     
                                  176      M_D_CPU1_SA_DQ<19>      
                                  177      GND                     
                                  178      M_D_CPU1_SA_DQS_DN<7>   
                                  179      M_D_CPU1_SA_DQS_DP<7>   
                                  180      GND                     
                                  181      M_D_CPU1_SA_DQ<22>      
                                  182      GND                     
                                  183      M_D_CPU1_SA_DQ<23>      
                                  184      GND                     
                                  185      M_D_CPU1_SA_DQ<26>      
                                  186      GND                     
                                  187      M_D_CPU1_SA_DQ<27>      
                                  188      GND                     
                                  189      M_D_CPU1_SA_DQS_DN<8>   
                                  190      M_D_CPU1_SA_DQS_DP<8>   
                                  191      GND                     
                                  192      M_D_CPU1_SA_DQ<30>      
                                  193      GND                     
                                  194      M_D_CPU1_SA_DQ<31>      
                                  195      GND                     
                                  196      M_D_CPU1_SA_CB<2>       
                                  197      GND                     
                                  198      M_D_CPU1_SA_CB<3>       
                                  199      GND                     
                                  200      M_D_CPU1_SA_DQS_DN<9>   
                                  201      M_D_CPU1_SA_DQS_DP<9>   
                                  202      GND                     
                                  203      M_D_CPU1_SA_CB<6>       
                                  204      GND                     
                                  205      M_D_CPU1_SA_CB<7>       
                                  206      GND                     
                                  207      RST_M_CD_CPU1_FPGA_N    
                                  208      GND                     
                                  209      M_D_CPU1_SA_CS_N<3>     
                                  210      GND                     
                                  211      M_D_CPU1_SA_CA<1>       
                                  212      GND                     
                                  213      M_D_CPU1_SA_CA<3>       
                                  214      GND                     
                                  215      M_D_CPU1_SA_CA<5>       
                                  216      GND                     
                                  217      M_D_CPU1_CLK_DP<1>      
                                  218      M_D_CPU1_CLK_DN<1>      
                                  219      GND                     
                                  221      M_D_CPU1_SB_CA<1>       
                                  222      GND                     
                                  223      M_D_CPU1_SB_CA<3>       
                                  224      GND                     
                                  225      M_D_CPU1_SB_CA<5>       
                                  226      GND                     
                                  227      M_D_CPU1_SB_PAR         
                                  228      GND                     
                                  229      M_D_CPU1_SB_CS_N<3>     
                                  230      GND                     
                                  233      GND                     
                                  234      M_D_CPU1_SB_CB<6>       
                                  235      GND                     
                                  236      M_D_CPU1_SB_CB<7>       
                                  237      GND                     
                                  238      M_D_CPU1_SB_DQS_DN<4>   
                                  239      M_D_CPU1_SB_DQS_DP<4>   
                                  240      GND                     
                                  241      M_D_CPU1_SB_CB<2>       
                                  242      GND                     
                                  243      M_D_CPU1_SB_CB<3>       
                                  244      GND                     
                                  245      M_D_CPU1_SB_DQ<2>       
                                  246      GND                     
                                  247      M_D_CPU1_SB_DQ<3>       
                                  248      GND                     
                                  249      M_D_CPU1_SB_DQS_DN<5>   
                                  250      M_D_CPU1_SB_DQS_DP<5>   
                                  251      GND                     
                                  252      M_D_CPU1_SB_DQ<6>       
                                  253      GND                     
                                  254      M_D_CPU1_SB_DQ<7>       
                                  255      GND                     
                                  256      M_D_CPU1_SB_DQ<10>      
                                  257      GND                     
                                  258      M_D_CPU1_SB_DQ<11>      
                                  259      GND                     
                                  260      M_D_CPU1_SB_DQS_DN<6>   
                                  261      M_D_CPU1_SB_DQS_DP<6>   
                                  262      GND                     
                                  263      M_D_CPU1_SB_DQ<14>      
                                  264      GND                     
                                  265      M_D_CPU1_SB_DQ<15>      
                                  266      GND                     
                                  267      M_D_CPU1_SB_DQ<18>      
                                  268      GND                     
                                  269      M_D_CPU1_SB_DQ<19>      
                                  270      GND                     
                                  271      M_D_CPU1_SB_DQS_DN<7>   
                                  272      M_D_CPU1_SB_DQS_DP<7>   
                                  273      GND                     
                                  274      M_D_CPU1_SB_DQ<22>      
                                  275      GND                     
                                  276      M_D_CPU1_SB_DQ<23>      
                                  277      GND                     
                                  278      M_D_CPU1_SB_DQ<26>      
                                  279      GND                     
                                  280      M_D_CPU1_SB_DQ<27>      
                                  281      GND                     
                                  282      M_D_CPU1_SB_DQS_DN<8>   
                                  283      M_D_CPU1_SB_DQS_DP<8>   
                                  284      GND                     
                                  285      M_D_CPU1_SB_DQ<30>      
                                  286      GND                     
                                  287      M_D_CPU1_SB_DQ<31>      
                                  288      GND                     
                                  G1       GND                     
                                  G2       GND                     
                                  G3       GND                     
J25              SCONN288_ADR50001P013C01-SCONNA 1        P12V_S3_AUX_CPU1_NVDIMM 
                                  3        P3V3_AUX                
                                  4        I3C_SPD_DDREFGH_CPU1_LVC1_SCL
                                  5        I3C_SPD_DDREFGH_CPU1_LVC1_SDA
                                  6        GND                     
                                  7        M_E_CPU1_SA_DQ<0>       
                                  8        GND                     
                                  9        M_E_CPU1_SA_DQ<1>       
                                  10       GND                     
                                  11       M_E_CPU1_SA_DQS_DP<0>   
                                  12       M_E_CPU1_SA_DQS_DN<0>   
                                  13       GND                     
                                  14       M_E_CPU1_SA_DQ<4>       
                                  15       GND                     
                                  16       M_E_CPU1_SA_DQ<5>       
                                  17       GND                     
                                  18       M_E_CPU1_SA_DQ<8>       
                                  19       GND                     
                                  20       M_E_CPU1_SA_DQ<9>       
                                  21       GND                     
                                  22       M_E_CPU1_SA_DQS_DP<1>   
                                  23       M_E_CPU1_SA_DQS_DN<1>   
                                  24       GND                     
                                  25       M_E_CPU1_SA_DQ<12>      
                                  26       GND                     
                                  27       M_E_CPU1_SA_DQ<13>      
                                  28       GND                     
                                  29       M_E_CPU1_SA_DQ<16>      
                                  30       GND                     
                                  31       M_E_CPU1_SA_DQ<17>      
                                  32       GND                     
                                  33       M_E_CPU1_SA_DQS_DP<2>   
                                  34       M_E_CPU1_SA_DQS_DN<2>   
                                  35       GND                     
                                  36       M_E_CPU1_SA_DQ<20>      
                                  37       GND                     
                                  38       M_E_CPU1_SA_DQ<21>      
                                  39       GND                     
                                  40       M_E_CPU1_SA_DQ<24>      
                                  41       GND                     
                                  42       M_E_CPU1_SA_DQ<25>      
                                  43       GND                     
                                  44       M_E_CPU1_SA_DQS_DP<3>   
                                  45       M_E_CPU1_SA_DQS_DN<3>   
                                  46       GND                     
                                  47       M_E_CPU1_SA_DQ<28>      
                                  48       GND                     
                                  49       M_E_CPU1_SA_DQ<29>      
                                  50       GND                     
                                  51       M_E_CPU1_SA_CB<0>       
                                  52       GND                     
                                  53       M_E_CPU1_SA_CB<1>       
                                  54       GND                     
                                  55       M_E_CPU1_SA_DQS_DP<4>   
                                  56       M_E_CPU1_SA_DQS_DN<4>   
                                  57       GND                     
                                  58       M_E_CPU1_SA_CB<4>       
                                  59       GND                     
                                  60       M_E_CPU1_SA_CB<5>       
                                  61       GND                     
                                  62       M_E_CPU1_ALERT_N        
                                  63       GND                     
                                  64       M_E_CPU1_SA_CS_N<0>     
                                  65       GND                     
                                  66       M_E_CPU1_SA_CA<0>       
                                  67       GND                     
                                  68       M_E_CPU1_SA_CA<2>       
                                  69       GND                     
                                  70       M_E_CPU1_SA_CA<4>       
                                  71       GND                     
                                  72       M_E_CPU1_SA_CA<6>       
                                  73       GND                     
                                  74       M_E_CPU1_SA_PAR         
                                  75       GND                     
                                  76       M_E_CPU1_SB_CA<0>       
                                  77       GND                     
                                  78       M_E_CPU1_SB_CA<2>       
                                  79       GND                     
                                  80       M_E_CPU1_SB_CA<4>       
                                  81       GND                     
                                  82       M_E_CPU1_SB_CA<6>       
                                  83       GND                     
                                  84       M_E_CPU1_SB_CS_N<0>     
                                  85       GND                     
                                  86       M_E_CPU1_SA_RSP<0>      
                                  87       M_E_CPU1_SB_RSP<0>      
                                  88       GND                     
                                  89       M_E_CPU1_SB_CB<4>       
                                  90       GND                     
                                  91       M_E_CPU1_SB_CB<5>       
                                  92       GND                     
                                  93       M_E_CPU1_SB_DQS_DP<9>   
                                  94       M_E_CPU1_SB_DQS_DN<9>   
                                  95       GND                     
                                  96       M_E_CPU1_SB_CB<0>       
                                  97       GND                     
                                  98       M_E_CPU1_SB_CB<1>       
                                  99       GND                     
                                  100      M_E_CPU1_SB_DQ<0>       
                                  101      GND                     
                                  102      M_E_CPU1_SB_DQ<1>       
                                  103      GND                     
                                  104      M_E_CPU1_SB_DQS_DP<0>   
                                  105      M_E_CPU1_SB_DQS_DN<0>   
                                  106      GND                     
                                  107      M_E_CPU1_SB_DQ<4>       
                                  108      GND                     
                                  109      M_E_CPU1_SB_DQ<5>       
                                  110      GND                     
                                  111      M_E_CPU1_SB_DQ<8>       
                                  112      GND                     
                                  113      M_E_CPU1_SB_DQ<9>       
                                  114      GND                     
                                  115      M_E_CPU1_SB_DQS_DP<1>   
                                  116      M_E_CPU1_SB_DQS_DN<1>   
                                  117      GND                     
                                  118      M_E_CPU1_SB_DQ<12>      
                                  119      GND                     
                                  120      M_E_CPU1_SB_DQ<13>      
                                  121      GND                     
                                  122      M_E_CPU1_SB_DQ<16>      
                                  123      GND                     
                                  124      M_E_CPU1_SB_DQ<17>      
                                  125      GND                     
                                  126      M_E_CPU1_SB_DQS_DP<2>   
                                  127      M_E_CPU1_SB_DQS_DN<2>   
                                  128      GND                     
                                  129      M_E_CPU1_SB_DQ<20>      
                                  130      GND                     
                                  131      M_E_CPU1_SB_DQ<21>      
                                  132      GND                     
                                  133      M_E_CPU1_SB_DQ<24>      
                                  134      GND                     
                                  135      M_E_CPU1_SB_DQ<25>      
                                  136      GND                     
                                  137      M_E_CPU1_SB_DQS_DP<3>   
                                  138      M_E_CPU1_SB_DQS_DN<3>   
                                  139      GND                     
                                  140      M_E_CPU1_SB_DQ<28>      
                                  141      GND                     
                                  142      M_E_CPU1_SB_DQ<29>      
                                  143      GND                     
                                  145      P12V_S3_AUX_CPU1_NVDIMM 
                                  146      P12V_S3_AUX_CPU1_NVDIMM 
                                  147      PWRGD_CHE_CPU1_DIMM1    
                                  148      PD_CHE_CPU1_DIMM1_SAA   
                                  151      GND                     
                                  152      M_E_CPU1_SA_DQ<2>       
                                  153      GND                     
                                  154      M_E_CPU1_SA_DQ<3>       
                                  155      GND                     
                                  156      M_E_CPU1_SA_DQS_DN<5>   
                                  157      M_E_CPU1_SA_DQS_DP<5>   
                                  158      GND                     
                                  159      M_E_CPU1_SA_DQ<6>       
                                  160      GND                     
                                  161      M_E_CPU1_SA_DQ<7>       
                                  162      GND                     
                                  163      M_E_CPU1_SA_DQ<10>      
                                  164      GND                     
                                  165      M_E_CPU1_SA_DQ<11>      
                                  166      GND                     
                                  167      M_E_CPU1_SA_DQS_DN<6>   
                                  168      M_E_CPU1_SA_DQS_DP<6>   
                                  169      GND                     
                                  170      M_E_CPU1_SA_DQ<14>      
                                  171      GND                     
                                  172      M_E_CPU1_SA_DQ<15>      
                                  173      GND                     
                                  174      M_E_CPU1_SA_DQ<18>      
                                  175      GND                     
                                  176      M_E_CPU1_SA_DQ<19>      
                                  177      GND                     
                                  178      M_E_CPU1_SA_DQS_DN<7>   
                                  179      M_E_CPU1_SA_DQS_DP<7>   
                                  180      GND                     
                                  181      M_E_CPU1_SA_DQ<22>      
                                  182      GND                     
                                  183      M_E_CPU1_SA_DQ<23>      
                                  184      GND                     
                                  185      M_E_CPU1_SA_DQ<26>      
                                  186      GND                     
                                  187      M_E_CPU1_SA_DQ<27>      
                                  188      GND                     
                                  189      M_E_CPU1_SA_DQS_DN<8>   
                                  190      M_E_CPU1_SA_DQS_DP<8>   
                                  191      GND                     
                                  192      M_E_CPU1_SA_DQ<30>      
                                  193      GND                     
                                  194      M_E_CPU1_SA_DQ<31>      
                                  195      GND                     
                                  196      M_E_CPU1_SA_CB<2>       
                                  197      GND                     
                                  198      M_E_CPU1_SA_CB<3>       
                                  199      GND                     
                                  200      M_E_CPU1_SA_DQS_DN<9>   
                                  201      M_E_CPU1_SA_DQS_DP<9>   
                                  202      GND                     
                                  203      M_E_CPU1_SA_CB<6>       
                                  204      GND                     
                                  205      M_E_CPU1_SA_CB<7>       
                                  206      GND                     
                                  207      RST_M_EF_CPU1_FPGA_N    
                                  208      GND                     
                                  209      M_E_CPU1_SA_CS_N<1>     
                                  210      GND                     
                                  211      M_E_CPU1_SA_CA<1>       
                                  212      GND                     
                                  213      M_E_CPU1_SA_CA<3>       
                                  214      GND                     
                                  215      M_E_CPU1_SA_CA<5>       
                                  216      GND                     
                                  217      M_E_CPU1_CLK_DP<0>      
                                  218      M_E_CPU1_CLK_DN<0>      
                                  219      GND                     
                                  221      M_E_CPU1_SB_CA<1>       
                                  222      GND                     
                                  223      M_E_CPU1_SB_CA<3>       
                                  224      GND                     
                                  225      M_E_CPU1_SB_CA<5>       
                                  226      GND                     
                                  227      M_E_CPU1_SB_PAR         
                                  228      GND                     
                                  229      M_E_CPU1_SB_CS_N<1>     
                                  230      GND                     
                                  233      GND                     
                                  234      M_E_CPU1_SB_CB<6>       
                                  235      GND                     
                                  236      M_E_CPU1_SB_CB<7>       
                                  237      GND                     
                                  238      M_E_CPU1_SB_DQS_DN<4>   
                                  239      M_E_CPU1_SB_DQS_DP<4>   
                                  240      GND                     
                                  241      M_E_CPU1_SB_CB<2>       
                                  242      GND                     
                                  243      M_E_CPU1_SB_CB<3>       
                                  244      GND                     
                                  245      M_E_CPU1_SB_DQ<2>       
                                  246      GND                     
                                  247      M_E_CPU1_SB_DQ<3>       
                                  248      GND                     
                                  249      M_E_CPU1_SB_DQS_DN<5>   
                                  250      M_E_CPU1_SB_DQS_DP<5>   
                                  251      GND                     
                                  252      M_E_CPU1_SB_DQ<6>       
                                  253      GND                     
                                  254      M_E_CPU1_SB_DQ<7>       
                                  255      GND                     
                                  256      M_E_CPU1_SB_DQ<10>      
                                  257      GND                     
                                  258      M_E_CPU1_SB_DQ<11>      
                                  259      GND                     
                                  260      M_E_CPU1_SB_DQS_DN<6>   
                                  261      M_E_CPU1_SB_DQS_DP<6>   
                                  262      GND                     
                                  263      M_E_CPU1_SB_DQ<14>      
                                  264      GND                     
                                  265      M_E_CPU1_SB_DQ<15>      
                                  266      GND                     
                                  267      M_E_CPU1_SB_DQ<18>      
                                  268      GND                     
                                  269      M_E_CPU1_SB_DQ<19>      
                                  270      GND                     
                                  271      M_E_CPU1_SB_DQS_DN<7>   
                                  272      M_E_CPU1_SB_DQS_DP<7>   
                                  273      GND                     
                                  274      M_E_CPU1_SB_DQ<22>      
                                  275      GND                     
                                  276      M_E_CPU1_SB_DQ<23>      
                                  277      GND                     
                                  278      M_E_CPU1_SB_DQ<26>      
                                  279      GND                     
                                  280      M_E_CPU1_SB_DQ<27>      
                                  281      GND                     
                                  282      M_E_CPU1_SB_DQS_DN<8>   
                                  283      M_E_CPU1_SB_DQS_DP<8>   
                                  284      GND                     
                                  285      M_E_CPU1_SB_DQ<30>      
                                  286      GND                     
                                  287      M_E_CPU1_SB_DQ<31>      
                                  288      GND                     
                                  G1       GND                     
                                  G2       GND                     
                                  G3       GND                     
J26              SCONN288_ADR50001P003C01-SCONNA 1        P12V_S3_AUX_CPU1_NVDIMM 
                                  3        P3V3_AUX                
                                  4        I3C_SPD_DDREFGH_CPU1_LVC1_SCL
                                  5        I3C_SPD_DDREFGH_CPU1_LVC1_SDA
                                  6        GND                     
                                  7        M_E_CPU1_SA_DQ<0>       
                                  8        GND                     
                                  9        M_E_CPU1_SA_DQ<1>       
                                  10       GND                     
                                  11       M_E_CPU1_SA_DQS_DP<0>   
                                  12       M_E_CPU1_SA_DQS_DN<0>   
                                  13       GND                     
                                  14       M_E_CPU1_SA_DQ<4>       
                                  15       GND                     
                                  16       M_E_CPU1_SA_DQ<5>       
                                  17       GND                     
                                  18       M_E_CPU1_SA_DQ<8>       
                                  19       GND                     
                                  20       M_E_CPU1_SA_DQ<9>       
                                  21       GND                     
                                  22       M_E_CPU1_SA_DQS_DP<1>   
                                  23       M_E_CPU1_SA_DQS_DN<1>   
                                  24       GND                     
                                  25       M_E_CPU1_SA_DQ<12>      
                                  26       GND                     
                                  27       M_E_CPU1_SA_DQ<13>      
                                  28       GND                     
                                  29       M_E_CPU1_SA_DQ<16>      
                                  30       GND                     
                                  31       M_E_CPU1_SA_DQ<17>      
                                  32       GND                     
                                  33       M_E_CPU1_SA_DQS_DP<2>   
                                  34       M_E_CPU1_SA_DQS_DN<2>   
                                  35       GND                     
                                  36       M_E_CPU1_SA_DQ<20>      
                                  37       GND                     
                                  38       M_E_CPU1_SA_DQ<21>      
                                  39       GND                     
                                  40       M_E_CPU1_SA_DQ<24>      
                                  41       GND                     
                                  42       M_E_CPU1_SA_DQ<25>      
                                  43       GND                     
                                  44       M_E_CPU1_SA_DQS_DP<3>   
                                  45       M_E_CPU1_SA_DQS_DN<3>   
                                  46       GND                     
                                  47       M_E_CPU1_SA_DQ<28>      
                                  48       GND                     
                                  49       M_E_CPU1_SA_DQ<29>      
                                  50       GND                     
                                  51       M_E_CPU1_SA_CB<0>       
                                  52       GND                     
                                  53       M_E_CPU1_SA_CB<1>       
                                  54       GND                     
                                  55       M_E_CPU1_SA_DQS_DP<4>   
                                  56       M_E_CPU1_SA_DQS_DN<4>   
                                  57       GND                     
                                  58       M_E_CPU1_SA_CB<4>       
                                  59       GND                     
                                  60       M_E_CPU1_SA_CB<5>       
                                  61       GND                     
                                  62       M_E_CPU1_ALERT_N        
                                  63       GND                     
                                  64       M_E_CPU1_SA_CS_N<2>     
                                  65       GND                     
                                  66       M_E_CPU1_SA_CA<0>       
                                  67       GND                     
                                  68       M_E_CPU1_SA_CA<2>       
                                  69       GND                     
                                  70       M_E_CPU1_SA_CA<4>       
                                  71       GND                     
                                  72       M_E_CPU1_SA_CA<6>       
                                  73       GND                     
                                  74       M_E_CPU1_SA_PAR         
                                  75       GND                     
                                  76       M_E_CPU1_SB_CA<0>       
                                  77       GND                     
                                  78       M_E_CPU1_SB_CA<2>       
                                  79       GND                     
                                  80       M_E_CPU1_SB_CA<4>       
                                  81       GND                     
                                  82       M_E_CPU1_SB_CA<6>       
                                  83       GND                     
                                  84       M_E_CPU1_SB_CS_N<2>     
                                  85       GND                     
                                  86       M_E_CPU1_SA_RSP<1>      
                                  87       M_E_CPU1_SB_RSP<1>      
                                  88       GND                     
                                  89       M_E_CPU1_SB_CB<4>       
                                  90       GND                     
                                  91       M_E_CPU1_SB_CB<5>       
                                  92       GND                     
                                  93       M_E_CPU1_SB_DQS_DP<9>   
                                  94       M_E_CPU1_SB_DQS_DN<9>   
                                  95       GND                     
                                  96       M_E_CPU1_SB_CB<0>       
                                  97       GND                     
                                  98       M_E_CPU1_SB_CB<1>       
                                  99       GND                     
                                  100      M_E_CPU1_SB_DQ<0>       
                                  101      GND                     
                                  102      M_E_CPU1_SB_DQ<1>       
                                  103      GND                     
                                  104      M_E_CPU1_SB_DQS_DP<0>   
                                  105      M_E_CPU1_SB_DQS_DN<0>   
                                  106      GND                     
                                  107      M_E_CPU1_SB_DQ<4>       
                                  108      GND                     
                                  109      M_E_CPU1_SB_DQ<5>       
                                  110      GND                     
                                  111      M_E_CPU1_SB_DQ<8>       
                                  112      GND                     
                                  113      M_E_CPU1_SB_DQ<9>       
                                  114      GND                     
                                  115      M_E_CPU1_SB_DQS_DP<1>   
                                  116      M_E_CPU1_SB_DQS_DN<1>   
                                  117      GND                     
                                  118      M_E_CPU1_SB_DQ<12>      
                                  119      GND                     
                                  120      M_E_CPU1_SB_DQ<13>      
                                  121      GND                     
                                  122      M_E_CPU1_SB_DQ<16>      
                                  123      GND                     
                                  124      M_E_CPU1_SB_DQ<17>      
                                  125      GND                     
                                  126      M_E_CPU1_SB_DQS_DP<2>   
                                  127      M_E_CPU1_SB_DQS_DN<2>   
                                  128      GND                     
                                  129      M_E_CPU1_SB_DQ<20>      
                                  130      GND                     
                                  131      M_E_CPU1_SB_DQ<21>      
                                  132      GND                     
                                  133      M_E_CPU1_SB_DQ<24>      
                                  134      GND                     
                                  135      M_E_CPU1_SB_DQ<25>      
                                  136      GND                     
                                  137      M_E_CPU1_SB_DQS_DP<3>   
                                  138      M_E_CPU1_SB_DQS_DN<3>   
                                  139      GND                     
                                  140      M_E_CPU1_SB_DQ<28>      
                                  141      GND                     
                                  142      M_E_CPU1_SB_DQ<29>      
                                  143      GND                     
                                  145      P12V_S3_AUX_CPU1_NVDIMM 
                                  146      P12V_S3_AUX_CPU1_NVDIMM 
                                  147      PWRGD_CHE_CPU1_DIMM2    
                                  148      PD_CHE_CPU1_DIMM2_SAA   
                                  151      GND                     
                                  152      M_E_CPU1_SA_DQ<2>       
                                  153      GND                     
                                  154      M_E_CPU1_SA_DQ<3>       
                                  155      GND                     
                                  156      M_E_CPU1_SA_DQS_DN<5>   
                                  157      M_E_CPU1_SA_DQS_DP<5>   
                                  158      GND                     
                                  159      M_E_CPU1_SA_DQ<6>       
                                  160      GND                     
                                  161      M_E_CPU1_SA_DQ<7>       
                                  162      GND                     
                                  163      M_E_CPU1_SA_DQ<10>      
                                  164      GND                     
                                  165      M_E_CPU1_SA_DQ<11>      
                                  166      GND                     
                                  167      M_E_CPU1_SA_DQS_DN<6>   
                                  168      M_E_CPU1_SA_DQS_DP<6>   
                                  169      GND                     
                                  170      M_E_CPU1_SA_DQ<14>      
                                  171      GND                     
                                  172      M_E_CPU1_SA_DQ<15>      
                                  173      GND                     
                                  174      M_E_CPU1_SA_DQ<18>      
                                  175      GND                     
                                  176      M_E_CPU1_SA_DQ<19>      
                                  177      GND                     
                                  178      M_E_CPU1_SA_DQS_DN<7>   
                                  179      M_E_CPU1_SA_DQS_DP<7>   
                                  180      GND                     
                                  181      M_E_CPU1_SA_DQ<22>      
                                  182      GND                     
                                  183      M_E_CPU1_SA_DQ<23>      
                                  184      GND                     
                                  185      M_E_CPU1_SA_DQ<26>      
                                  186      GND                     
                                  187      M_E_CPU1_SA_DQ<27>      
                                  188      GND                     
                                  189      M_E_CPU1_SA_DQS_DN<8>   
                                  190      M_E_CPU1_SA_DQS_DP<8>   
                                  191      GND                     
                                  192      M_E_CPU1_SA_DQ<30>      
                                  193      GND                     
                                  194      M_E_CPU1_SA_DQ<31>      
                                  195      GND                     
                                  196      M_E_CPU1_SA_CB<2>       
                                  197      GND                     
                                  198      M_E_CPU1_SA_CB<3>       
                                  199      GND                     
                                  200      M_E_CPU1_SA_DQS_DN<9>   
                                  201      M_E_CPU1_SA_DQS_DP<9>   
                                  202      GND                     
                                  203      M_E_CPU1_SA_CB<6>       
                                  204      GND                     
                                  205      M_E_CPU1_SA_CB<7>       
                                  206      GND                     
                                  207      RST_M_EF_CPU1_FPGA_N    
                                  208      GND                     
                                  209      M_E_CPU1_SA_CS_N<3>     
                                  210      GND                     
                                  211      M_E_CPU1_SA_CA<1>       
                                  212      GND                     
                                  213      M_E_CPU1_SA_CA<3>       
                                  214      GND                     
                                  215      M_E_CPU1_SA_CA<5>       
                                  216      GND                     
                                  217      M_E_CPU1_CLK_DP<1>      
                                  218      M_E_CPU1_CLK_DN<1>      
                                  219      GND                     
                                  221      M_E_CPU1_SB_CA<1>       
                                  222      GND                     
                                  223      M_E_CPU1_SB_CA<3>       
                                  224      GND                     
                                  225      M_E_CPU1_SB_CA<5>       
                                  226      GND                     
                                  227      M_E_CPU1_SB_PAR         
                                  228      GND                     
                                  229      M_E_CPU1_SB_CS_N<3>     
                                  230      GND                     
                                  233      GND                     
                                  234      M_E_CPU1_SB_CB<6>       
                                  235      GND                     
                                  236      M_E_CPU1_SB_CB<7>       
                                  237      GND                     
                                  238      M_E_CPU1_SB_DQS_DN<4>   
                                  239      M_E_CPU1_SB_DQS_DP<4>   
                                  240      GND                     
                                  241      M_E_CPU1_SB_CB<2>       
                                  242      GND                     
                                  243      M_E_CPU1_SB_CB<3>       
                                  244      GND                     
                                  245      M_E_CPU1_SB_DQ<2>       
                                  246      GND                     
                                  247      M_E_CPU1_SB_DQ<3>       
                                  248      GND                     
                                  249      M_E_CPU1_SB_DQS_DN<5>   
                                  250      M_E_CPU1_SB_DQS_DP<5>   
                                  251      GND                     
                                  252      M_E_CPU1_SB_DQ<6>       
                                  253      GND                     
                                  254      M_E_CPU1_SB_DQ<7>       
                                  255      GND                     
                                  256      M_E_CPU1_SB_DQ<10>      
                                  257      GND                     
                                  258      M_E_CPU1_SB_DQ<11>      
                                  259      GND                     
                                  260      M_E_CPU1_SB_DQS_DN<6>   
                                  261      M_E_CPU1_SB_DQS_DP<6>   
                                  262      GND                     
                                  263      M_E_CPU1_SB_DQ<14>      
                                  264      GND                     
                                  265      M_E_CPU1_SB_DQ<15>      
                                  266      GND                     
                                  267      M_E_CPU1_SB_DQ<18>      
                                  268      GND                     
                                  269      M_E_CPU1_SB_DQ<19>      
                                  270      GND                     
                                  271      M_E_CPU1_SB_DQS_DN<7>   
                                  272      M_E_CPU1_SB_DQS_DP<7>   
                                  273      GND                     
                                  274      M_E_CPU1_SB_DQ<22>      
                                  275      GND                     
                                  276      M_E_CPU1_SB_DQ<23>      
                                  277      GND                     
                                  278      M_E_CPU1_SB_DQ<26>      
                                  279      GND                     
                                  280      M_E_CPU1_SB_DQ<27>      
                                  281      GND                     
                                  282      M_E_CPU1_SB_DQS_DN<8>   
                                  283      M_E_CPU1_SB_DQS_DP<8>   
                                  284      GND                     
                                  285      M_E_CPU1_SB_DQ<30>      
                                  286      GND                     
                                  287      M_E_CPU1_SB_DQ<31>      
                                  288      GND                     
                                  G1       GND                     
                                  G2       GND                     
                                  G3       GND                     
J27              SCONN288_ADR50001P013C01-SCONNA 1        P12V_S3_AUX_CPU1_NVDIMM 
                                  3        P3V3_AUX                
                                  4        I3C_SPD_DDREFGH_CPU1_LVC1_SCL
                                  5        I3C_SPD_DDREFGH_CPU1_LVC1_SDA
                                  6        GND                     
                                  7        M_F_CPU1_SA_DQ<0>       
                                  8        GND                     
                                  9        M_F_CPU1_SA_DQ<1>       
                                  10       GND                     
                                  11       M_F_CPU1_SA_DQS_DP<0>   
                                  12       M_F_CPU1_SA_DQS_DN<0>   
                                  13       GND                     
                                  14       M_F_CPU1_SA_DQ<4>       
                                  15       GND                     
                                  16       M_F_CPU1_SA_DQ<5>       
                                  17       GND                     
                                  18       M_F_CPU1_SA_DQ<8>       
                                  19       GND                     
                                  20       M_F_CPU1_SA_DQ<9>       
                                  21       GND                     
                                  22       M_F_CPU1_SA_DQS_DP<1>   
                                  23       M_F_CPU1_SA_DQS_DN<1>   
                                  24       GND                     
                                  25       M_F_CPU1_SA_DQ<12>      
                                  26       GND                     
                                  27       M_F_CPU1_SA_DQ<13>      
                                  28       GND                     
                                  29       M_F_CPU1_SA_DQ<16>      
                                  30       GND                     
                                  31       M_F_CPU1_SA_DQ<17>      
                                  32       GND                     
                                  33       M_F_CPU1_SA_DQS_DP<2>   
                                  34       M_F_CPU1_SA_DQS_DN<2>   
                                  35       GND                     
                                  36       M_F_CPU1_SA_DQ<20>      
                                  37       GND                     
                                  38       M_F_CPU1_SA_DQ<21>      
                                  39       GND                     
                                  40       M_F_CPU1_SA_DQ<24>      
                                  41       GND                     
                                  42       M_F_CPU1_SA_DQ<25>      
                                  43       GND                     
                                  44       M_F_CPU1_SA_DQS_DP<3>   
                                  45       M_F_CPU1_SA_DQS_DN<3>   
                                  46       GND                     
                                  47       M_F_CPU1_SA_DQ<28>      
                                  48       GND                     
                                  49       M_F_CPU1_SA_DQ<29>      
                                  50       GND                     
                                  51       M_F_CPU1_SA_CB<0>       
                                  52       GND                     
                                  53       M_F_CPU1_SA_CB<1>       
                                  54       GND                     
                                  55       M_F_CPU1_SA_DQS_DP<4>   
                                  56       M_F_CPU1_SA_DQS_DN<4>   
                                  57       GND                     
                                  58       M_F_CPU1_SA_CB<4>       
                                  59       GND                     
                                  60       M_F_CPU1_SA_CB<5>       
                                  61       GND                     
                                  62       M_F_CPU1_ALERT_N        
                                  63       GND                     
                                  64       M_F_CPU1_SA_CS_N<0>     
                                  65       GND                     
                                  66       M_F_CPU1_SA_CA<0>       
                                  67       GND                     
                                  68       M_F_CPU1_SA_CA<2>       
                                  69       GND                     
                                  70       M_F_CPU1_SA_CA<4>       
                                  71       GND                     
                                  72       M_F_CPU1_SA_CA<6>       
                                  73       GND                     
                                  74       M_F_CPU1_SA_PAR         
                                  75       GND                     
                                  76       M_F_CPU1_SB_CA<0>       
                                  77       GND                     
                                  78       M_F_CPU1_SB_CA<2>       
                                  79       GND                     
                                  80       M_F_CPU1_SB_CA<4>       
                                  81       GND                     
                                  82       M_F_CPU1_SB_CA<6>       
                                  83       GND                     
                                  84       M_F_CPU1_SB_CS_N<0>     
                                  85       GND                     
                                  86       M_F_CPU1_SA_RSP<0>      
                                  87       M_F_CPU1_SB_RSP<0>      
                                  88       GND                     
                                  89       M_F_CPU1_SB_CB<4>       
                                  90       GND                     
                                  91       M_F_CPU1_SB_CB<5>       
                                  92       GND                     
                                  93       M_F_CPU1_SB_DQS_DP<9>   
                                  94       M_F_CPU1_SB_DQS_DN<9>   
                                  95       GND                     
                                  96       M_F_CPU1_SB_CB<0>       
                                  97       GND                     
                                  98       M_F_CPU1_SB_CB<1>       
                                  99       GND                     
                                  100      M_F_CPU1_SB_DQ<0>       
                                  101      GND                     
                                  102      M_F_CPU1_SB_DQ<1>       
                                  103      GND                     
                                  104      M_F_CPU1_SB_DQS_DP<0>   
                                  105      M_F_CPU1_SB_DQS_DN<0>   
                                  106      GND                     
                                  107      M_F_CPU1_SB_DQ<4>       
                                  108      GND                     
                                  109      M_F_CPU1_SB_DQ<5>       
                                  110      GND                     
                                  111      M_F_CPU1_SB_DQ<8>       
                                  112      GND                     
                                  113      M_F_CPU1_SB_DQ<9>       
                                  114      GND                     
                                  115      M_F_CPU1_SB_DQS_DP<1>   
                                  116      M_F_CPU1_SB_DQS_DN<1>   
                                  117      GND                     
                                  118      M_F_CPU1_SB_DQ<12>      
                                  119      GND                     
                                  120      M_F_CPU1_SB_DQ<13>      
                                  121      GND                     
                                  122      M_F_CPU1_SB_DQ<16>      
                                  123      GND                     
                                  124      M_F_CPU1_SB_DQ<17>      
                                  125      GND                     
                                  126      M_F_CPU1_SB_DQS_DP<2>   
                                  127      M_F_CPU1_SB_DQS_DN<2>   
                                  128      GND                     
                                  129      M_F_CPU1_SB_DQ<20>      
                                  130      GND                     
                                  131      M_F_CPU1_SB_DQ<21>      
                                  132      GND                     
                                  133      M_F_CPU1_SB_DQ<24>      
                                  134      GND                     
                                  135      M_F_CPU1_SB_DQ<25>      
                                  136      GND                     
                                  137      M_F_CPU1_SB_DQS_DP<3>   
                                  138      M_F_CPU1_SB_DQS_DN<3>   
                                  139      GND                     
                                  140      M_F_CPU1_SB_DQ<28>      
                                  141      GND                     
                                  142      M_F_CPU1_SB_DQ<29>      
                                  143      GND                     
                                  145      P12V_S3_AUX_CPU1_NVDIMM 
                                  146      P12V_S3_AUX_CPU1_NVDIMM 
                                  147      PWRGD_CHF_CPU1_DIMM1    
                                  148      PD_CHF_CPU1_DIMM1_SAA   
                                  151      GND                     
                                  152      M_F_CPU1_SA_DQ<2>       
                                  153      GND                     
                                  154      M_F_CPU1_SA_DQ<3>       
                                  155      GND                     
                                  156      M_F_CPU1_SA_DQS_DN<5>   
                                  157      M_F_CPU1_SA_DQS_DP<5>   
                                  158      GND                     
                                  159      M_F_CPU1_SA_DQ<6>       
                                  160      GND                     
                                  161      M_F_CPU1_SA_DQ<7>       
                                  162      GND                     
                                  163      M_F_CPU1_SA_DQ<10>      
                                  164      GND                     
                                  165      M_F_CPU1_SA_DQ<11>      
                                  166      GND                     
                                  167      M_F_CPU1_SA_DQS_DN<6>   
                                  168      M_F_CPU1_SA_DQS_DP<6>   
                                  169      GND                     
                                  170      M_F_CPU1_SA_DQ<14>      
                                  171      GND                     
                                  172      M_F_CPU1_SA_DQ<15>      
                                  173      GND                     
                                  174      M_F_CPU1_SA_DQ<18>      
                                  175      GND                     
                                  176      M_F_CPU1_SA_DQ<19>      
                                  177      GND                     
                                  178      M_F_CPU1_SA_DQS_DN<7>   
                                  179      M_F_CPU1_SA_DQS_DP<7>   
                                  180      GND                     
                                  181      M_F_CPU1_SA_DQ<22>      
                                  182      GND                     
                                  183      M_F_CPU1_SA_DQ<23>      
                                  184      GND                     
                                  185      M_F_CPU1_SA_DQ<26>      
                                  186      GND                     
                                  187      M_F_CPU1_SA_DQ<27>      
                                  188      GND                     
                                  189      M_F_CPU1_SA_DQS_DN<8>   
                                  190      M_F_CPU1_SA_DQS_DP<8>   
                                  191      GND                     
                                  192      M_F_CPU1_SA_DQ<30>      
                                  193      GND                     
                                  194      M_F_CPU1_SA_DQ<31>      
                                  195      GND                     
                                  196      M_F_CPU1_SA_CB<2>       
                                  197      GND                     
                                  198      M_F_CPU1_SA_CB<3>       
                                  199      GND                     
                                  200      M_F_CPU1_SA_DQS_DN<9>   
                                  201      M_F_CPU1_SA_DQS_DP<9>   
                                  202      GND                     
                                  203      M_F_CPU1_SA_CB<6>       
                                  204      GND                     
                                  205      M_F_CPU1_SA_CB<7>       
                                  206      GND                     
                                  207      RST_M_EF_CPU1_FPGA_N    
                                  208      GND                     
                                  209      M_F_CPU1_SA_CS_N<1>     
                                  210      GND                     
                                  211      M_F_CPU1_SA_CA<1>       
                                  212      GND                     
                                  213      M_F_CPU1_SA_CA<3>       
                                  214      GND                     
                                  215      M_F_CPU1_SA_CA<5>       
                                  216      GND                     
                                  217      M_F_CPU1_CLK_DP<0>      
                                  218      M_F_CPU1_CLK_DN<0>      
                                  219      GND                     
                                  221      M_F_CPU1_SB_CA<1>       
                                  222      GND                     
                                  223      M_F_CPU1_SB_CA<3>       
                                  224      GND                     
                                  225      M_F_CPU1_SB_CA<5>       
                                  226      GND                     
                                  227      M_F_CPU1_SB_PAR         
                                  228      GND                     
                                  229      M_F_CPU1_SB_CS_N<1>     
                                  230      GND                     
                                  233      GND                     
                                  234      M_F_CPU1_SB_CB<6>       
                                  235      GND                     
                                  236      M_F_CPU1_SB_CB<7>       
                                  237      GND                     
                                  238      M_F_CPU1_SB_DQS_DN<4>   
                                  239      M_F_CPU1_SB_DQS_DP<4>   
                                  240      GND                     
                                  241      M_F_CPU1_SB_CB<2>       
                                  242      GND                     
                                  243      M_F_CPU1_SB_CB<3>       
                                  244      GND                     
                                  245      M_F_CPU1_SB_DQ<2>       
                                  246      GND                     
                                  247      M_F_CPU1_SB_DQ<3>       
                                  248      GND                     
                                  249      M_F_CPU1_SB_DQS_DN<5>   
                                  250      M_F_CPU1_SB_DQS_DP<5>   
                                  251      GND                     
                                  252      M_F_CPU1_SB_DQ<6>       
                                  253      GND                     
                                  254      M_F_CPU1_SB_DQ<7>       
                                  255      GND                     
                                  256      M_F_CPU1_SB_DQ<10>      
                                  257      GND                     
                                  258      M_F_CPU1_SB_DQ<11>      
                                  259      GND                     
                                  260      M_F_CPU1_SB_DQS_DN<6>   
                                  261      M_F_CPU1_SB_DQS_DP<6>   
                                  262      GND                     
                                  263      M_F_CPU1_SB_DQ<14>      
                                  264      GND                     
                                  265      M_F_CPU1_SB_DQ<15>      
                                  266      GND                     
                                  267      M_F_CPU1_SB_DQ<18>      
                                  268      GND                     
                                  269      M_F_CPU1_SB_DQ<19>      
                                  270      GND                     
                                  271      M_F_CPU1_SB_DQS_DN<7>   
                                  272      M_F_CPU1_SB_DQS_DP<7>   
                                  273      GND                     
                                  274      M_F_CPU1_SB_DQ<22>      
                                  275      GND                     
                                  276      M_F_CPU1_SB_DQ<23>      
                                  277      GND                     
                                  278      M_F_CPU1_SB_DQ<26>      
                                  279      GND                     
                                  280      M_F_CPU1_SB_DQ<27>      
                                  281      GND                     
                                  282      M_F_CPU1_SB_DQS_DN<8>   
                                  283      M_F_CPU1_SB_DQS_DP<8>   
                                  284      GND                     
                                  285      M_F_CPU1_SB_DQ<30>      
                                  286      GND                     
                                  287      M_F_CPU1_SB_DQ<31>      
                                  288      GND                     
                                  G1       GND                     
                                  G2       GND                     
                                  G3       GND                     
J28              SCONN288_ADR50001P003C01-SCONNA 1        P12V_S3_AUX_CPU1_NVDIMM 
                                  3        P3V3_AUX                
                                  4        I3C_SPD_DDREFGH_CPU1_LVC1_SCL
                                  5        I3C_SPD_DDREFGH_CPU1_LVC1_SDA
                                  6        GND                     
                                  7        M_F_CPU1_SA_DQ<0>       
                                  8        GND                     
                                  9        M_F_CPU1_SA_DQ<1>       
                                  10       GND                     
                                  11       M_F_CPU1_SA_DQS_DP<0>   
                                  12       M_F_CPU1_SA_DQS_DN<0>   
                                  13       GND                     
                                  14       M_F_CPU1_SA_DQ<4>       
                                  15       GND                     
                                  16       M_F_CPU1_SA_DQ<5>       
                                  17       GND                     
                                  18       M_F_CPU1_SA_DQ<8>       
                                  19       GND                     
                                  20       M_F_CPU1_SA_DQ<9>       
                                  21       GND                     
                                  22       M_F_CPU1_SA_DQS_DP<1>   
                                  23       M_F_CPU1_SA_DQS_DN<1>   
                                  24       GND                     
                                  25       M_F_CPU1_SA_DQ<12>      
                                  26       GND                     
                                  27       M_F_CPU1_SA_DQ<13>      
                                  28       GND                     
                                  29       M_F_CPU1_SA_DQ<16>      
                                  30       GND                     
                                  31       M_F_CPU1_SA_DQ<17>      
                                  32       GND                     
                                  33       M_F_CPU1_SA_DQS_DP<2>   
                                  34       M_F_CPU1_SA_DQS_DN<2>   
                                  35       GND                     
                                  36       M_F_CPU1_SA_DQ<20>      
                                  37       GND                     
                                  38       M_F_CPU1_SA_DQ<21>      
                                  39       GND                     
                                  40       M_F_CPU1_SA_DQ<24>      
                                  41       GND                     
                                  42       M_F_CPU1_SA_DQ<25>      
                                  43       GND                     
                                  44       M_F_CPU1_SA_DQS_DP<3>   
                                  45       M_F_CPU1_SA_DQS_DN<3>   
                                  46       GND                     
                                  47       M_F_CPU1_SA_DQ<28>      
                                  48       GND                     
                                  49       M_F_CPU1_SA_DQ<29>      
                                  50       GND                     
                                  51       M_F_CPU1_SA_CB<0>       
                                  52       GND                     
                                  53       M_F_CPU1_SA_CB<1>       
                                  54       GND                     
                                  55       M_F_CPU1_SA_DQS_DP<4>   
                                  56       M_F_CPU1_SA_DQS_DN<4>   
                                  57       GND                     
                                  58       M_F_CPU1_SA_CB<4>       
                                  59       GND                     
                                  60       M_F_CPU1_SA_CB<5>       
                                  61       GND                     
                                  62       M_F_CPU1_ALERT_N        
                                  63       GND                     
                                  64       M_F_CPU1_SA_CS_N<2>     
                                  65       GND                     
                                  66       M_F_CPU1_SA_CA<0>       
                                  67       GND                     
                                  68       M_F_CPU1_SA_CA<2>       
                                  69       GND                     
                                  70       M_F_CPU1_SA_CA<4>       
                                  71       GND                     
                                  72       M_F_CPU1_SA_CA<6>       
                                  73       GND                     
                                  74       M_F_CPU1_SA_PAR         
                                  75       GND                     
                                  76       M_F_CPU1_SB_CA<0>       
                                  77       GND                     
                                  78       M_F_CPU1_SB_CA<2>       
                                  79       GND                     
                                  80       M_F_CPU1_SB_CA<4>       
                                  81       GND                     
                                  82       M_F_CPU1_SB_CA<6>       
                                  83       GND                     
                                  84       M_F_CPU1_SB_CS_N<2>     
                                  85       GND                     
                                  86       M_F_CPU1_SA_RSP<1>      
                                  87       M_F_CPU1_SB_RSP<1>      
                                  88       GND                     
                                  89       M_F_CPU1_SB_CB<4>       
                                  90       GND                     
                                  91       M_F_CPU1_SB_CB<5>       
                                  92       GND                     
                                  93       M_F_CPU1_SB_DQS_DP<9>   
                                  94       M_F_CPU1_SB_DQS_DN<9>   
                                  95       GND                     
                                  96       M_F_CPU1_SB_CB<0>       
                                  97       GND                     
                                  98       M_F_CPU1_SB_CB<1>       
                                  99       GND                     
                                  100      M_F_CPU1_SB_DQ<0>       
                                  101      GND                     
                                  102      M_F_CPU1_SB_DQ<1>       
                                  103      GND                     
                                  104      M_F_CPU1_SB_DQS_DP<0>   
                                  105      M_F_CPU1_SB_DQS_DN<0>   
                                  106      GND                     
                                  107      M_F_CPU1_SB_DQ<4>       
                                  108      GND                     
                                  109      M_F_CPU1_SB_DQ<5>       
                                  110      GND                     
                                  111      M_F_CPU1_SB_DQ<8>       
                                  112      GND                     
                                  113      M_F_CPU1_SB_DQ<9>       
                                  114      GND                     
                                  115      M_F_CPU1_SB_DQS_DP<1>   
                                  116      M_F_CPU1_SB_DQS_DN<1>   
                                  117      GND                     
                                  118      M_F_CPU1_SB_DQ<12>      
                                  119      GND                     
                                  120      M_F_CPU1_SB_DQ<13>      
                                  121      GND                     
                                  122      M_F_CPU1_SB_DQ<16>      
                                  123      GND                     
                                  124      M_F_CPU1_SB_DQ<17>      
                                  125      GND                     
                                  126      M_F_CPU1_SB_DQS_DP<2>   
                                  127      M_F_CPU1_SB_DQS_DN<2>   
                                  128      GND                     
                                  129      M_F_CPU1_SB_DQ<20>      
                                  130      GND                     
                                  131      M_F_CPU1_SB_DQ<21>      
                                  132      GND                     
                                  133      M_F_CPU1_SB_DQ<24>      
                                  134      GND                     
                                  135      M_F_CPU1_SB_DQ<25>      
                                  136      GND                     
                                  137      M_F_CPU1_SB_DQS_DP<3>   
                                  138      M_F_CPU1_SB_DQS_DN<3>   
                                  139      GND                     
                                  140      M_F_CPU1_SB_DQ<28>      
                                  141      GND                     
                                  142      M_F_CPU1_SB_DQ<29>      
                                  143      GND                     
                                  145      P12V_S3_AUX_CPU1_NVDIMM 
                                  146      P12V_S3_AUX_CPU1_NVDIMM 
                                  147      PWRGD_CHF_CPU1_DIMM2    
                                  148      PD_CHF_CPU1_DIMM2_SAA   
                                  151      GND                     
                                  152      M_F_CPU1_SA_DQ<2>       
                                  153      GND                     
                                  154      M_F_CPU1_SA_DQ<3>       
                                  155      GND                     
                                  156      M_F_CPU1_SA_DQS_DN<5>   
                                  157      M_F_CPU1_SA_DQS_DP<5>   
                                  158      GND                     
                                  159      M_F_CPU1_SA_DQ<6>       
                                  160      GND                     
                                  161      M_F_CPU1_SA_DQ<7>       
                                  162      GND                     
                                  163      M_F_CPU1_SA_DQ<10>      
                                  164      GND                     
                                  165      M_F_CPU1_SA_DQ<11>      
                                  166      GND                     
                                  167      M_F_CPU1_SA_DQS_DN<6>   
                                  168      M_F_CPU1_SA_DQS_DP<6>   
                                  169      GND                     
                                  170      M_F_CPU1_SA_DQ<14>      
                                  171      GND                     
                                  172      M_F_CPU1_SA_DQ<15>      
                                  173      GND                     
                                  174      M_F_CPU1_SA_DQ<18>      
                                  175      GND                     
                                  176      M_F_CPU1_SA_DQ<19>      
                                  177      GND                     
                                  178      M_F_CPU1_SA_DQS_DN<7>   
                                  179      M_F_CPU1_SA_DQS_DP<7>   
                                  180      GND                     
                                  181      M_F_CPU1_SA_DQ<22>      
                                  182      GND                     
                                  183      M_F_CPU1_SA_DQ<23>      
                                  184      GND                     
                                  185      M_F_CPU1_SA_DQ<26>      
                                  186      GND                     
                                  187      M_F_CPU1_SA_DQ<27>      
                                  188      GND                     
                                  189      M_F_CPU1_SA_DQS_DN<8>   
                                  190      M_F_CPU1_SA_DQS_DP<8>   
                                  191      GND                     
                                  192      M_F_CPU1_SA_DQ<30>      
                                  193      GND                     
                                  194      M_F_CPU1_SA_DQ<31>      
                                  195      GND                     
                                  196      M_F_CPU1_SA_CB<2>       
                                  197      GND                     
                                  198      M_F_CPU1_SA_CB<3>       
                                  199      GND                     
                                  200      M_F_CPU1_SA_DQS_DN<9>   
                                  201      M_F_CPU1_SA_DQS_DP<9>   
                                  202      GND                     
                                  203      M_F_CPU1_SA_CB<6>       
                                  204      GND                     
                                  205      M_F_CPU1_SA_CB<7>       
                                  206      GND                     
                                  207      RST_M_EF_CPU1_FPGA_N    
                                  208      GND                     
                                  209      M_F_CPU1_SA_CS_N<3>     
                                  210      GND                     
                                  211      M_F_CPU1_SA_CA<1>       
                                  212      GND                     
                                  213      M_F_CPU1_SA_CA<3>       
                                  214      GND                     
                                  215      M_F_CPU1_SA_CA<5>       
                                  216      GND                     
                                  217      M_F_CPU1_CLK_DP<1>      
                                  218      M_F_CPU1_CLK_DN<1>      
                                  219      GND                     
                                  221      M_F_CPU1_SB_CA<1>       
                                  222      GND                     
                                  223      M_F_CPU1_SB_CA<3>       
                                  224      GND                     
                                  225      M_F_CPU1_SB_CA<5>       
                                  226      GND                     
                                  227      M_F_CPU1_SB_PAR         
                                  228      GND                     
                                  229      M_F_CPU1_SB_CS_N<3>     
                                  230      GND                     
                                  233      GND                     
                                  234      M_F_CPU1_SB_CB<6>       
                                  235      GND                     
                                  236      M_F_CPU1_SB_CB<7>       
                                  237      GND                     
                                  238      M_F_CPU1_SB_DQS_DN<4>   
                                  239      M_F_CPU1_SB_DQS_DP<4>   
                                  240      GND                     
                                  241      M_F_CPU1_SB_CB<2>       
                                  242      GND                     
                                  243      M_F_CPU1_SB_CB<3>       
                                  244      GND                     
                                  245      M_F_CPU1_SB_DQ<2>       
                                  246      GND                     
                                  247      M_F_CPU1_SB_DQ<3>       
                                  248      GND                     
                                  249      M_F_CPU1_SB_DQS_DN<5>   
                                  250      M_F_CPU1_SB_DQS_DP<5>   
                                  251      GND                     
                                  252      M_F_CPU1_SB_DQ<6>       
                                  253      GND                     
                                  254      M_F_CPU1_SB_DQ<7>       
                                  255      GND                     
                                  256      M_F_CPU1_SB_DQ<10>      
                                  257      GND                     
                                  258      M_F_CPU1_SB_DQ<11>      
                                  259      GND                     
                                  260      M_F_CPU1_SB_DQS_DN<6>   
                                  261      M_F_CPU1_SB_DQS_DP<6>   
                                  262      GND                     
                                  263      M_F_CPU1_SB_DQ<14>      
                                  264      GND                     
                                  265      M_F_CPU1_SB_DQ<15>      
                                  266      GND                     
                                  267      M_F_CPU1_SB_DQ<18>      
                                  268      GND                     
                                  269      M_F_CPU1_SB_DQ<19>      
                                  270      GND                     
                                  271      M_F_CPU1_SB_DQS_DN<7>   
                                  272      M_F_CPU1_SB_DQS_DP<7>   
                                  273      GND                     
                                  274      M_F_CPU1_SB_DQ<22>      
                                  275      GND                     
                                  276      M_F_CPU1_SB_DQ<23>      
                                  277      GND                     
                                  278      M_F_CPU1_SB_DQ<26>      
                                  279      GND                     
                                  280      M_F_CPU1_SB_DQ<27>      
                                  281      GND                     
                                  282      M_F_CPU1_SB_DQS_DN<8>   
                                  283      M_F_CPU1_SB_DQS_DP<8>   
                                  284      GND                     
                                  285      M_F_CPU1_SB_DQ<30>      
                                  286      GND                     
                                  287      M_F_CPU1_SB_DQ<31>      
                                  288      GND                     
                                  G1       GND                     
                                  G2       GND                     
                                  G3       GND                     
J29              SCONN288_ADR50001P013C01-SCONNA 1        P12V_S3_AUX_CPU1_NVDIMM 
                                  3        P3V3_AUX                
                                  4        I3C_SPD_DDREFGH_CPU1_LVC1_SCL
                                  5        I3C_SPD_DDREFGH_CPU1_LVC1_SDA
                                  6        GND                     
                                  7        M_G_CPU1_SA_DQ<0>       
                                  8        GND                     
                                  9        M_G_CPU1_SA_DQ<1>       
                                  10       GND                     
                                  11       M_G_CPU1_SA_DQS_DP<0>   
                                  12       M_G_CPU1_SA_DQS_DN<0>   
                                  13       GND                     
                                  14       M_G_CPU1_SA_DQ<4>       
                                  15       GND                     
                                  16       M_G_CPU1_SA_DQ<5>       
                                  17       GND                     
                                  18       M_G_CPU1_SA_DQ<8>       
                                  19       GND                     
                                  20       M_G_CPU1_SA_DQ<9>       
                                  21       GND                     
                                  22       M_G_CPU1_SA_DQS_DP<1>   
                                  23       M_G_CPU1_SA_DQS_DN<1>   
                                  24       GND                     
                                  25       M_G_CPU1_SA_DQ<12>      
                                  26       GND                     
                                  27       M_G_CPU1_SA_DQ<13>      
                                  28       GND                     
                                  29       M_G_CPU1_SA_DQ<16>      
                                  30       GND                     
                                  31       M_G_CPU1_SA_DQ<17>      
                                  32       GND                     
                                  33       M_G_CPU1_SA_DQS_DP<2>   
                                  34       M_G_CPU1_SA_DQS_DN<2>   
                                  35       GND                     
                                  36       M_G_CPU1_SA_DQ<20>      
                                  37       GND                     
                                  38       M_G_CPU1_SA_DQ<21>      
                                  39       GND                     
                                  40       M_G_CPU1_SA_DQ<24>      
                                  41       GND                     
                                  42       M_G_CPU1_SA_DQ<25>      
                                  43       GND                     
                                  44       M_G_CPU1_SA_DQS_DP<3>   
                                  45       M_G_CPU1_SA_DQS_DN<3>   
                                  46       GND                     
                                  47       M_G_CPU1_SA_DQ<28>      
                                  48       GND                     
                                  49       M_G_CPU1_SA_DQ<29>      
                                  50       GND                     
                                  51       M_G_CPU1_SA_CB<0>       
                                  52       GND                     
                                  53       M_G_CPU1_SA_CB<1>       
                                  54       GND                     
                                  55       M_G_CPU1_SA_DQS_DP<4>   
                                  56       M_G_CPU1_SA_DQS_DN<4>   
                                  57       GND                     
                                  58       M_G_CPU1_SA_CB<4>       
                                  59       GND                     
                                  60       M_G_CPU1_SA_CB<5>       
                                  61       GND                     
                                  62       M_G_CPU1_ALERT_N        
                                  63       GND                     
                                  64       M_G_CPU1_SA_CS_N<0>     
                                  65       GND                     
                                  66       M_G_CPU1_SA_CA<0>       
                                  67       GND                     
                                  68       M_G_CPU1_SA_CA<2>       
                                  69       GND                     
                                  70       M_G_CPU1_SA_CA<4>       
                                  71       GND                     
                                  72       M_G_CPU1_SA_CA<6>       
                                  73       GND                     
                                  74       M_G_CPU1_SA_PAR         
                                  75       GND                     
                                  76       M_G_CPU1_SB_CA<0>       
                                  77       GND                     
                                  78       M_G_CPU1_SB_CA<2>       
                                  79       GND                     
                                  80       M_G_CPU1_SB_CA<4>       
                                  81       GND                     
                                  82       M_G_CPU1_SB_CA<6>       
                                  83       GND                     
                                  84       M_G_CPU1_SB_CS_N<0>     
                                  85       GND                     
                                  86       M_G_CPU1_SA_RSP<0>      
                                  87       M_G_CPU1_SB_RSP<0>      
                                  88       GND                     
                                  89       M_G_CPU1_SB_CB<4>       
                                  90       GND                     
                                  91       M_G_CPU1_SB_CB<5>       
                                  92       GND                     
                                  93       M_G_CPU1_SB_DQS_DP<9>   
                                  94       M_G_CPU1_SB_DQS_DN<9>   
                                  95       GND                     
                                  96       M_G_CPU1_SB_CB<0>       
                                  97       GND                     
                                  98       M_G_CPU1_SB_CB<1>       
                                  99       GND                     
                                  100      M_G_CPU1_SB_DQ<0>       
                                  101      GND                     
                                  102      M_G_CPU1_SB_DQ<1>       
                                  103      GND                     
                                  104      M_G_CPU1_SB_DQS_DP<0>   
                                  105      M_G_CPU1_SB_DQS_DN<0>   
                                  106      GND                     
                                  107      M_G_CPU1_SB_DQ<4>       
                                  108      GND                     
                                  109      M_G_CPU1_SB_DQ<5>       
                                  110      GND                     
                                  111      M_G_CPU1_SB_DQ<8>       
                                  112      GND                     
                                  113      M_G_CPU1_SB_DQ<9>       
                                  114      GND                     
                                  115      M_G_CPU1_SB_DQS_DP<1>   
                                  116      M_G_CPU1_SB_DQS_DN<1>   
                                  117      GND                     
                                  118      M_G_CPU1_SB_DQ<12>      
                                  119      GND                     
                                  120      M_G_CPU1_SB_DQ<13>      
                                  121      GND                     
                                  122      M_G_CPU1_SB_DQ<16>      
                                  123      GND                     
                                  124      M_G_CPU1_SB_DQ<17>      
                                  125      GND                     
                                  126      M_G_CPU1_SB_DQS_DP<2>   
                                  127      M_G_CPU1_SB_DQS_DN<2>   
                                  128      GND                     
                                  129      M_G_CPU1_SB_DQ<20>      
                                  130      GND                     
                                  131      M_G_CPU1_SB_DQ<21>      
                                  132      GND                     
                                  133      M_G_CPU1_SB_DQ<24>      
                                  134      GND                     
                                  135      M_G_CPU1_SB_DQ<25>      
                                  136      GND                     
                                  137      M_G_CPU1_SB_DQS_DP<3>   
                                  138      M_G_CPU1_SB_DQS_DN<3>   
                                  139      GND                     
                                  140      M_G_CPU1_SB_DQ<28>      
                                  141      GND                     
                                  142      M_G_CPU1_SB_DQ<29>      
                                  143      GND                     
                                  145      P12V_S3_AUX_CPU1_NVDIMM 
                                  146      P12V_S3_AUX_CPU1_NVDIMM 
                                  147      PWRGD_CHG_CPU1_DIMM1    
                                  148      PD_CHG_CPU1_DIMM1_SAA   
                                  151      GND                     
                                  152      M_G_CPU1_SA_DQ<2>       
                                  153      GND                     
                                  154      M_G_CPU1_SA_DQ<3>       
                                  155      GND                     
                                  156      M_G_CPU1_SA_DQS_DN<5>   
                                  157      M_G_CPU1_SA_DQS_DP<5>   
                                  158      GND                     
                                  159      M_G_CPU1_SA_DQ<6>       
                                  160      GND                     
                                  161      M_G_CPU1_SA_DQ<7>       
                                  162      GND                     
                                  163      M_G_CPU1_SA_DQ<10>      
                                  164      GND                     
                                  165      M_G_CPU1_SA_DQ<11>      
                                  166      GND                     
                                  167      M_G_CPU1_SA_DQS_DN<6>   
                                  168      M_G_CPU1_SA_DQS_DP<6>   
                                  169      GND                     
                                  170      M_G_CPU1_SA_DQ<14>      
                                  171      GND                     
                                  172      M_G_CPU1_SA_DQ<15>      
                                  173      GND                     
                                  174      M_G_CPU1_SA_DQ<18>      
                                  175      GND                     
                                  176      M_G_CPU1_SA_DQ<19>      
                                  177      GND                     
                                  178      M_G_CPU1_SA_DQS_DN<7>   
                                  179      M_G_CPU1_SA_DQS_DP<7>   
                                  180      GND                     
                                  181      M_G_CPU1_SA_DQ<22>      
                                  182      GND                     
                                  183      M_G_CPU1_SA_DQ<23>      
                                  184      GND                     
                                  185      M_G_CPU1_SA_DQ<26>      
                                  186      GND                     
                                  187      M_G_CPU1_SA_DQ<27>      
                                  188      GND                     
                                  189      M_G_CPU1_SA_DQS_DN<8>   
                                  190      M_G_CPU1_SA_DQS_DP<8>   
                                  191      GND                     
                                  192      M_G_CPU1_SA_DQ<30>      
                                  193      GND                     
                                  194      M_G_CPU1_SA_DQ<31>      
                                  195      GND                     
                                  196      M_G_CPU1_SA_CB<2>       
                                  197      GND                     
                                  198      M_G_CPU1_SA_CB<3>       
                                  199      GND                     
                                  200      M_G_CPU1_SA_DQS_DN<9>   
                                  201      M_G_CPU1_SA_DQS_DP<9>   
                                  202      GND                     
                                  203      M_G_CPU1_SA_CB<6>       
                                  204      GND                     
                                  205      M_G_CPU1_SA_CB<7>       
                                  206      GND                     
                                  207      RST_M_GH_CPU1_FPGA_N    
                                  208      GND                     
                                  209      M_G_CPU1_SA_CS_N<1>     
                                  210      GND                     
                                  211      M_G_CPU1_SA_CA<1>       
                                  212      GND                     
                                  213      M_G_CPU1_SA_CA<3>       
                                  214      GND                     
                                  215      M_G_CPU1_SA_CA<5>       
                                  216      GND                     
                                  217      M_G_CPU1_CLK_DP<0>      
                                  218      M_G_CPU1_CLK_DN<0>      
                                  219      GND                     
                                  221      M_G_CPU1_SB_CA<1>       
                                  222      GND                     
                                  223      M_G_CPU1_SB_CA<3>       
                                  224      GND                     
                                  225      M_G_CPU1_SB_CA<5>       
                                  226      GND                     
                                  227      M_G_CPU1_SB_PAR         
                                  228      GND                     
                                  229      M_G_CPU1_SB_CS_N<1>     
                                  230      GND                     
                                  233      GND                     
                                  234      M_G_CPU1_SB_CB<6>       
                                  235      GND                     
                                  236      M_G_CPU1_SB_CB<7>       
                                  237      GND                     
                                  238      M_G_CPU1_SB_DQS_DN<4>   
                                  239      M_G_CPU1_SB_DQS_DP<4>   
                                  240      GND                     
                                  241      M_G_CPU1_SB_CB<2>       
                                  242      GND                     
                                  243      M_G_CPU1_SB_CB<3>       
                                  244      GND                     
                                  245      M_G_CPU1_SB_DQ<2>       
                                  246      GND                     
                                  247      M_G_CPU1_SB_DQ<3>       
                                  248      GND                     
                                  249      M_G_CPU1_SB_DQS_DN<5>   
                                  250      M_G_CPU1_SB_DQS_DP<5>   
                                  251      GND                     
                                  252      M_G_CPU1_SB_DQ<6>       
                                  253      GND                     
                                  254      M_G_CPU1_SB_DQ<7>       
                                  255      GND                     
                                  256      M_G_CPU1_SB_DQ<10>      
                                  257      GND                     
                                  258      M_G_CPU1_SB_DQ<11>      
                                  259      GND                     
                                  260      M_G_CPU1_SB_DQS_DN<6>   
                                  261      M_G_CPU1_SB_DQS_DP<6>   
                                  262      GND                     
                                  263      M_G_CPU1_SB_DQ<14>      
                                  264      GND                     
                                  265      M_G_CPU1_SB_DQ<15>      
                                  266      GND                     
                                  267      M_G_CPU1_SB_DQ<18>      
                                  268      GND                     
                                  269      M_G_CPU1_SB_DQ<19>      
                                  270      GND                     
                                  271      M_G_CPU1_SB_DQS_DN<7>   
                                  272      M_G_CPU1_SB_DQS_DP<7>   
                                  273      GND                     
                                  274      M_G_CPU1_SB_DQ<22>      
                                  275      GND                     
                                  276      M_G_CPU1_SB_DQ<23>      
                                  277      GND                     
                                  278      M_G_CPU1_SB_DQ<26>      
                                  279      GND                     
                                  280      M_G_CPU1_SB_DQ<27>      
                                  281      GND                     
                                  282      M_G_CPU1_SB_DQS_DN<8>   
                                  283      M_G_CPU1_SB_DQS_DP<8>   
                                  284      GND                     
                                  285      M_G_CPU1_SB_DQ<30>      
                                  286      GND                     
                                  287      M_G_CPU1_SB_DQ<31>      
                                  288      GND                     
                                  G1       GND                     
                                  G2       GND                     
                                  G3       GND                     
J30              SCONN288_ADR50001P003C01-SCONNA 1        P12V_S3_AUX_CPU1_NVDIMM 
                                  3        P3V3_AUX                
                                  4        I3C_SPD_DDREFGH_CPU1_LVC1_SCL
                                  5        I3C_SPD_DDREFGH_CPU1_LVC1_SDA
                                  6        GND                     
                                  7        M_G_CPU1_SA_DQ<0>       
                                  8        GND                     
                                  9        M_G_CPU1_SA_DQ<1>       
                                  10       GND                     
                                  11       M_G_CPU1_SA_DQS_DP<0>   
                                  12       M_G_CPU1_SA_DQS_DN<0>   
                                  13       GND                     
                                  14       M_G_CPU1_SA_DQ<4>       
                                  15       GND                     
                                  16       M_G_CPU1_SA_DQ<5>       
                                  17       GND                     
                                  18       M_G_CPU1_SA_DQ<8>       
                                  19       GND                     
                                  20       M_G_CPU1_SA_DQ<9>       
                                  21       GND                     
                                  22       M_G_CPU1_SA_DQS_DP<1>   
                                  23       M_G_CPU1_SA_DQS_DN<1>   
                                  24       GND                     
                                  25       M_G_CPU1_SA_DQ<12>      
                                  26       GND                     
                                  27       M_G_CPU1_SA_DQ<13>      
                                  28       GND                     
                                  29       M_G_CPU1_SA_DQ<16>      
                                  30       GND                     
                                  31       M_G_CPU1_SA_DQ<17>      
                                  32       GND                     
                                  33       M_G_CPU1_SA_DQS_DP<2>   
                                  34       M_G_CPU1_SA_DQS_DN<2>   
                                  35       GND                     
                                  36       M_G_CPU1_SA_DQ<20>      
                                  37       GND                     
                                  38       M_G_CPU1_SA_DQ<21>      
                                  39       GND                     
                                  40       M_G_CPU1_SA_DQ<24>      
                                  41       GND                     
                                  42       M_G_CPU1_SA_DQ<25>      
                                  43       GND                     
                                  44       M_G_CPU1_SA_DQS_DP<3>   
                                  45       M_G_CPU1_SA_DQS_DN<3>   
                                  46       GND                     
                                  47       M_G_CPU1_SA_DQ<28>      
                                  48       GND                     
                                  49       M_G_CPU1_SA_DQ<29>      
                                  50       GND                     
                                  51       M_G_CPU1_SA_CB<0>       
                                  52       GND                     
                                  53       M_G_CPU1_SA_CB<1>       
                                  54       GND                     
                                  55       M_G_CPU1_SA_DQS_DP<4>   
                                  56       M_G_CPU1_SA_DQS_DN<4>   
                                  57       GND                     
                                  58       M_G_CPU1_SA_CB<4>       
                                  59       GND                     
                                  60       M_G_CPU1_SA_CB<5>       
                                  61       GND                     
                                  62       M_G_CPU1_ALERT_N        
                                  63       GND                     
                                  64       M_G_CPU1_SA_CS_N<2>     
                                  65       GND                     
                                  66       M_G_CPU1_SA_CA<0>       
                                  67       GND                     
                                  68       M_G_CPU1_SA_CA<2>       
                                  69       GND                     
                                  70       M_G_CPU1_SA_CA<4>       
                                  71       GND                     
                                  72       M_G_CPU1_SA_CA<6>       
                                  73       GND                     
                                  74       M_G_CPU1_SA_PAR         
                                  75       GND                     
                                  76       M_G_CPU1_SB_CA<0>       
                                  77       GND                     
                                  78       M_G_CPU1_SB_CA<2>       
                                  79       GND                     
                                  80       M_G_CPU1_SB_CA<4>       
                                  81       GND                     
                                  82       M_G_CPU1_SB_CA<6>       
                                  83       GND                     
                                  84       M_G_CPU1_SB_CS_N<2>     
                                  85       GND                     
                                  86       M_G_CPU1_SA_RSP<1>      
                                  87       M_G_CPU1_SB_RSP<1>      
                                  88       GND                     
                                  89       M_G_CPU1_SB_CB<4>       
                                  90       GND                     
                                  91       M_G_CPU1_SB_CB<5>       
                                  92       GND                     
                                  93       M_G_CPU1_SB_DQS_DP<9>   
                                  94       M_G_CPU1_SB_DQS_DN<9>   
                                  95       GND                     
                                  96       M_G_CPU1_SB_CB<0>       
                                  97       GND                     
                                  98       M_G_CPU1_SB_CB<1>       
                                  99       GND                     
                                  100      M_G_CPU1_SB_DQ<0>       
                                  101      GND                     
                                  102      M_G_CPU1_SB_DQ<1>       
                                  103      GND                     
                                  104      M_G_CPU1_SB_DQS_DP<0>   
                                  105      M_G_CPU1_SB_DQS_DN<0>   
                                  106      GND                     
                                  107      M_G_CPU1_SB_DQ<4>       
                                  108      GND                     
                                  109      M_G_CPU1_SB_DQ<5>       
                                  110      GND                     
                                  111      M_G_CPU1_SB_DQ<8>       
                                  112      GND                     
                                  113      M_G_CPU1_SB_DQ<9>       
                                  114      GND                     
                                  115      M_G_CPU1_SB_DQS_DP<1>   
                                  116      M_G_CPU1_SB_DQS_DN<1>   
                                  117      GND                     
                                  118      M_G_CPU1_SB_DQ<12>      
                                  119      GND                     
                                  120      M_G_CPU1_SB_DQ<13>      
                                  121      GND                     
                                  122      M_G_CPU1_SB_DQ<16>      
                                  123      GND                     
                                  124      M_G_CPU1_SB_DQ<17>      
                                  125      GND                     
                                  126      M_G_CPU1_SB_DQS_DP<2>   
                                  127      M_G_CPU1_SB_DQS_DN<2>   
                                  128      GND                     
                                  129      M_G_CPU1_SB_DQ<20>      
                                  130      GND                     
                                  131      M_G_CPU1_SB_DQ<21>      
                                  132      GND                     
                                  133      M_G_CPU1_SB_DQ<24>      
                                  134      GND                     
                                  135      M_G_CPU1_SB_DQ<25>      
                                  136      GND                     
                                  137      M_G_CPU1_SB_DQS_DP<3>   
                                  138      M_G_CPU1_SB_DQS_DN<3>   
                                  139      GND                     
                                  140      M_G_CPU1_SB_DQ<28>      
                                  141      GND                     
                                  142      M_G_CPU1_SB_DQ<29>      
                                  143      GND                     
                                  145      P12V_S3_AUX_CPU1_NVDIMM 
                                  146      P12V_S3_AUX_CPU1_NVDIMM 
                                  147      PWRGD_CHG_CPU1_DIMM2    
                                  148      PD_CHG_CPU1_DIMM2_SAA   
                                  151      GND                     
                                  152      M_G_CPU1_SA_DQ<2>       
                                  153      GND                     
                                  154      M_G_CPU1_SA_DQ<3>       
                                  155      GND                     
                                  156      M_G_CPU1_SA_DQS_DN<5>   
                                  157      M_G_CPU1_SA_DQS_DP<5>   
                                  158      GND                     
                                  159      M_G_CPU1_SA_DQ<6>       
                                  160      GND                     
                                  161      M_G_CPU1_SA_DQ<7>       
                                  162      GND                     
                                  163      M_G_CPU1_SA_DQ<10>      
                                  164      GND                     
                                  165      M_G_CPU1_SA_DQ<11>      
                                  166      GND                     
                                  167      M_G_CPU1_SA_DQS_DN<6>   
                                  168      M_G_CPU1_SA_DQS_DP<6>   
                                  169      GND                     
                                  170      M_G_CPU1_SA_DQ<14>      
                                  171      GND                     
                                  172      M_G_CPU1_SA_DQ<15>      
                                  173      GND                     
                                  174      M_G_CPU1_SA_DQ<18>      
                                  175      GND                     
                                  176      M_G_CPU1_SA_DQ<19>      
                                  177      GND                     
                                  178      M_G_CPU1_SA_DQS_DN<7>   
                                  179      M_G_CPU1_SA_DQS_DP<7>   
                                  180      GND                     
                                  181      M_G_CPU1_SA_DQ<22>      
                                  182      GND                     
                                  183      M_G_CPU1_SA_DQ<23>      
                                  184      GND                     
                                  185      M_G_CPU1_SA_DQ<26>      
                                  186      GND                     
                                  187      M_G_CPU1_SA_DQ<27>      
                                  188      GND                     
                                  189      M_G_CPU1_SA_DQS_DN<8>   
                                  190      M_G_CPU1_SA_DQS_DP<8>   
                                  191      GND                     
                                  192      M_G_CPU1_SA_DQ<30>      
                                  193      GND                     
                                  194      M_G_CPU1_SA_DQ<31>      
                                  195      GND                     
                                  196      M_G_CPU1_SA_CB<2>       
                                  197      GND                     
                                  198      M_G_CPU1_SA_CB<3>       
                                  199      GND                     
                                  200      M_G_CPU1_SA_DQS_DN<9>   
                                  201      M_G_CPU1_SA_DQS_DP<9>   
                                  202      GND                     
                                  203      M_G_CPU1_SA_CB<6>       
                                  204      GND                     
                                  205      M_G_CPU1_SA_CB<7>       
                                  206      GND                     
                                  207      RST_M_GH_CPU1_FPGA_N    
                                  208      GND                     
                                  209      M_G_CPU1_SA_CS_N<3>     
                                  210      GND                     
                                  211      M_G_CPU1_SA_CA<1>       
                                  212      GND                     
                                  213      M_G_CPU1_SA_CA<3>       
                                  214      GND                     
                                  215      M_G_CPU1_SA_CA<5>       
                                  216      GND                     
                                  217      M_G_CPU1_CLK_DP<1>      
                                  218      M_G_CPU1_CLK_DN<1>      
                                  219      GND                     
                                  221      M_G_CPU1_SB_CA<1>       
                                  222      GND                     
                                  223      M_G_CPU1_SB_CA<3>       
                                  224      GND                     
                                  225      M_G_CPU1_SB_CA<5>       
                                  226      GND                     
                                  227      M_G_CPU1_SB_PAR         
                                  228      GND                     
                                  229      M_G_CPU1_SB_CS_N<3>     
                                  230      GND                     
                                  233      GND                     
                                  234      M_G_CPU1_SB_CB<6>       
                                  235      GND                     
                                  236      M_G_CPU1_SB_CB<7>       
                                  237      GND                     
                                  238      M_G_CPU1_SB_DQS_DN<4>   
                                  239      M_G_CPU1_SB_DQS_DP<4>   
                                  240      GND                     
                                  241      M_G_CPU1_SB_CB<2>       
                                  242      GND                     
                                  243      M_G_CPU1_SB_CB<3>       
                                  244      GND                     
                                  245      M_G_CPU1_SB_DQ<2>       
                                  246      GND                     
                                  247      M_G_CPU1_SB_DQ<3>       
                                  248      GND                     
                                  249      M_G_CPU1_SB_DQS_DN<5>   
                                  250      M_G_CPU1_SB_DQS_DP<5>   
                                  251      GND                     
                                  252      M_G_CPU1_SB_DQ<6>       
                                  253      GND                     
                                  254      M_G_CPU1_SB_DQ<7>       
                                  255      GND                     
                                  256      M_G_CPU1_SB_DQ<10>      
                                  257      GND                     
                                  258      M_G_CPU1_SB_DQ<11>      
                                  259      GND                     
                                  260      M_G_CPU1_SB_DQS_DN<6>   
                                  261      M_G_CPU1_SB_DQS_DP<6>   
                                  262      GND                     
                                  263      M_G_CPU1_SB_DQ<14>      
                                  264      GND                     
                                  265      M_G_CPU1_SB_DQ<15>      
                                  266      GND                     
                                  267      M_G_CPU1_SB_DQ<18>      
                                  268      GND                     
                                  269      M_G_CPU1_SB_DQ<19>      
                                  270      GND                     
                                  271      M_G_CPU1_SB_DQS_DN<7>   
                                  272      M_G_CPU1_SB_DQS_DP<7>   
                                  273      GND                     
                                  274      M_G_CPU1_SB_DQ<22>      
                                  275      GND                     
                                  276      M_G_CPU1_SB_DQ<23>      
                                  277      GND                     
                                  278      M_G_CPU1_SB_DQ<26>      
                                  279      GND                     
                                  280      M_G_CPU1_SB_DQ<27>      
                                  281      GND                     
                                  282      M_G_CPU1_SB_DQS_DN<8>   
                                  283      M_G_CPU1_SB_DQS_DP<8>   
                                  284      GND                     
                                  285      M_G_CPU1_SB_DQ<30>      
                                  286      GND                     
                                  287      M_G_CPU1_SB_DQ<31>      
                                  288      GND                     
                                  G1       GND                     
                                  G2       GND                     
                                  G3       GND                     
J31              SCONN288_ADR50001P013C01-SCONNA 1        P12V_S3_AUX_CPU1_NVDIMM 
                                  3        P3V3_AUX                
                                  4        I3C_SPD_DDREFGH_CPU1_LVC1_SCL
                                  5        I3C_SPD_DDREFGH_CPU1_LVC1_SDA
                                  6        GND                     
                                  7        M_H_CPU1_SA_DQ<0>       
                                  8        GND                     
                                  9        M_H_CPU1_SA_DQ<1>       
                                  10       GND                     
                                  11       M_H_CPU1_SA_DQS_DP<0>   
                                  12       M_H_CPU1_SA_DQS_DN<0>   
                                  13       GND                     
                                  14       M_H_CPU1_SA_DQ<4>       
                                  15       GND                     
                                  16       M_H_CPU1_SA_DQ<5>       
                                  17       GND                     
                                  18       M_H_CPU1_SA_DQ<8>       
                                  19       GND                     
                                  20       M_H_CPU1_SA_DQ<9>       
                                  21       GND                     
                                  22       M_H_CPU1_SA_DQS_DP<1>   
                                  23       M_H_CPU1_SA_DQS_DN<1>   
                                  24       GND                     
                                  25       M_H_CPU1_SA_DQ<12>      
                                  26       GND                     
                                  27       M_H_CPU1_SA_DQ<13>      
                                  28       GND                     
                                  29       M_H_CPU1_SA_DQ<16>      
                                  30       GND                     
                                  31       M_H_CPU1_SA_DQ<17>      
                                  32       GND                     
                                  33       M_H_CPU1_SA_DQS_DP<2>   
                                  34       M_H_CPU1_SA_DQS_DN<2>   
                                  35       GND                     
                                  36       M_H_CPU1_SA_DQ<20>      
                                  37       GND                     
                                  38       M_H_CPU1_SA_DQ<21>      
                                  39       GND                     
                                  40       M_H_CPU1_SA_DQ<24>      
                                  41       GND                     
                                  42       M_H_CPU1_SA_DQ<25>      
                                  43       GND                     
                                  44       M_H_CPU1_SA_DQS_DP<3>   
                                  45       M_H_CPU1_SA_DQS_DN<3>   
                                  46       GND                     
                                  47       M_H_CPU1_SA_DQ<28>      
                                  48       GND                     
                                  49       M_H_CPU1_SA_DQ<29>      
                                  50       GND                     
                                  51       M_H_CPU1_SA_CB<0>       
                                  52       GND                     
                                  53       M_H_CPU1_SA_CB<1>       
                                  54       GND                     
                                  55       M_H_CPU1_SA_DQS_DP<4>   
                                  56       M_H_CPU1_SA_DQS_DN<4>   
                                  57       GND                     
                                  58       M_H_CPU1_SA_CB<4>       
                                  59       GND                     
                                  60       M_H_CPU1_SA_CB<5>       
                                  61       GND                     
                                  62       M_H_CPU1_ALERT_N        
                                  63       GND                     
                                  64       M_H_CPU1_SA_CS_N<0>     
                                  65       GND                     
                                  66       M_H_CPU1_SA_CA<0>       
                                  67       GND                     
                                  68       M_H_CPU1_SA_CA<2>       
                                  69       GND                     
                                  70       M_H_CPU1_SA_CA<4>       
                                  71       GND                     
                                  72       M_H_CPU1_SA_CA<6>       
                                  73       GND                     
                                  74       M_H_CPU1_SA_PAR         
                                  75       GND                     
                                  76       M_H_CPU1_SB_CA<0>       
                                  77       GND                     
                                  78       M_H_CPU1_SB_CA<2>       
                                  79       GND                     
                                  80       M_H_CPU1_SB_CA<4>       
                                  81       GND                     
                                  82       M_H_CPU1_SB_CA<6>       
                                  83       GND                     
                                  84       M_H_CPU1_SB_CS_N<0>     
                                  85       GND                     
                                  86       M_H_CPU1_SA_RSP<0>      
                                  87       M_H_CPU1_SB_RSP<0>      
                                  88       GND                     
                                  89       M_H_CPU1_SB_CB<4>       
                                  90       GND                     
                                  91       M_H_CPU1_SB_CB<5>       
                                  92       GND                     
                                  93       M_H_CPU1_SB_DQS_DP<9>   
                                  94       M_H_CPU1_SB_DQS_DN<9>   
                                  95       GND                     
                                  96       M_H_CPU1_SB_CB<0>       
                                  97       GND                     
                                  98       M_H_CPU1_SB_CB<1>       
                                  99       GND                     
                                  100      M_H_CPU1_SB_DQ<0>       
                                  101      GND                     
                                  102      M_H_CPU1_SB_DQ<1>       
                                  103      GND                     
                                  104      M_H_CPU1_SB_DQS_DP<0>   
                                  105      M_H_CPU1_SB_DQS_DN<0>   
                                  106      GND                     
                                  107      M_H_CPU1_SB_DQ<4>       
                                  108      GND                     
                                  109      M_H_CPU1_SB_DQ<5>       
                                  110      GND                     
                                  111      M_H_CPU1_SB_DQ<8>       
                                  112      GND                     
                                  113      M_H_CPU1_SB_DQ<9>       
                                  114      GND                     
                                  115      M_H_CPU1_SB_DQS_DP<1>   
                                  116      M_H_CPU1_SB_DQS_DN<1>   
                                  117      GND                     
                                  118      M_H_CPU1_SB_DQ<12>      
                                  119      GND                     
                                  120      M_H_CPU1_SB_DQ<13>      
                                  121      GND                     
                                  122      M_H_CPU1_SB_DQ<16>      
                                  123      GND                     
                                  124      M_H_CPU1_SB_DQ<17>      
                                  125      GND                     
                                  126      M_H_CPU1_SB_DQS_DP<2>   
                                  127      M_H_CPU1_SB_DQS_DN<2>   
                                  128      GND                     
                                  129      M_H_CPU1_SB_DQ<20>      
                                  130      GND                     
                                  131      M_H_CPU1_SB_DQ<21>      
                                  132      GND                     
                                  133      M_H_CPU1_SB_DQ<24>      
                                  134      GND                     
                                  135      M_H_CPU1_SB_DQ<25>      
                                  136      GND                     
                                  137      M_H_CPU1_SB_DQS_DP<3>   
                                  138      M_H_CPU1_SB_DQS_DN<3>   
                                  139      GND                     
                                  140      M_H_CPU1_SB_DQ<28>      
                                  141      GND                     
                                  142      M_H_CPU1_SB_DQ<29>      
                                  143      GND                     
                                  145      P12V_S3_AUX_CPU1_NVDIMM 
                                  146      P12V_S3_AUX_CPU1_NVDIMM 
                                  147      PWRGD_CHH_CPU1_DIMM1    
                                  148      PD_CHH_CPU1_DIMM1_SAA   
                                  151      GND                     
                                  152      M_H_CPU1_SA_DQ<2>       
                                  153      GND                     
                                  154      M_H_CPU1_SA_DQ<3>       
                                  155      GND                     
                                  156      M_H_CPU1_SA_DQS_DN<5>   
                                  157      M_H_CPU1_SA_DQS_DP<5>   
                                  158      GND                     
                                  159      M_H_CPU1_SA_DQ<6>       
                                  160      GND                     
                                  161      M_H_CPU1_SA_DQ<7>       
                                  162      GND                     
                                  163      M_H_CPU1_SA_DQ<10>      
                                  164      GND                     
                                  165      M_H_CPU1_SA_DQ<11>      
                                  166      GND                     
                                  167      M_H_CPU1_SA_DQS_DN<6>   
                                  168      M_H_CPU1_SA_DQS_DP<6>   
                                  169      GND                     
                                  170      M_H_CPU1_SA_DQ<14>      
                                  171      GND                     
                                  172      M_H_CPU1_SA_DQ<15>      
                                  173      GND                     
                                  174      M_H_CPU1_SA_DQ<18>      
                                  175      GND                     
                                  176      M_H_CPU1_SA_DQ<19>      
                                  177      GND                     
                                  178      M_H_CPU1_SA_DQS_DN<7>   
                                  179      M_H_CPU1_SA_DQS_DP<7>   
                                  180      GND                     
                                  181      M_H_CPU1_SA_DQ<22>      
                                  182      GND                     
                                  183      M_H_CPU1_SA_DQ<23>      
                                  184      GND                     
                                  185      M_H_CPU1_SA_DQ<26>      
                                  186      GND                     
                                  187      M_H_CPU1_SA_DQ<27>      
                                  188      GND                     
                                  189      M_H_CPU1_SA_DQS_DN<8>   
                                  190      M_H_CPU1_SA_DQS_DP<8>   
                                  191      GND                     
                                  192      M_H_CPU1_SA_DQ<30>      
                                  193      GND                     
                                  194      M_H_CPU1_SA_DQ<31>      
                                  195      GND                     
                                  196      M_H_CPU1_SA_CB<2>       
                                  197      GND                     
                                  198      M_H_CPU1_SA_CB<3>       
                                  199      GND                     
                                  200      M_H_CPU1_SA_DQS_DN<9>   
                                  201      M_H_CPU1_SA_DQS_DP<9>   
                                  202      GND                     
                                  203      M_H_CPU1_SA_CB<6>       
                                  204      GND                     
                                  205      M_H_CPU1_SA_CB<7>       
                                  206      GND                     
                                  207      RST_M_GH_CPU1_FPGA_N    
                                  208      GND                     
                                  209      M_H_CPU1_SA_CS_N<1>     
                                  210      GND                     
                                  211      M_H_CPU1_SA_CA<1>       
                                  212      GND                     
                                  213      M_H_CPU1_SA_CA<3>       
                                  214      GND                     
                                  215      M_H_CPU1_SA_CA<5>       
                                  216      GND                     
                                  217      M_H_CPU1_CLK_DP<0>      
                                  218      M_H_CPU1_CLK_DN<0>      
                                  219      GND                     
                                  221      M_H_CPU1_SB_CA<1>       
                                  222      GND                     
                                  223      M_H_CPU1_SB_CA<3>       
                                  224      GND                     
                                  225      M_H_CPU1_SB_CA<5>       
                                  226      GND                     
                                  227      M_H_CPU1_SB_PAR         
                                  228      GND                     
                                  229      M_H_CPU1_SB_CS_N<1>     
                                  230      GND                     
                                  233      GND                     
                                  234      M_H_CPU1_SB_CB<6>       
                                  235      GND                     
                                  236      M_H_CPU1_SB_CB<7>       
                                  237      GND                     
                                  238      M_H_CPU1_SB_DQS_DN<4>   
                                  239      M_H_CPU1_SB_DQS_DP<4>   
                                  240      GND                     
                                  241      M_H_CPU1_SB_CB<2>       
                                  242      GND                     
                                  243      M_H_CPU1_SB_CB<3>       
                                  244      GND                     
                                  245      M_H_CPU1_SB_DQ<2>       
                                  246      GND                     
                                  247      M_H_CPU1_SB_DQ<3>       
                                  248      GND                     
                                  249      M_H_CPU1_SB_DQS_DN<5>   
                                  250      M_H_CPU1_SB_DQS_DP<5>   
                                  251      GND                     
                                  252      M_H_CPU1_SB_DQ<6>       
                                  253      GND                     
                                  254      M_H_CPU1_SB_DQ<7>       
                                  255      GND                     
                                  256      M_H_CPU1_SB_DQ<10>      
                                  257      GND                     
                                  258      M_H_CPU1_SB_DQ<11>      
                                  259      GND                     
                                  260      M_H_CPU1_SB_DQS_DN<6>   
                                  261      M_H_CPU1_SB_DQS_DP<6>   
                                  262      GND                     
                                  263      M_H_CPU1_SB_DQ<14>      
                                  264      GND                     
                                  265      M_H_CPU1_SB_DQ<15>      
                                  266      GND                     
                                  267      M_H_CPU1_SB_DQ<18>      
                                  268      GND                     
                                  269      M_H_CPU1_SB_DQ<19>      
                                  270      GND                     
                                  271      M_H_CPU1_SB_DQS_DN<7>   
                                  272      M_H_CPU1_SB_DQS_DP<7>   
                                  273      GND                     
                                  274      M_H_CPU1_SB_DQ<22>      
                                  275      GND                     
                                  276      M_H_CPU1_SB_DQ<23>      
                                  277      GND                     
                                  278      M_H_CPU1_SB_DQ<26>      
                                  279      GND                     
                                  280      M_H_CPU1_SB_DQ<27>      
                                  281      GND                     
                                  282      M_H_CPU1_SB_DQS_DN<8>   
                                  283      M_H_CPU1_SB_DQS_DP<8>   
                                  284      GND                     
                                  285      M_H_CPU1_SB_DQ<30>      
                                  286      GND                     
                                  287      M_H_CPU1_SB_DQ<31>      
                                  288      GND                     
                                  G1       GND                     
                                  G2       GND                     
                                  G3       GND                     
J32              SCONN288_ADR50001P003C01-SCONNA 1        P12V_S3_AUX_CPU1_NVDIMM 
                                  3        P3V3_AUX                
                                  4        I3C_SPD_DDREFGH_CPU1_LVC1_SCL
                                  5        I3C_SPD_DDREFGH_CPU1_LVC1_SDA
                                  6        GND                     
                                  7        M_H_CPU1_SA_DQ<0>       
                                  8        GND                     
                                  9        M_H_CPU1_SA_DQ<1>       
                                  10       GND                     
                                  11       M_H_CPU1_SA_DQS_DP<0>   
                                  12       M_H_CPU1_SA_DQS_DN<0>   
                                  13       GND                     
                                  14       M_H_CPU1_SA_DQ<4>       
                                  15       GND                     
                                  16       M_H_CPU1_SA_DQ<5>       
                                  17       GND                     
                                  18       M_H_CPU1_SA_DQ<8>       
                                  19       GND                     
                                  20       M_H_CPU1_SA_DQ<9>       
                                  21       GND                     
                                  22       M_H_CPU1_SA_DQS_DP<1>   
                                  23       M_H_CPU1_SA_DQS_DN<1>   
                                  24       GND                     
                                  25       M_H_CPU1_SA_DQ<12>      
                                  26       GND                     
                                  27       M_H_CPU1_SA_DQ<13>      
                                  28       GND                     
                                  29       M_H_CPU1_SA_DQ<16>      
                                  30       GND                     
                                  31       M_H_CPU1_SA_DQ<17>      
                                  32       GND                     
                                  33       M_H_CPU1_SA_DQS_DP<2>   
                                  34       M_H_CPU1_SA_DQS_DN<2>   
                                  35       GND                     
                                  36       M_H_CPU1_SA_DQ<20>      
                                  37       GND                     
                                  38       M_H_CPU1_SA_DQ<21>      
                                  39       GND                     
                                  40       M_H_CPU1_SA_DQ<24>      
                                  41       GND                     
                                  42       M_H_CPU1_SA_DQ<25>      
                                  43       GND                     
                                  44       M_H_CPU1_SA_DQS_DP<3>   
                                  45       M_H_CPU1_SA_DQS_DN<3>   
                                  46       GND                     
                                  47       M_H_CPU1_SA_DQ<28>      
                                  48       GND                     
                                  49       M_H_CPU1_SA_DQ<29>      
                                  50       GND                     
                                  51       M_H_CPU1_SA_CB<0>       
                                  52       GND                     
                                  53       M_H_CPU1_SA_CB<1>       
                                  54       GND                     
                                  55       M_H_CPU1_SA_DQS_DP<4>   
                                  56       M_H_CPU1_SA_DQS_DN<4>   
                                  57       GND                     
                                  58       M_H_CPU1_SA_CB<4>       
                                  59       GND                     
                                  60       M_H_CPU1_SA_CB<5>       
                                  61       GND                     
                                  62       M_H_CPU1_ALERT_N        
                                  63       GND                     
                                  64       M_H_CPU1_SA_CS_N<2>     
                                  65       GND                     
                                  66       M_H_CPU1_SA_CA<0>       
                                  67       GND                     
                                  68       M_H_CPU1_SA_CA<2>       
                                  69       GND                     
                                  70       M_H_CPU1_SA_CA<4>       
                                  71       GND                     
                                  72       M_H_CPU1_SA_CA<6>       
                                  73       GND                     
                                  74       M_H_CPU1_SA_PAR         
                                  75       GND                     
                                  76       M_H_CPU1_SB_CA<0>       
                                  77       GND                     
                                  78       M_H_CPU1_SB_CA<2>       
                                  79       GND                     
                                  80       M_H_CPU1_SB_CA<4>       
                                  81       GND                     
                                  82       M_H_CPU1_SB_CA<6>       
                                  83       GND                     
                                  84       M_H_CPU1_SB_CS_N<2>     
                                  85       GND                     
                                  86       M_H_CPU1_SA_RSP<1>      
                                  87       M_H_CPU1_SB_RSP<1>      
                                  88       GND                     
                                  89       M_H_CPU1_SB_CB<4>       
                                  90       GND                     
                                  91       M_H_CPU1_SB_CB<5>       
                                  92       GND                     
                                  93       M_H_CPU1_SB_DQS_DP<9>   
                                  94       M_H_CPU1_SB_DQS_DN<9>   
                                  95       GND                     
                                  96       M_H_CPU1_SB_CB<0>       
                                  97       GND                     
                                  98       M_H_CPU1_SB_CB<1>       
                                  99       GND                     
                                  100      M_H_CPU1_SB_DQ<0>       
                                  101      GND                     
                                  102      M_H_CPU1_SB_DQ<1>       
                                  103      GND                     
                                  104      M_H_CPU1_SB_DQS_DP<0>   
                                  105      M_H_CPU1_SB_DQS_DN<0>   
                                  106      GND                     
                                  107      M_H_CPU1_SB_DQ<4>       
                                  108      GND                     
                                  109      M_H_CPU1_SB_DQ<5>       
                                  110      GND                     
                                  111      M_H_CPU1_SB_DQ<8>       
                                  112      GND                     
                                  113      M_H_CPU1_SB_DQ<9>       
                                  114      GND                     
                                  115      M_H_CPU1_SB_DQS_DP<1>   
                                  116      M_H_CPU1_SB_DQS_DN<1>   
                                  117      GND                     
                                  118      M_H_CPU1_SB_DQ<12>      
                                  119      GND                     
                                  120      M_H_CPU1_SB_DQ<13>      
                                  121      GND                     
                                  122      M_H_CPU1_SB_DQ<16>      
                                  123      GND                     
                                  124      M_H_CPU1_SB_DQ<17>      
                                  125      GND                     
                                  126      M_H_CPU1_SB_DQS_DP<2>   
                                  127      M_H_CPU1_SB_DQS_DN<2>   
                                  128      GND                     
                                  129      M_H_CPU1_SB_DQ<20>      
                                  130      GND                     
                                  131      M_H_CPU1_SB_DQ<21>      
                                  132      GND                     
                                  133      M_H_CPU1_SB_DQ<24>      
                                  134      GND                     
                                  135      M_H_CPU1_SB_DQ<25>      
                                  136      GND                     
                                  137      M_H_CPU1_SB_DQS_DP<3>   
                                  138      M_H_CPU1_SB_DQS_DN<3>   
                                  139      GND                     
                                  140      M_H_CPU1_SB_DQ<28>      
                                  141      GND                     
                                  142      M_H_CPU1_SB_DQ<29>      
                                  143      GND                     
                                  145      P12V_S3_AUX_CPU1_NVDIMM 
                                  146      P12V_S3_AUX_CPU1_NVDIMM 
                                  147      PWRGD_CHH_CPU1_DIMM2    
                                  148      PD_CHH_CPU1_DIMM2_SAA   
                                  151      GND                     
                                  152      M_H_CPU1_SA_DQ<2>       
                                  153      GND                     
                                  154      M_H_CPU1_SA_DQ<3>       
                                  155      GND                     
                                  156      M_H_CPU1_SA_DQS_DN<5>   
                                  157      M_H_CPU1_SA_DQS_DP<5>   
                                  158      GND                     
                                  159      M_H_CPU1_SA_DQ<6>       
                                  160      GND                     
                                  161      M_H_CPU1_SA_DQ<7>       
                                  162      GND                     
                                  163      M_H_CPU1_SA_DQ<10>      
                                  164      GND                     
                                  165      M_H_CPU1_SA_DQ<11>      
                                  166      GND                     
                                  167      M_H_CPU1_SA_DQS_DN<6>   
                                  168      M_H_CPU1_SA_DQS_DP<6>   
                                  169      GND                     
                                  170      M_H_CPU1_SA_DQ<14>      
                                  171      GND                     
                                  172      M_H_CPU1_SA_DQ<15>      
                                  173      GND                     
                                  174      M_H_CPU1_SA_DQ<18>      
                                  175      GND                     
                                  176      M_H_CPU1_SA_DQ<19>      
                                  177      GND                     
                                  178      M_H_CPU1_SA_DQS_DN<7>   
                                  179      M_H_CPU1_SA_DQS_DP<7>   
                                  180      GND                     
                                  181      M_H_CPU1_SA_DQ<22>      
                                  182      GND                     
                                  183      M_H_CPU1_SA_DQ<23>      
                                  184      GND                     
                                  185      M_H_CPU1_SA_DQ<26>      
                                  186      GND                     
                                  187      M_H_CPU1_SA_DQ<27>      
                                  188      GND                     
                                  189      M_H_CPU1_SA_DQS_DN<8>   
                                  190      M_H_CPU1_SA_DQS_DP<8>   
                                  191      GND                     
                                  192      M_H_CPU1_SA_DQ<30>      
                                  193      GND                     
                                  194      M_H_CPU1_SA_DQ<31>      
                                  195      GND                     
                                  196      M_H_CPU1_SA_CB<2>       
                                  197      GND                     
                                  198      M_H_CPU1_SA_CB<3>       
                                  199      GND                     
                                  200      M_H_CPU1_SA_DQS_DN<9>   
                                  201      M_H_CPU1_SA_DQS_DP<9>   
                                  202      GND                     
                                  203      M_H_CPU1_SA_CB<6>       
                                  204      GND                     
                                  205      M_H_CPU1_SA_CB<7>       
                                  206      GND                     
                                  207      RST_M_GH_CPU1_FPGA_N    
                                  208      GND                     
                                  209      M_H_CPU1_SA_CS_N<3>     
                                  210      GND                     
                                  211      M_H_CPU1_SA_CA<1>       
                                  212      GND                     
                                  213      M_H_CPU1_SA_CA<3>       
                                  214      GND                     
                                  215      M_H_CPU1_SA_CA<5>       
                                  216      GND                     
                                  217      M_H_CPU1_CLK_DP<1>      
                                  218      M_H_CPU1_CLK_DN<1>      
                                  219      GND                     
                                  221      M_H_CPU1_SB_CA<1>       
                                  222      GND                     
                                  223      M_H_CPU1_SB_CA<3>       
                                  224      GND                     
                                  225      M_H_CPU1_SB_CA<5>       
                                  226      GND                     
                                  227      M_H_CPU1_SB_PAR         
                                  228      GND                     
                                  229      M_H_CPU1_SB_CS_N<3>     
                                  230      GND                     
                                  233      GND                     
                                  234      M_H_CPU1_SB_CB<6>       
                                  235      GND                     
                                  236      M_H_CPU1_SB_CB<7>       
                                  237      GND                     
                                  238      M_H_CPU1_SB_DQS_DN<4>   
                                  239      M_H_CPU1_SB_DQS_DP<4>   
                                  240      GND                     
                                  241      M_H_CPU1_SB_CB<2>       
                                  242      GND                     
                                  243      M_H_CPU1_SB_CB<3>       
                                  244      GND                     
                                  245      M_H_CPU1_SB_DQ<2>       
                                  246      GND                     
                                  247      M_H_CPU1_SB_DQ<3>       
                                  248      GND                     
                                  249      M_H_CPU1_SB_DQS_DN<5>   
                                  250      M_H_CPU1_SB_DQS_DP<5>   
                                  251      GND                     
                                  252      M_H_CPU1_SB_DQ<6>       
                                  253      GND                     
                                  254      M_H_CPU1_SB_DQ<7>       
                                  255      GND                     
                                  256      M_H_CPU1_SB_DQ<10>      
                                  257      GND                     
                                  258      M_H_CPU1_SB_DQ<11>      
                                  259      GND                     
                                  260      M_H_CPU1_SB_DQS_DN<6>   
                                  261      M_H_CPU1_SB_DQS_DP<6>   
                                  262      GND                     
                                  263      M_H_CPU1_SB_DQ<14>      
                                  264      GND                     
                                  265      M_H_CPU1_SB_DQ<15>      
                                  266      GND                     
                                  267      M_H_CPU1_SB_DQ<18>      
                                  268      GND                     
                                  269      M_H_CPU1_SB_DQ<19>      
                                  270      GND                     
                                  271      M_H_CPU1_SB_DQS_DN<7>   
                                  272      M_H_CPU1_SB_DQS_DP<7>   
                                  273      GND                     
                                  274      M_H_CPU1_SB_DQ<22>      
                                  275      GND                     
                                  276      M_H_CPU1_SB_DQ<23>      
                                  277      GND                     
                                  278      M_H_CPU1_SB_DQ<26>      
                                  279      GND                     
                                  280      M_H_CPU1_SB_DQ<27>      
                                  281      GND                     
                                  282      M_H_CPU1_SB_DQS_DN<8>   
                                  283      M_H_CPU1_SB_DQS_DP<8>   
                                  284      GND                     
                                  285      M_H_CPU1_SB_DQ<30>      
                                  286      GND                     
                                  287      M_H_CPU1_SB_DQ<31>      
                                  288      GND                     
                                  G1       GND                     
                                  G2       GND                     
                                  G3       GND                     
J33              SCONN84_123318136-SCONN84_1-23A A1       GND                     
                                  A2       GND                     
                                  A3       GND                     
                                  A4       GND                     
                                  A5       GND                     
                                  A6       GND                     
                                  A7       SMB_EDSFF2A_3V3AUX_SCL_R
                                  A8       SMB_EDSFF2A_3V3AUX_SDA_R
                                  A9       RST_SMB_EDSFF2A_N       
                                  A11      PU_EDSFF2A_PERST1_CLKREQ_N
                                  A12      PD_PCIE_EDSFF2A_PRSNT_0_N
                                  A13      GND                     
                                  A16      GND                     
                                  A17      P5E_CPU0_PE4_RX_DN<7>   
                                  A18      P5E_CPU0_PE4_RX_DP<7>   
                                  A19      GND                     
                                  A20      P5E_CPU0_PE4_RX_DN<6>   
                                  A21      P5E_CPU0_PE4_RX_DP<6>   
                                  A22      GND                     
                                  A23      P5E_CPU0_PE4_RX_DP<5>   
                                  A24      P5E_CPU0_PE4_RX_DN<5>   
                                  A25      GND                     
                                  A26      P5E_CPU0_PE4_RX_DN<4>   
                                  A27      P5E_CPU0_PE4_RX_DP<4>   
                                  A28      GND                     
                                  A29      GND                     
                                  A30      P5E_CPU0_PE4_RX_DN<3>   
                                  A31      P5E_CPU0_PE4_RX_DP<3>   
                                  A32      GND                     
                                  A33      P5E_CPU0_PE4_RX_DN<2>   
                                  A34      P5E_CPU0_PE4_RX_DP<2>   
                                  A35      GND                     
                                  A36      P5E_CPU0_PE4_RX_DP<1>   
                                  A37      P5E_CPU0_PE4_RX_DN<1>   
                                  A38      GND                     
                                  A39      P5E_CPU0_PE4_RX_DN<0>   
                                  A40      P5E_CPU0_PE4_RX_DP<0>   
                                  A41      GND                     
                                  A42      P3V3                    
                                  B1       P12V_REAR_CPU           
                                  B2       P12V_REAR_CPU           
                                  B3       P12V_REAR_CPU           
                                  B4       P12V_REAR_CPU           
                                  B5       P12V_REAR_CPU           
                                  B6       P12V_REAR_CPU           
                                  B7       FM_EDSFF2A_TYPE_ID      
                                  B8       FM_EDSFF2A_PWRBRK_N     
                                  B10      RST_PCIE_EDSFF2A_PERST_N
                                  B11      P3V3_AUX                
                                  B12      PD_EDSFF2A_PWRDIS       
                                  B13      GND                     
                                  B14      CLK_100M_EDSFF2A_DN     
                                  B15      CLK_100M_EDSFF2A_DP     
                                  B16      GND                     
                                  B17      P5E_CPU0_PE4_TX_C_DP<7> 
                                  B18      P5E_CPU0_PE4_TX_C_DN<7> 
                                  B19      GND                     
                                  B20      P5E_CPU0_PE4_TX_C_DP<6> 
                                  B21      P5E_CPU0_PE4_TX_C_DN<6> 
                                  B22      GND                     
                                  B23      P5E_CPU0_PE4_TX_C_DP<5> 
                                  B24      P5E_CPU0_PE4_TX_C_DN<5> 
                                  B25      GND                     
                                  B26      P5E_CPU0_PE4_TX_C_DP<4> 
                                  B27      P5E_CPU0_PE4_TX_C_DN<4> 
                                  B28      GND                     
                                  B29      GND                     
                                  B30      P5E_CPU0_PE4_TX_C_DP<3> 
                                  B31      P5E_CPU0_PE4_TX_C_DN<3> 
                                  B32      GND                     
                                  B33      P5E_CPU0_PE4_TX_C_DP<2> 
                                  B34      P5E_CPU0_PE4_TX_C_DN<2> 
                                  B35      GND                     
                                  B36      P5E_CPU0_PE4_TX_C_DP<1> 
                                  B37      P5E_CPU0_PE4_TX_C_DN<1> 
                                  B38      GND                     
                                  B39      P5E_CPU0_PE4_TX_C_DP<0> 
                                  B40      P5E_CPU0_PE4_TX_C_DN<0> 
                                  B41      GND                     
                                  B42      FM_PCIE_EDSFF2A_PRSNT_1_N
                                  G1       GND                     
                                  G2       GND                     
                                  G3       GND                     
                                  G4       GND                     
                                  G5       GND                     
J34              SCONN84_123318136-SCONN84_1-23A A1       GND                     
                                  A2       GND                     
                                  A3       GND                     
                                  A4       GND                     
                                  A5       GND                     
                                  A6       GND                     
                                  A7       SMB_EDSFF2B_3V3AUX_SCL_R
                                  A8       SMB_EDSFF2B_3V3AUX_SDA_R
                                  A9       RST_SMB_EDSFF2B_N       
                                  A11      PU_EDSFF2B_PERST1_CLKREQ_N
                                  A12      PD_PCIE_EDSFF2B_PRSNT_0_N
                                  A13      GND                     
                                  A16      GND                     
                                  A17      P5E_CPU0_PE4_RX_DN<15>  
                                  A18      P5E_CPU0_PE4_RX_DP<15>  
                                  A19      GND                     
                                  A20      P5E_CPU0_PE4_RX_DN<14>  
                                  A21      P5E_CPU0_PE4_RX_DP<14>  
                                  A22      GND                     
                                  A23      P5E_CPU0_PE4_RX_DN<13>  
                                  A24      P5E_CPU0_PE4_RX_DP<13>  
                                  A25      GND                     
                                  A26      P5E_CPU0_PE4_RX_DN<12>  
                                  A27      P5E_CPU0_PE4_RX_DP<12>  
                                  A28      GND                     
                                  A29      GND                     
                                  A30      P5E_CPU0_PE4_RX_DN<11>  
                                  A31      P5E_CPU0_PE4_RX_DP<11>  
                                  A32      GND                     
                                  A33      P5E_CPU0_PE4_RX_DN<10>  
                                  A34      P5E_CPU0_PE4_RX_DP<10>  
                                  A35      GND                     
                                  A36      P5E_CPU0_PE4_RX_DN<9>   
                                  A37      P5E_CPU0_PE4_RX_DP<9>   
                                  A38      GND                     
                                  A39      P5E_CPU0_PE4_RX_DN<8>   
                                  A40      P5E_CPU0_PE4_RX_DP<8>   
                                  A41      GND                     
                                  A42      P3V3                    
                                  B1       P12V_REAR_CPU           
                                  B2       P12V_REAR_CPU           
                                  B3       P12V_REAR_CPU           
                                  B4       P12V_REAR_CPU           
                                  B5       P12V_REAR_CPU           
                                  B6       P12V_REAR_CPU           
                                  B7       FM_EDSFF2B_TYPE_ID      
                                  B8       FM_EDSFF2B_PWRBRK_N     
                                  B10      RST_PCIE_EDSFF2B_PERST_N
                                  B11      P3V3_AUX                
                                  B12      PD_EDSFF2B_PWRDIS       
                                  B13      GND                     
                                  B14      CLK_100M_EDSFF2B_DN     
                                  B15      CLK_100M_EDSFF2B_DP     
                                  B16      GND                     
                                  B17      P5E_CPU0_PE4_TX_C_DP<15>
                                  B18      P5E_CPU0_PE4_TX_C_DN<15>
                                  B19      GND                     
                                  B20      P5E_CPU0_PE4_TX_C_DP<14>
                                  B21      P5E_CPU0_PE4_TX_C_DN<14>
                                  B22      GND                     
                                  B23      P5E_CPU0_PE4_TX_C_DP<13>
                                  B24      P5E_CPU0_PE4_TX_C_DN<13>
                                  B25      GND                     
                                  B26      P5E_CPU0_PE4_TX_C_DP<12>
                                  B27      P5E_CPU0_PE4_TX_C_DN<12>
                                  B28      GND                     
                                  B29      GND                     
                                  B30      P5E_CPU0_PE4_TX_C_DP<11>
                                  B31      P5E_CPU0_PE4_TX_C_DN<11>
                                  B32      GND                     
                                  B33      P5E_CPU0_PE4_TX_C_DP<10>
                                  B34      P5E_CPU0_PE4_TX_C_DN<10>
                                  B35      GND                     
                                  B36      P5E_CPU0_PE4_TX_C_DP<9> 
                                  B37      P5E_CPU0_PE4_TX_C_DN<9> 
                                  B38      GND                     
                                  B39      P5E_CPU0_PE4_TX_C_DP<8> 
                                  B40      P5E_CPU0_PE4_TX_C_DN<8> 
                                  B41      GND                     
                                  B42      FM_PCIE_EDSFF2B_PRSNT_1_N
                                  G1       GND                     
                                  G2       GND                     
                                  G3       GND                     
                                  G4       GND                     
                                  G5       GND                     
J35              SCONN140_G64V3431BHR-SCONN140_B A1       EDSFF3_PRSNT_0_N        
                                  A2       GND                     
                                  A3       P3V3                    
                                  A4       P3V3                    
                                  A5       GND                     
                                  A6       GND                     
                                  A7       GND                     
                                  A8       GND                     
                                  A9       RST_PCIE_EDSFF3_PERST_N 
                                  A10      GND                     
                                  A11      SMB_EDSFF3_3V3AUX_SCL_R 
                                  A12      SMB_EDSFF3_3V3AUX_SDA_R 
                                  A13      GND                     
                                  A14      EDSFF3_USB2_5_DN        
                                  A15      EDSFF3_USB2_5_DP        
                                  A16      GND                     
                                  A17      FM_EDSFF3_TYPE_ID       
                                  A19      GND                     
                                  A20      P5E_CPU1_PE3_RX_DP<0>   
                                  A21      P5E_CPU1_PE3_RX_DN<0>   
                                  A22      GND                     
                                  A23      P5E_CPU1_PE3_RX_DP<1>   
                                  A24      P5E_CPU1_PE3_RX_DN<1>   
                                  A25      GND                     
                                  A26      P5E_CPU1_PE3_RX_DN<2>   
                                  A27      P5E_CPU1_PE3_RX_DP<2>   
                                  A28      GND                     
                                  A29      GND                     
                                  A30      P5E_CPU1_PE3_RX_DP<3>   
                                  A31      P5E_CPU1_PE3_RX_DN<3>   
                                  A32      GND                     
                                  A33      P5E_CPU1_PE3_RX_DP<4>   
                                  A34      P5E_CPU1_PE3_RX_DN<4>   
                                  A35      GND                     
                                  A36      P5E_CPU1_PE3_RX_DN<5>   
                                  A37      P5E_CPU1_PE3_RX_DP<5>   
                                  A38      GND                     
                                  A39      P5E_CPU1_PE3_RX_DP<6>   
                                  A40      P5E_CPU1_PE3_RX_DN<6>   
                                  A41      GND                     
                                  A42      IRQ_LVC3_WAKE_EDSFF3_N  
                                  A43      GND                     
                                  A44      P5E_CPU1_PE3_RX_DN<7>   
                                  A45      P5E_CPU1_PE3_RX_DP<7>   
                                  A46      GND                     
                                  A47      P5E_CPU1_PE3_RX_DN<8>   
                                  A48      P5E_CPU1_PE3_RX_DP<8>   
                                  A49      GND                     
                                  A50      P5E_CPU1_PE3_RX_DP<9>   
                                  A51      P5E_CPU1_PE3_RX_DN<9>   
                                  A52      GND                     
                                  A53      P5E_CPU1_PE3_RX_DN<10>  
                                  A54      P5E_CPU1_PE3_RX_DP<10>  
                                  A55      GND                     
                                  A56      P5E_CPU1_PE3_RX_DP<11>  
                                  A57      P5E_CPU1_PE3_RX_DN<11>  
                                  A58      GND                     
                                  A59      P5E_CPU1_PE3_RX_DP<12>  
                                  A60      P5E_CPU1_PE3_RX_DN<12>  
                                  A61      GND                     
                                  A62      P5E_CPU1_PE3_RX_DN<13>  
                                  A63      P5E_CPU1_PE3_RX_DP<13>  
                                  A64      GND                     
                                  A65      P5E_CPU1_PE3_RX_DP<14>  
                                  A66      P5E_CPU1_PE3_RX_DN<14>  
                                  A67      GND                     
                                  A68      P5E_CPU1_PE3_RX_DN<15>  
                                  A69      P5E_CPU1_PE3_RX_DP<15>  
                                  A70      GND                     
                                  B1       P12V_REAR_CPU           
                                  B2       P12V_REAR_CPU           
                                  B3       P12V_REAR_CPU           
                                  B4       P12V_REAR_CPU           
                                  B5       P12V_REAR_CPU           
                                  B6       GND                     
                                  B7       GND                     
                                  B8       P12V_REAR_CPU           
                                  B9       P12V_REAR_CPU           
                                  B10      P12V_REAR_CPU           
                                  B11      P12V_REAR_CPU           
                                  B12      P12V_REAR_CPU           
                                  B13      GND                     
                                  B14      FM_EDSFF3_PWRBRK_N      
                                  B15      P3V3_AUX                
                                  B16      GND                     
                                  B17      CLK_100M_EDSFF3_DN      
                                  B18      CLK_100M_EDSFF3_DP      
                                  B19      GND                     
                                  B20      P5E_CPU1_PE3_TX_C_DN<0> 
                                  B21      P5E_CPU1_PE3_TX_C_DP<0> 
                                  B22      GND                     
                                  B23      P5E_CPU1_PE3_TX_C_DP<1> 
                                  B24      P5E_CPU1_PE3_TX_C_DN<1> 
                                  B25      GND                     
                                  B26      P5E_CPU1_PE3_TX_C_DP<2> 
                                  B27      P5E_CPU1_PE3_TX_C_DN<2> 
                                  B28      GND                     
                                  B29      GND                     
                                  B30      P5E_CPU1_PE3_TX_C_DP<3> 
                                  B31      P5E_CPU1_PE3_TX_C_DN<3> 
                                  B32      GND                     
                                  B33      P5E_CPU1_PE3_TX_C_DP<4> 
                                  B34      P5E_CPU1_PE3_TX_C_DN<4> 
                                  B35      GND                     
                                  B36      P5E_CPU1_PE3_TX_C_DP<5> 
                                  B37      P5E_CPU1_PE3_TX_C_DN<5> 
                                  B38      GND                     
                                  B39      P5E_CPU1_PE3_TX_C_DP<6> 
                                  B40      P5E_CPU1_PE3_TX_C_DN<6> 
                                  B41      GND                     
                                  B42      FM_PCIE_EDSFF3_PRSNT_1_N
                                  B43      GND                     
                                  B44      P5E_CPU1_PE3_TX_C_DP<7> 
                                  B45      P5E_CPU1_PE3_TX_C_DN<7> 
                                  B46      GND                     
                                  B47      P5E_CPU1_PE3_TX_C_DP<8> 
                                  B48      P5E_CPU1_PE3_TX_C_DN<8> 
                                  B49      GND                     
                                  B50      P5E_CPU1_PE3_TX_C_DP<9> 
                                  B51      P5E_CPU1_PE3_TX_C_DN<9> 
                                  B52      GND                     
                                  B53      P5E_CPU1_PE3_TX_C_DP<10>
                                  B54      P5E_CPU1_PE3_TX_C_DN<10>
                                  B55      GND                     
                                  B56      P5E_CPU1_PE3_TX_C_DP<11>
                                  B57      P5E_CPU1_PE3_TX_C_DN<11>
                                  B58      GND                     
                                  B59      P5E_CPU1_PE3_TX_C_DP<12>
                                  B60      P5E_CPU1_PE3_TX_C_DN<12>
                                  B61      GND                     
                                  B62      P5E_CPU1_PE3_TX_C_DP<13>
                                  B63      P5E_CPU1_PE3_TX_C_DN<13>
                                  B64      GND                     
                                  B65      P5E_CPU1_PE3_TX_C_DP<14>
                                  B66      P5E_CPU1_PE3_TX_C_DN<14>
                                  B67      GND                     
                                  B68      P5E_CPU1_PE3_TX_C_DP<15>
                                  B69      P5E_CPU1_PE3_TX_C_DN<15>
                                  B70      GND                     
                                  G1       GND                     
                                  G2       GND                     
                                  G3       GND                     
                                  G4       GND                     
                                  G5       GND                     
                                  G6       GND                     
                                  G7       GND                     
                                  G8       GND                     
J37              SCONN168_623403212-SCONN168_6-A A1       GND                     
                                  A2       GND                     
                                  A3       GND                     
                                  A4       GND                     
                                  A5       GND                     
                                  A6       GND                     
                                  A7       SMB_OCP_SFF_3V3AUX_R_SCL
                                  A8       SMB_OCP_SFF_3V3AUX_R_SDA
                                  A9       PU_RST_SMB_OCP_SFF_N    
                                  A10      OCP_SFF_PRSNTA_R_N      
                                  A11      RST_PERST1_OCP_SFF_N    
                                  A12      OCP_SFF_PRSNT2_R_N      
                                  A13      GND                     
                                  A14      CLK_100M_OCP_SFF_1_DN   
                                  A15      CLK_100M_OCP_SFF_1_DP   
                                  A16      GND                     
                                  A17      P5E_CPU0_PE1_RX_DP<0>   
                                  A18      P5E_CPU0_PE1_RX_DN<0>   
                                  A19      GND                     
                                  A20      P5E_CPU0_PE1_RX_DP<1>   
                                  A21      P5E_CPU0_PE1_RX_DN<1>   
                                  A22      GND                     
                                  A23      P5E_CPU0_PE1_RX_DP<2>   
                                  A24      P5E_CPU0_PE1_RX_DN<2>   
                                  A25      GND                     
                                  A26      P5E_CPU0_PE1_RX_DP<3>   
                                  A27      P5E_CPU0_PE1_RX_DN<3>   
                                  A28      GND                     
                                  A29      GND                     
                                  A30      P5E_CPU0_PE1_RX_DP<4>   
                                  A31      P5E_CPU0_PE1_RX_DN<4>   
                                  A32      GND                     
                                  A33      P5E_CPU0_PE1_RX_DP<5>   
                                  A34      P5E_CPU0_PE1_RX_DN<5>   
                                  A35      GND                     
                                  A36      P5E_CPU0_PE1_RX_DP<6>   
                                  A37      P5E_CPU0_PE1_RX_DN<6>   
                                  A38      GND                     
                                  A39      P5E_CPU0_PE1_RX_DP<7>   
                                  A40      P5E_CPU0_PE1_RX_DN<7>   
                                  A41      GND                     
                                  A42      OCP_SFF_PRSNT1_R_N      
                                  A43      GND                     
                                  A44      P5E_CPU0_PE1_RX_DP<8>   
                                  A45      P5E_CPU0_PE1_RX_DN<8>   
                                  A46      GND                     
                                  A47      P5E_CPU0_PE1_RX_DP<9>   
                                  A48      P5E_CPU0_PE1_RX_DN<9>   
                                  A49      GND                     
                                  A50      P5E_CPU0_PE1_RX_DP<10>  
                                  A51      P5E_CPU0_PE1_RX_DN<10>  
                                  A52      GND                     
                                  A53      P5E_CPU0_PE1_RX_DP<11>  
                                  A54      P5E_CPU0_PE1_RX_DN<11>  
                                  A55      GND                     
                                  A56      P5E_CPU0_PE1_RX_DP<12>  
                                  A57      P5E_CPU0_PE1_RX_DN<12>  
                                  A58      GND                     
                                  A59      P5E_CPU0_PE1_RX_DP<13>  
                                  A60      P5E_CPU0_PE1_RX_DN<13>  
                                  A61      GND                     
                                  A62      P5E_CPU0_PE1_RX_DP<14>  
                                  A63      P5E_CPU0_PE1_RX_DN<14>  
                                  A64      GND                     
                                  A65      P5E_CPU0_PE1_RX_DP<15>  
                                  A66      P5E_CPU0_PE1_RX_DN<15>  
                                  A67      GND                     
                                  A68      OCP_SFF_USB2_3_DN       
                                  A69      OCP_SFF_USB2_3_DP       
                                  A70      OCP_SFF_PWRBRK_N        
                                  B1       P12V_OCP_SFF            
                                  B2       P12V_OCP_SFF            
                                  B3       P12V_OCP_SFF            
                                  B4       P12V_OCP_SFF            
                                  B5       P12V_OCP_SFF            
                                  B6       P12V_OCP_SFF            
                                  B7       OCP_SFF_BIF0_R_N        
                                  B8       OCP_SFF_BIF1_R_N        
                                  B9       OCP_SFF_BIF2_R_N        
                                  B10      RST_PERST0_OCP_SFF_N    
                                  B11      P3V3_OCP_SFF            
                                  B12      OCP_SFF_AUX_PWR_EN_R    
                                  B13      GND                     
                                  B14      CLK_100M_OCP_SFF_0_DN   
                                  B15      CLK_100M_OCP_SFF_0_DP   
                                  B16      GND                     
                                  B17      P5E_CPU0_PE1_TX_C_DP<0> 
                                  B18      P5E_CPU0_PE1_TX_C_DN<0> 
                                  B19      GND                     
                                  B20      P5E_CPU0_PE1_TX_C_DP<1> 
                                  B21      P5E_CPU0_PE1_TX_C_DN<1> 
                                  B22      GND                     
                                  B23      P5E_CPU0_PE1_TX_C_DP<2> 
                                  B24      P5E_CPU0_PE1_TX_C_DN<2> 
                                  B25      GND                     
                                  B26      P5E_CPU0_PE1_TX_C_DP<3> 
                                  B27      P5E_CPU0_PE1_TX_C_DN<3> 
                                  B28      GND                     
                                  B29      GND                     
                                  B30      P5E_CPU0_PE1_TX_C_DP<4> 
                                  B31      P5E_CPU0_PE1_TX_C_DN<4> 
                                  B32      GND                     
                                  B33      P5E_CPU0_PE1_TX_C_DP<5> 
                                  B34      P5E_CPU0_PE1_TX_C_DN<5> 
                                  B35      GND                     
                                  B36      P5E_CPU0_PE1_TX_C_DP<6> 
                                  B37      P5E_CPU0_PE1_TX_C_DN<6> 
                                  B38      GND                     
                                  B39      P5E_CPU0_PE1_TX_C_DP<7> 
                                  B40      P5E_CPU0_PE1_TX_C_DN<7> 
                                  B41      GND                     
                                  B42      OCP_SFF_PRSNT0_R_N      
                                  B43      GND                     
                                  B44      P5E_CPU0_PE1_TX_C_DP<8> 
                                  B45      P5E_CPU0_PE1_TX_C_DN<8> 
                                  B46      GND                     
                                  B47      P5E_CPU0_PE1_TX_C_DP<9> 
                                  B48      P5E_CPU0_PE1_TX_C_DN<9> 
                                  B49      GND                     
                                  B50      P5E_CPU0_PE1_TX_C_DP<10>
                                  B51      P5E_CPU0_PE1_TX_C_DN<10>
                                  B52      GND                     
                                  B53      P5E_CPU0_PE1_TX_C_DP<11>
                                  B54      P5E_CPU0_PE1_TX_C_DN<11>
                                  B55      GND                     
                                  B56      P5E_CPU0_PE1_TX_C_DP<12>
                                  B57      P5E_CPU0_PE1_TX_C_DN<12>
                                  B58      GND                     
                                  B59      P5E_CPU0_PE1_TX_C_DP<13>
                                  B60      P5E_CPU0_PE1_TX_C_DN<13>
                                  B61      GND                     
                                  B62      P5E_CPU0_PE1_TX_C_DP<14>
                                  B63      P5E_CPU0_PE1_TX_C_DN<14>
                                  B64      GND                     
                                  B65      P5E_CPU0_PE1_TX_C_DP<15>
                                  B66      P5E_CPU0_PE1_TX_C_DN<15>
                                  B67      GND                     
                                  B70      OCP_SFF_PRSNT3_R_N      
                                  OCP_A1   RST_PERST2_OCP_SFF_N    
                                  OCP_A2   RST_PERST3_OCP_SFF_N    
                                  OCP_A3   IRQ_LVC3_OCP_SFF_WAKE_N 
                                  OCP_A4   OCP_SFF_RBT_ARB_IN      
                                  OCP_A5   OCP_SFF_RBT_ARB_OUT     
                                  OCP_A6   OCP_SFF_ID1             
                                  OCP_A7   NCSI_OCP_SFF_TX_EN      
                                  OCP_A8   NCSI_OCP_SFF_TXD1       
                                  OCP_A9   NCSI_OCP_SFF_TXD0       
                                  OCP_A10  GND                     
                                  OCP_A11  CLK_100M_OCP_SFF_3_DN   
                                  OCP_A12  CLK_100M_OCP_SFF_3_DP   
                                  OCP_A13  GND                     
                                  OCP_A14  CLK_50M_NCSI_OCP_SFF    
                                  OCP_B1   FM_OCP_SFF_PWR_GOOD     
                                  OCP_B2   OCP_SFF_MAIN_PWR_EN     
                                  OCP_B3   SGPIO_OCP_SFF_LD_N      
                                  OCP_B4   SGPIO_OCP_SFF_DATAIN_N  
                                  OCP_B5   SGPIO_OCP_SFF_DATAOUT_N 
                                  OCP_B6   SGPIO_OCP_SFF_CLK_N     
                                  OCP_B7   OCP_SFF_ID0             
                                  OCP_B8   NCSI_OCP_SFF_RXD1       
                                  OCP_B9   NCSI_OCP_SFF_RXD0       
                                  OCP_B10  GND                     
                                  OCP_B11  CLK_100M_OCP_SFF_2_DN   
                                  OCP_B12  CLK_100M_OCP_SFF_2_DP   
                                  OCP_B13  GND                     
                                  OCP_B14  NCSI_OCP_SFF_CRS_DV     
J41              SCONN168_623403212-SCONN168_6-A A1       SMB_PLD_3V3AUX_SCL      
                                  A2       SMB_PLD_3V3AUX_SDA      
                                  A3       SMB_HOST_3V3AUX_SCL     
                                  A4       SMB_HOST_3V3AUX_SDA     
                                  A5       SMB_VR_3V3AUX_SCL       
                                  A6       SMB_VR_3V3AUX_SDA       
                                  A7       SMB_SML1_PMBUS_3V3AUX_PCH_SCL
                                  A8       SMB_SML1_PMBUS_3V3AUX_PCH_SDA
                                  A9       SMB_SENSOR_3V3AUX_SCL   
                                  A10      SMB_SENSOR_3V3AUX_SDA   
                                  A11      GND                     
                                  A12      CLK_100M_BMC_P3E_DP     
                                  A13      CLK_100M_BMC_P3E_DN     
                                  A14      GND                     
                                  A15      P3E_PCH_BMC_TX_C_DP     
                                  A16      P3E_PCH_BMC_TX_C_DN     
                                  A17      GND                     
                                  A18      P3E_PCH_BMC_RX_DP       
                                  A19      P3E_PCH_BMC_RX_DN       
                                  A20      GND                     
                                  A21      SMB_CPU_PIROM_3V3AUX_SCL
                                  A22      SMB_CPU_PIROM_3V3AUX_SDA
                                  A23      SMB_PCIE0_3V3AUX_SCL    
                                  A24      SMB_PCIE0_3V3AUX_SDA    
                                  A25      SMB_SML0_3V3AUX_SCL     
                                  A26      SMB_SML0_3V3AUX_SDA     
                                  A27      SMB_PCIE1_3V3AUX_SCL    
                                  A28      SMB_PCIE1_3V3AUX_SDA    
                                  A29      SMB_FAN_3V3AUX_SCL      
                                  A30      SMB_FAN_3V3AUX_SDA      
                                  A31      SMB_PCIE2_3V3AUX_SCL    
                                  A32      SMB_PCIE2_3V3AUX_SDA    
                                  A33      GND                     
                                  A34      JTAG_BMC_TCK            
                                  A35      JTAG_BMC_TMS            
                                  A36      JTAG_BMC_TDI            
                                  A37      JTAG_BMC_TDO            
                                  A38      SMB_PCIE3_3V3AUX_SCL    
                                  A39      SMB_PCIE3_3V3AUX_SDA    
                                  A40      SMB_S3M_CPU_3V3AUX_SCL  
                                  A41      SMB_S3M_CPU_3V3AUX_SDA  
                                  A42      GND                     
                                  A43      GND                     
                                  A44      PWRGD_PS_PWROK_R        
                                  A46      RST_MB_STBY_N           
                                  A47      FM_BMC_PWRBTN_OUT_R_N   
                                  A48      PWRGD_SYS_PWROK         
                                  A49      JTAG_BMC_DBP_PREQ_N     
                                  A50      JTAG_DBP_BMC_PRDY_N     
                                  A51      RST_PLTRST_B_N          
                                  A52      GND                     
                                  A53      ROT_P1_RST_IND_N        
                                  A54      FM_BMC_CPU_FBRK_OUT_R_N 
                                  A55      GND                     
                                  A56      IRQ0_A57                
                                  A57      FM_SCM_PRSNT1_N         
                                  A58      GND                     
                                  A59      P3E_PCH_M2_RX_DP<4>     
                                  A60      P3E_PCH_M2_RX_DN<4>     
                                  A61      GND                     
                                  A64      GND                     
                                  A67      GND                     
                                  A70      GND                     
                                  B1       ESPI_HOST_LPC_BMC_CLK   
                                  B2       ESPI_HOST_LPC_BMC_LFRAME_N
                                  B3       IRQ_ESPI_LPC_SERIRQ_ALERT_R_N
                                  B4       ESPI_BMC_LPC_RST_N      
                                  B5       ESPI_LPC_LAD0_IO0       
                                  B6       ESPI_LPC_LAD0_IO1       
                                  B7       ESPI_LPC_LAD0_IO2       
                                  B8       ESPI_LPC_LAD0_IO3       
                                  B9       FM_LPC_ESPI_SEL         
                                  B10      GND                     
                                  B11      SPI_SYS_CLK             
                                  B12      SPI_SYS_CS0_N           
                                  B13      SPI_SYS_MOSI            
                                  B14      SPI_SYS_MISO            
                                  B15      SPI_SYS_WP_IO2          
                                  B16      SPI_SYS_HOLD_IO3        
                                  B17      GND                     
                                  B18      CLK_50M_RMII_BMC_OCP    
                                  B19      RMII_OCP_BMC_CRSDV      
                                  B20      RMII_BMC_OCP_TX_EN      
                                  B21      RMII_BMC_OCP_TXD_0      
                                  B22      RMII_BMC_OCP_TXD_1      
                                  B23      RMII_BMC_OCP_RX_ER      
                                  B24      RMII_OCP_BMC_RXD_0      
                                  B25      RMII_OCP_BMC_RXD_1      
                                  B26      GND                     
                                  B27      PECI_BMC                
                                  B28      PVCCIO_PECI_BMC         
                                  B29      SGPIO_DO_0              
                                  B30      SGPIO_CLK_0             
                                  B31      SGPIO_DI_0              
                                  B32      SGPIO_LD_0              
                                  B33      GND                     
                                  B34      SGPIO_DO_1              
                                  B35      SGPIO_CLK_1             
                                  B36      SGPIO_DI_1              
                                  B37      SGPIO_LD_1              
                                  B38      GND                     
                                  B39      RST_SGPIO_RESET_N       
                                  B40      IRQ_SGPIO_INTR_N        
                                  B41      P3V_BAT_R               
                                  B42      SPI_PCH_PFR_CS1_N       
                                  B49      GND                     
                                  B50      USB2_9_DP               
                                  B51      USB2_9_DN               
                                  B52      GND                     
                                  B53      USB2_8_DP               
                                  B54      USB2_8_DN               
                                  B55      GND                     
                                  B56      USB2_0_DP               
                                  B57      USB2_0_DN               
                                  B58      GND                     
                                  B59      P3E_PCH_M2_TX_C_DP<4>   
                                  B60      P3E_PCH_M2_TX_C_DN<4>   
                                  B61      GND                     
                                  B64      GND                     
                                  B67      GND                     
                                  B70      GND                     
                                  OCP_A1   P12V_SCM                
                                  OCP_A2   P12V_SCM                
                                  OCP_A3   GND                     
                                  OCP_A4   GND                     
                                  OCP_A5   I3C_SPD_DDRABCD_CPU0_BMC_R_SCL
                                  OCP_A6   I3C_SPD_DDRABCD_CPU0_BMC_R_SDA
                                  OCP_A7   I3C_SPD_DDREFGH_CPU0_BMC_R_SCL
                                  OCP_A8   I3C_SPD_DDREFGH_CPU0_BMC_R_SDA
                                  OCP_A9   I3C_SPD_DDRABCD_CPU1_BMC_R_SCL
                                  OCP_A10  I3C_SPD_DDRABCD_CPU1_BMC_R_SDA
                                  OCP_A11  I3C_SPD_DDREFGH_CPU1_BMC_R_SCL
                                  OCP_A12  I3C_SPD_DDREFGH_CPU1_BMC_R_SDA
                                  OCP_A13  GND                     
                                  OCP_A14  VIRTUAL_RESEAT          
                                  OCP_B1   P12V_SCM                
                                  OCP_B2   P12V_SCM                
                                  OCP_B3   PRSNT0_N                
                                  OCP_B4   GND                     
                                  OCP_B7   GND                     
                                  OCP_B10  GND                     
                                  OCP_B12  SPI_TPM_CS_N            
J42              SCONN60_QSH03001LDAKTR-SCONN60A 1        P1V05_PCH_AUX           
                                  2        JTAG_DBP_TMS_R          
                                  3        JTAG_DBP_CPU_GTL_TCK_R  
                                  4        JTAG_DBP_TDO_R          
                                  5        JTAG_DBP_TDI_R          
                                  6        JTAG_RST_DBP_RST_CO_N   
                                  7        JTAG_DBP_PMODE          
                                  8        PD_TRST_P3              
                                  10       JTAG_DBP_PREQ_N_R       
                                  11       JTAG_DBP_PRDY_R1_N      
                                  12       P1V8_PCH_AUX            
                                  13       JTAG_TRC_PCH_PTI0_CLK   
                                  14       GND                     
                                  15       JTAG_DBP_PCH_DEBUG_CONSENT_N
                                  16       GND                     
                                  17       JTAG_DBP_PRESENT_R_N    
                                  19       JTAG_TRC_PCH_PTI<0>     
                                  21       JTAG_TRC_PCH_PTI<1>     
                                  23       JTAG_TRC_PCH_PTI<2>     
                                  25       JTAG_TRC_PCH_PTI<3>     
                                  27       JTAG_TRC_PCH_PTI<4>     
                                  29       JTAG_TRC_PCH_PTI<5>     
                                  31       JTAG_TRC_PCH_PTI<6>     
                                  33       JTAG_TRC_PCH_PTI<7>     
                                  35       JTAG_TRC_PCH_PTI<8>     
                                  36       JTAG_DBP_BOOT_HALT_N    
                                  37       JTAG_TRC_PCH_PTI<9>     
                                  38       FM_CPU_FBRK_DEBUG_N     
                                  39       JTAG_TRC_PCH_PTI<10>    
                                  40       JTAG_DBP_POWER_BTN_N    
                                  41       JTAG_TRC_PCH_PTI<11>    
                                  42       JTAG_RST_DBP_RSMRST_N   
                                  43       JTAG_TRC_PCH_PTI<12>    
                                  45       JTAG_TRC_PCH_PTI<13>    
                                  47       JTAG_TRC_PCH_PTI<14>    
                                  48       SMB_HOST_3V3AUX_SCL     
                                  49       JTAG_TRC_PCH_PTI<15>    
                                  50       SMB_HOST_3V3AUX_SDA     
                                  51       JTAG_DBP_TCK_R_TCK      
                                  52       P3V3_AUX                
                                  53       JTAG_DBP_CPU_HOOK9_MBP3_GTL_N
                                  55       JTAG_DBP_CPU_HOOK8_MBP2_GTL_N
                                  57       GND                     
                                  58       GND                     
                                  59       JTAG_TRC_PCH_PTI1_CLK   
                                  60       GND                     
                                  G1       GND                     
                                  G2       GND                     
                                  G3       GND                     
                                  G4       GND                     
J43              CONN10_G2100HT0038071-CONN10_GA 1        JTAG_BMC_PLD_TCK        
                                  2        GND                     
                                  3        JTAG_BMC_PLD_TDO        
                                  4        P3V3_AUX                
                                  5        JTAG_BMC_PLD_TMS        
                                  8        JTAG_PLD_JTAGEN_R       
                                  9        JTAG_BMC_PLD_TDI        
                                  10       GND                     
J44              CONN24_52SH90245BRD-CONN24_52SA 1        P3V3_AUX                
                                  2        FAN_PDB_PRSNT_N         
                                  3        P3V3_AUX                
                                  4        GND                     
                                  5        GND                     
                                  6        SMB_PMBUS_PSU1_SCL_R2   
                                  8        GND                     
                                  9        FM_OV_ADR_TRIGGER_N     
                                  10       SMB_PMBUS_PSU1_SDA_R2   
                                  11       FM_UV_ADR_TRIGGER_N     
                                  12       GND                     
                                  13       IRQ_P12V_HSC_FAULT_N    
                                  14       SMB_FAN_3V3AUX_SCL_R1   
                                  15       IRQ_SML1_PMBUS_ALERT_R_N
                                  16       GND                     
                                  17       PWRGD_HSC_P12V_PWROK    
                                  18       SMB_FAN_3V3AUX_SDA_R1   
                                  19       PSU1_THROTTLE_R         
                                  20       GND                     
                                  23       PD_MB_PRSNT             
J48              CONN9_2UB3903013101F-CONN9_2UBA 1        P5V_USB_INT             
                                  2        USB2_1_F_DN             
                                  3        USB2_1_F_DP             
                                  4        GND                     
                                  5        USB3_9_RX_DN_FB         
                                  6        USB3_9_RX_DP_FB         
                                  7        GND                     
                                  8        USB3_9_TX_DN_FB         
                                  9        USB3_9_TX_DP_FB         
                                  G1       GND                     
                                  G2       GND                     
                                  G3       GND                     
                                  G4       GND                     
J49              CONN10_10142708102011LF-CONN10A 1        GND                     
                                  2        GND                     
                                  3        GND                     
                                  4        GND                     
                                  5        GND                     
                                  6        P12V_AUX                
                                  7        P12V_AUX                
                                  8        P12V_AUX                
                                  9        P12V_AUX                
                                  10       P12V_AUX                
J50              CONN10_10142708102011LF-CONN10A 1        GND                     
                                  2        GND                     
                                  3        GND                     
                                  4        GND                     
                                  5        GND                     
                                  6        P12V_AUX                
                                  7        P12V_AUX                
                                  8        P12V_AUX                
                                  9        P12V_AUX                
                                  10       P12V_AUX                
J54              CONN7_ABASAT054KA1-CONN7_ABA-SA 1        GND                     
                                  2        SATA_P11_TX_C_DP        
                                  3        SATA_P11_TX_C_DN        
                                  4        GND                     
                                  5        SATA_P11_RX_C_DN        
                                  6        SATA_P11_RX_C_DP        
                                  7        GND                     
                                  G1       GND                     
                                  G2       GND                     
J55              SCONN140_G64V3431BHR-SCONN140_A A1       P12V_FRONT_CPU1         
                                  A2       P12V_FRONT_CPU1         
                                  A3       P12V_FRONT_CPU1         
                                  A4       P12V_FRONT_CPU1         
                                  A5       P12V_FRONT_CPU1         
                                  A6       P12V_FRONT_CPU1         
                                  A8       FM_RISER1_PWRBRK_N      
                                  A9       RISER1_TYPE_ID          
                                  A11      P3V3_AUX                
                                  A13      GND                     
                                  A14      CLK_100M_PE_0_DN        
                                  A15      CLK_100M_PE_0_DP        
                                  A16      GND                     
                                  A17      P5E_CPU0_PE2_TX_C_DP<15>
                                  A18      P5E_CPU0_PE2_TX_C_DN<15>
                                  A19      GND                     
                                  A20      P5E_CPU0_PE2_TX_C_DP<14>
                                  A21      P5E_CPU0_PE2_TX_C_DN<14>
                                  A22      GND                     
                                  A23      P5E_CPU0_PE2_TX_C_DP<13>
                                  A24      P5E_CPU0_PE2_TX_C_DN<13>
                                  A25      GND                     
                                  A26      P5E_CPU0_PE2_TX_C_DP<12>
                                  A27      P5E_CPU0_PE2_TX_C_DN<12>
                                  A28      GND                     
                                  A29      GND                     
                                  A30      P5E_CPU0_PE2_TX_C_DP<11>
                                  A31      P5E_CPU0_PE2_TX_C_DN<11>
                                  A32      GND                     
                                  A33      P5E_CPU0_PE2_TX_C_DP<10>
                                  A34      P5E_CPU0_PE2_TX_C_DN<10>
                                  A35      GND                     
                                  A36      P5E_CPU0_PE2_TX_C_DP<9> 
                                  A37      P5E_CPU0_PE2_TX_C_DN<9> 
                                  A38      GND                     
                                  A39      P5E_CPU0_PE2_TX_C_DP<8> 
                                  A40      P5E_CPU0_PE2_TX_C_DN<8> 
                                  A41      GND                     
                                  A42      GND                     
                                  A43      GND                     
                                  A44      P5E_CPU0_PE2_TX_C_DP<7> 
                                  A45      P5E_CPU0_PE2_TX_C_DN<7> 
                                  A46      GND                     
                                  A47      P5E_CPU0_PE2_TX_C_DP<6> 
                                  A48      P5E_CPU0_PE2_TX_C_DN<6> 
                                  A49      GND                     
                                  A50      P5E_CPU0_PE2_TX_C_DP<5> 
                                  A51      P5E_CPU0_PE2_TX_C_DN<5> 
                                  A52      GND                     
                                  A53      P5E_CPU0_PE2_TX_C_DP<4> 
                                  A54      P5E_CPU0_PE2_TX_C_DN<4> 
                                  A55      GND                     
                                  A56      P5E_CPU0_PE2_TX_C_DP<3> 
                                  A57      P5E_CPU0_PE2_TX_C_DN<3> 
                                  A58      GND                     
                                  A59      P5E_CPU0_PE2_TX_C_DP<2> 
                                  A60      P5E_CPU0_PE2_TX_C_DN<2> 
                                  A61      GND                     
                                  A62      P5E_CPU0_PE2_TX_C_DP<1> 
                                  A63      P5E_CPU0_PE2_TX_C_DN<1> 
                                  A64      GND                     
                                  A65      P5E_CPU0_PE2_TX_C_DP<0> 
                                  A66      P5E_CPU0_PE2_TX_C_DN<0> 
                                  A67      GND                     
                                  A68      P3V3                    
                                  A69      P3V3                    
                                  A70      PCIE_RISER1_PRSNT2_N    
                                  B1       PD_RISER1_PRSNT1        
                                  B2       JTAG_RISER1_TCK         
                                  B3       JTAG_RISER1_TDI         
                                  B4       JTAG_RISER1_TDO         
                                  B5       GND                     
                                  B6       GND                     
                                  B7       SMB_RISER1_3V3AUX_SCL   
                                  B8       SMB_RISER1_3V3AUX_SDA   
                                  B11      RISER1_CLK0_EN_N        
                                  B12      RISER1_CLK1_EN_N        
                                  B13      GND                     
                                  B14      CLK_100M_PE_1_DN        
                                  B15      CLK_100M_PE_1_DP        
                                  B16      GND                     
                                  B17      P5E_CPU0_PE2_RX_DP<15>  
                                  B18      P5E_CPU0_PE2_RX_DN<15>  
                                  B19      GND                     
                                  B20      P5E_CPU0_PE2_RX_DP<14>  
                                  B21      P5E_CPU0_PE2_RX_DN<14>  
                                  B22      GND                     
                                  B23      P5E_CPU0_PE2_RX_DP<13>  
                                  B24      P5E_CPU0_PE2_RX_DN<13>  
                                  B25      GND                     
                                  B26      P5E_CPU0_PE2_RX_DP<12>  
                                  B27      P5E_CPU0_PE2_RX_DN<12>  
                                  B28      GND                     
                                  B29      GND                     
                                  B30      P5E_CPU0_PE2_RX_DP<11>  
                                  B31      P5E_CPU0_PE2_RX_DN<11>  
                                  B32      GND                     
                                  B33      P5E_CPU0_PE2_RX_DP<10>  
                                  B34      P5E_CPU0_PE2_RX_DN<10>  
                                  B35      GND                     
                                  B36      P5E_CPU0_PE2_RX_DP<9>   
                                  B37      P5E_CPU0_PE2_RX_DN<9>   
                                  B38      GND                     
                                  B39      P5E_CPU0_PE2_RX_DP<8>   
                                  B40      P5E_CPU0_PE2_RX_DN<8>   
                                  B41      GND                     
                                  B42      JTAG_RISER1_TMS         
                                  B43      GND                     
                                  B44      P5E_CPU0_PE2_RX_DP<7>   
                                  B45      P5E_CPU0_PE2_RX_DN<7>   
                                  B46      GND                     
                                  B47      P5E_CPU0_PE2_RX_DP<6>   
                                  B48      P5E_CPU0_PE2_RX_DN<6>   
                                  B49      GND                     
                                  B50      P5E_CPU0_PE2_RX_DP<5>   
                                  B51      P5E_CPU0_PE2_RX_DN<5>   
                                  B52      GND                     
                                  B53      P5E_CPU0_PE2_RX_DP<4>   
                                  B54      P5E_CPU0_PE2_RX_DN<4>   
                                  B55      GND                     
                                  B56      P5E_CPU0_PE2_RX_DP<3>   
                                  B57      P5E_CPU0_PE2_RX_DN<3>   
                                  B58      GND                     
                                  B59      P5E_CPU0_PE2_RX_DP<2>   
                                  B60      P5E_CPU0_PE2_RX_DN<2>   
                                  B61      GND                     
                                  B62      P5E_CPU0_PE2_RX_DP<1>   
                                  B63      P5E_CPU0_PE2_RX_DN<1>   
                                  B64      GND                     
                                  B65      P5E_CPU0_PE2_RX_DP<0>   
                                  B66      P5E_CPU0_PE2_RX_DN<0>   
                                  B67      GND                     
                                  B68      JTAG_RISER1_TRST_N      
                                  B69      P3V3                    
                                  B70      IRQ_LVC3_WAKE_R1_N      
                                  G1       GND                     
                                  G2       GND                     
                                  G3       GND                     
                                  G4       GND                     
                                  G5       GND                     
                                  G6       GND                     
                                  G7       GND                     
                                  G8       GND                     
J57              SCONN140_G64V3431BHR-SCONN140_A A1       P12V_FRONT_CPU1         
                                  A2       P12V_FRONT_CPU1         
                                  A3       P12V_FRONT_CPU1         
                                  A4       P12V_FRONT_CPU1         
                                  A5       P12V_FRONT_CPU1         
                                  A6       P12V_FRONT_CPU1         
                                  A8       FM_RISER3_PWRBRK_N      
                                  A9       RISER3_TYPE_ID          
                                  A10      RST_PCIE_RISER3_N       
                                  A11      P3V3_AUX                
                                  A13      GND                     
                                  A14      CLK_100M_PE_4_DN        
                                  A15      CLK_100M_PE_4_DP        
                                  A16      GND                     
                                  A17      P5E_CPU1_PE1_TX_C_DP<15>
                                  A18      P5E_CPU1_PE1_TX_C_DN<15>
                                  A19      GND                     
                                  A20      P5E_CPU1_PE1_TX_C_DP<14>
                                  A21      P5E_CPU1_PE1_TX_C_DN<14>
                                  A22      GND                     
                                  A23      P5E_CPU1_PE1_TX_C_DP<13>
                                  A24      P5E_CPU1_PE1_TX_C_DN<13>
                                  A25      GND                     
                                  A26      P5E_CPU1_PE1_TX_C_DP<12>
                                  A27      P5E_CPU1_PE1_TX_C_DN<12>
                                  A28      GND                     
                                  A29      GND                     
                                  A30      P5E_CPU1_PE1_TX_C_DP<11>
                                  A31      P5E_CPU1_PE1_TX_C_DN<11>
                                  A32      GND                     
                                  A33      P5E_CPU1_PE1_TX_C_DP<10>
                                  A34      P5E_CPU1_PE1_TX_C_DN<10>
                                  A35      GND                     
                                  A36      P5E_CPU1_PE1_TX_C_DP<9> 
                                  A37      P5E_CPU1_PE1_TX_C_DN<9> 
                                  A38      GND                     
                                  A39      P5E_CPU1_PE1_TX_C_DP<8> 
                                  A40      P5E_CPU1_PE1_TX_C_DN<8> 
                                  A41      GND                     
                                  A42      GND                     
                                  A43      GND                     
                                  A44      P5E_CPU1_PE1_TX_C_DP<7> 
                                  A45      P5E_CPU1_PE1_TX_C_DN<7> 
                                  A46      GND                     
                                  A47      P5E_CPU1_PE1_TX_C_DP<6> 
                                  A48      P5E_CPU1_PE1_TX_C_DN<6> 
                                  A49      GND                     
                                  A50      P5E_CPU1_PE1_TX_C_DP<5> 
                                  A51      P5E_CPU1_PE1_TX_C_DN<5> 
                                  A52      GND                     
                                  A53      P5E_CPU1_PE1_TX_C_DP<4> 
                                  A54      P5E_CPU1_PE1_TX_C_DN<4> 
                                  A55      GND                     
                                  A56      P5E_CPU1_PE1_TX_C_DP<3> 
                                  A57      P5E_CPU1_PE1_TX_C_DN<3> 
                                  A58      GND                     
                                  A59      P5E_CPU1_PE1_TX_C_DP<2> 
                                  A60      P5E_CPU1_PE1_TX_C_DN<2> 
                                  A61      GND                     
                                  A62      P5E_CPU1_PE1_TX_C_DP<1> 
                                  A63      P5E_CPU1_PE1_TX_C_DN<1> 
                                  A64      GND                     
                                  A65      P5E_CPU1_PE1_TX_C_DP<0> 
                                  A66      P5E_CPU1_PE1_TX_C_DN<0> 
                                  A67      GND                     
                                  A68      P3V3                    
                                  A69      P3V3                    
                                  A70      PCIE_RISER3_PRSNT2_N    
                                  B1       PD_RISER3_PRSNT1        
                                  B2       JTAG_RISER3_TCK         
                                  B3       JTAG_RISER3_TDI         
                                  B4       JTAG_RISER3_TDO         
                                  B5       GND                     
                                  B6       GND                     
                                  B7       SMB_RISER3_3V3AUX_SCL   
                                  B8       SMB_RISER3_3V3AUX_SDA   
                                  B11      RISER3_CLK4_EN_N        
                                  B12      RISER3_CLK5_EN_N        
                                  B13      GND                     
                                  B14      CLK_100M_PE_5_DN        
                                  B15      CLK_100M_PE_5_DP        
                                  B16      GND                     
                                  B17      P5E_CPU1_PE1_RX_DP<15>  
                                  B18      P5E_CPU1_PE1_RX_DN<15>  
                                  B19      GND                     
                                  B20      P5E_CPU1_PE1_RX_DP<14>  
                                  B21      P5E_CPU1_PE1_RX_DN<14>  
                                  B22      GND                     
                                  B23      P5E_CPU1_PE1_RX_DP<13>  
                                  B24      P5E_CPU1_PE1_RX_DN<13>  
                                  B25      GND                     
                                  B26      P5E_CPU1_PE1_RX_DP<12>  
                                  B27      P5E_CPU1_PE1_RX_DN<12>  
                                  B28      GND                     
                                  B29      GND                     
                                  B30      P5E_CPU1_PE1_RX_DP<11>  
                                  B31      P5E_CPU1_PE1_RX_DN<11>  
                                  B32      GND                     
                                  B33      P5E_CPU1_PE1_RX_DP<10>  
                                  B34      P5E_CPU1_PE1_RX_DN<10>  
                                  B35      GND                     
                                  B36      P5E_CPU1_PE1_RX_DP<9>   
                                  B37      P5E_CPU1_PE1_RX_DN<9>   
                                  B38      GND                     
                                  B39      P5E_CPU1_PE1_RX_DP<8>   
                                  B40      P5E_CPU1_PE1_RX_DN<8>   
                                  B41      GND                     
                                  B42      JTAG_RISER3_TMS         
                                  B43      GND                     
                                  B44      P5E_CPU1_PE1_RX_DP<7>   
                                  B45      P5E_CPU1_PE1_RX_DN<7>   
                                  B46      GND                     
                                  B47      P5E_CPU1_PE1_RX_DP<6>   
                                  B48      P5E_CPU1_PE1_RX_DN<6>   
                                  B49      GND                     
                                  B50      P5E_CPU1_PE1_RX_DP<5>   
                                  B51      P5E_CPU1_PE1_RX_DN<5>   
                                  B52      GND                     
                                  B53      P5E_CPU1_PE1_RX_DP<4>   
                                  B54      P5E_CPU1_PE1_RX_DN<4>   
                                  B55      GND                     
                                  B56      P5E_CPU1_PE1_RX_DP<3>   
                                  B57      P5E_CPU1_PE1_RX_DN<3>   
                                  B58      GND                     
                                  B59      P5E_CPU1_PE1_RX_DP<2>   
                                  B60      P5E_CPU1_PE1_RX_DN<2>   
                                  B61      GND                     
                                  B62      P5E_CPU1_PE1_RX_DP<1>   
                                  B63      P5E_CPU1_PE1_RX_DN<1>   
                                  B64      GND                     
                                  B65      P5E_CPU1_PE1_RX_DP<0>   
                                  B66      P5E_CPU1_PE1_RX_DN<0>   
                                  B67      GND                     
                                  B68      JTAG_RISER3_TRST_N      
                                  B69      P3V3                    
                                  B70      IRQ_LVC3_WAKE_R3_N      
                                  G1       GND                     
                                  G2       GND                     
                                  G3       GND                     
                                  G4       GND                     
                                  G5       GND                     
                                  G6       GND                     
                                  G7       GND                     
                                  G8       GND                     
J59              SCONN75K_APCI0155P004A-SCONN75A 1        PCIE_M2_SSD0_PRSNT_N    
                                  2        P3V3                    
                                  3        GND                     
                                  4        P3V3                    
                                  5        P3E_PCH_M2_RX_DN<0>     
                                  7        P3E_PCH_M2_RX_DP<0>     
                                  9        GND                     
                                  10       PU_DAS_DSS_N            
                                  11       P3E_PCH_M2_TX_C_DP<0>   
                                  12       P3V3                    
                                  13       P3E_PCH_M2_TX_C_DN<0>   
                                  14       P3V3                    
                                  15       GND                     
                                  16       P3V3                    
                                  17       P3E_PCH_M2_RX_DN<1>     
                                  18       P3V3                    
                                  19       P3E_PCH_M2_RX_DP<1>     
                                  21       GND                     
                                  23       P3E_PCH_M2_TX_C_DP<1>   
                                  25       P3E_PCH_M2_TX_C_DN<1>   
                                  27       GND                     
                                  29       P3E_PCH_M2_RX_DN<2>     
                                  31       P3E_PCH_M2_RX_DP<2>     
                                  33       GND                     
                                  35       P3E_PCH_M2_TX_C_DP<2>   
                                  37       P3E_PCH_M2_TX_C_DN<2>   
                                  38       PD_M2_1_DEVSLP          
                                  39       GND                     
                                  40       SMB_M2_P0_1V8AUX_SCL    
                                  41       P3E_PCH_M2_RX_C_DP<3>   
                                  42       SMB_M2_P0_1V8AUX_SDA    
                                  43       P3E_PCH_M2_RX_C_DN<3>   
                                  45       GND                     
                                  47       P3E_PCH_M2_TX_C_DN<3>   
                                  49       P3E_PCH_M2_TX_C_DP<3>   
                                  50       RST_PCIE_PCH_DEV_0_N    
                                  51       GND                     
                                  52       M2_SSD0_CLKREQ_EN_N_BUF 
                                  53       CLK_100M_PE_M2_0_DN     
                                  55       CLK_100M_PE_M2_0_DP     
                                  57       GND                     
                                  69       FM_M2_SSD_1_PEDET       
                                  70       P3V3                    
                                  71       GND                     
                                  72       P3V3                    
                                  73       GND                     
                                  74       P3V3                    
                                  75       GND                     
                                  G1       GND                     
                                  G2       GND                     
J61              SCONN84_123318136-SCONN84_1-23A A1       GND                     
                                  A2       GND                     
                                  A3       GND                     
                                  A4       GND                     
                                  A5       GND                     
                                  A6       GND                     
                                  A7       P3V3                    
                                  A8       P3V3                    
                                  A9       P3V3                    
                                  A10      FM_JTAG_EDSFF4_SEL      
                                  A11      EDSFF4B_PERST1_CLKREQ_N 
                                  A12      PD_PCIE_EDSFF4B_PRSNT_0_N
                                  A13      GND                     
                                  A14      JTAG_EDSFF4_TCK         
                                  A15      JTAG_EDSFF4_TMS         
                                  A16      GND                     
                                  A17      P5E_CPU1_PE4_RX_DN<8>   
                                  A18      P5E_CPU1_PE4_RX_DP<8>   
                                  A19      GND                     
                                  A20      P5E_CPU1_PE4_RX_DP<9>   
                                  A21      P5E_CPU1_PE4_RX_DN<9>   
                                  A22      GND                     
                                  A23      P5E_CPU1_PE4_RX_DN<10>  
                                  A24      P5E_CPU1_PE4_RX_DP<10>  
                                  A25      GND                     
                                  A26      P5E_CPU1_PE4_RX_DP<11>  
                                  A27      P5E_CPU1_PE4_RX_DN<11>  
                                  A28      GND                     
                                  A29      GND                     
                                  A30      P5E_CPU1_PE4_RX_DP<12>  
                                  A31      P5E_CPU1_PE4_RX_DN<12>  
                                  A32      GND                     
                                  A33      P5E_CPU1_PE4_RX_DN<13>  
                                  A34      P5E_CPU1_PE4_RX_DP<13>  
                                  A35      GND                     
                                  A36      P5E_CPU1_PE4_RX_DP<14>  
                                  A37      P5E_CPU1_PE4_RX_DN<14>  
                                  A38      GND                     
                                  A39      P5E_CPU1_PE4_RX_DN<15>  
                                  A40      P5E_CPU1_PE4_RX_DP<15>  
                                  A41      GND                     
                                  A42      JTAG_EDSFF4_TRST_N      
                                  B1       P12V_REAR_CPU           
                                  B2       P12V_REAR_CPU           
                                  B3       P12V_REAR_CPU           
                                  B4       P12V_REAR_CPU           
                                  B5       P12V_REAR_CPU           
                                  B6       P12V_REAR_CPU           
                                  B7       FM_EDSFF4A_TYPE_ID      
                                  B8       JTAG_EDSFF4_TDO         
                                  B9       JTAG_EDSFF4_TDI         
                                  B10      RST_PCIE_EDSFF4B_PERST_N
                                  B11      P3V3_AUX                
                                  B12      PD_EDSFF4B_PWRDIS       
                                  B13      GND                     
                                  B14      CLK_100M_EDSFF4B_DN     
                                  B15      CLK_100M_EDSFF4B_DP     
                                  B16      GND                     
                                  B17      P5E_CPU1_PE4_TX_C_DP<8> 
                                  B18      P5E_CPU1_PE4_TX_C_DN<8> 
                                  B19      GND                     
                                  B20      P5E_CPU1_PE4_TX_C_DP<9> 
                                  B21      P5E_CPU1_PE4_TX_C_DN<9> 
                                  B22      GND                     
                                  B23      P5E_CPU1_PE4_TX_C_DP<10>
                                  B24      P5E_CPU1_PE4_TX_C_DN<10>
                                  B25      GND                     
                                  B26      P5E_CPU1_PE4_TX_C_DP<11>
                                  B27      P5E_CPU1_PE4_TX_C_DN<11>
                                  B28      GND                     
                                  B29      GND                     
                                  B30      P5E_CPU1_PE4_TX_C_DP<12>
                                  B31      P5E_CPU1_PE4_TX_C_DN<12>
                                  B32      GND                     
                                  B33      P5E_CPU1_PE4_TX_C_DP<13>
                                  B34      P5E_CPU1_PE4_TX_C_DN<13>
                                  B35      GND                     
                                  B36      P5E_CPU1_PE4_TX_C_DP<14>
                                  B37      P5E_CPU1_PE4_TX_C_DN<14>
                                  B38      GND                     
                                  B39      P5E_CPU1_PE4_TX_C_DP<15>
                                  B40      P5E_CPU1_PE4_TX_C_DN<15>
                                  B41      GND                     
                                  B42      FM_PCIE_EDSFF4B_PRSNT_1_N
                                  G1       GND                     
                                  G2       GND                     
                                  G3       GND                     
                                  G4       GND                     
                                  G5       GND                     
J62              SCONN84_123318136-SCONN84_1-23A A1       GND                     
                                  A2       GND                     
                                  A3       GND                     
                                  A4       GND                     
                                  A5       GND                     
                                  A6       GND                     
                                  A7       SMB_EDSFF1A_3V3AUX_SCL_R
                                  A8       SMB_EDSFF1A_3V3AUX_SDA_R
                                  A9       RST_SMB_EDSFF1A_N       
                                  A10      SMB_PEHPCPU0_EDSFF1A_LVC3_R_SCL
                                  A11      EDSFF1A_PERST1_CLKREQ_N 
                                  A12      PD_PCIE_EDSFF1A_PRSNT_0_N
                                  A13      GND                     
                                  A14      CLK_100M_EDSFF1A_1_DN   
                                  A15      CLK_100M_EDSFF1A_1_DP   
                                  A16      GND                     
                                  A17      P5E_CPU0_PE3_RX_DN<0>   
                                  A18      P5E_CPU0_PE3_RX_DP<0>   
                                  A19      GND                     
                                  A20      P5E_CPU0_PE3_RX_DN<1>   
                                  A21      P5E_CPU0_PE3_RX_DP<1>   
                                  A22      GND                     
                                  A23      P5E_CPU0_PE3_RX_DN<2>   
                                  A24      P5E_CPU0_PE3_RX_DP<2>   
                                  A25      GND                     
                                  A26      P5E_CPU0_PE3_RX_DN<3>   
                                  A27      P5E_CPU0_PE3_RX_DP<3>   
                                  A28      GND                     
                                  A29      GND                     
                                  A30      P5E_CPU0_PE3_RX_DN<4>   
                                  A31      P5E_CPU0_PE3_RX_DP<4>   
                                  A32      GND                     
                                  A33      P5E_CPU0_PE3_RX_DN<5>   
                                  A34      P5E_CPU0_PE3_RX_DP<5>   
                                  A35      GND                     
                                  A36      P5E_CPU0_PE3_RX_DN<6>   
                                  A37      P5E_CPU0_PE3_RX_DP<6>   
                                  A38      GND                     
                                  A39      P5E_CPU0_PE3_RX_DN<7>   
                                  A40      P5E_CPU0_PE3_RX_DP<7>   
                                  A41      GND                     
                                  B1       P12V_REAR_CPU           
                                  B2       P12V_REAR_CPU           
                                  B3       P12V_REAR_CPU           
                                  B4       P12V_REAR_CPU           
                                  B5       P12V_REAR_CPU           
                                  B6       P12V_REAR_CPU           
                                  B7       FM_EDSFF1A_TYPE_ID      
                                  B8       FM_EDSFF1A_PWRBRK_N     
                                  B9       SMB_PEHPCPU0_EDSFF1ALVC3_R_SDA
                                  B10      RST_PCIE_EDSFF1A_PERST_N
                                  B11      P3V3_AUX                
                                  B12      PD_EDSFF1A_PWRDIS       
                                  B13      GND                     
                                  B14      CLK_100M_EDSFF1A_DN     
                                  B15      CLK_100M_EDSFF1A_DP     
                                  B16      GND                     
                                  B17      P5E_CPU0_PE3_TX_C_DN<0> 
                                  B18      P5E_CPU0_PE3_TX_C_DP<0> 
                                  B19      GND                     
                                  B20      P5E_CPU0_PE3_TX_C_DN<1> 
                                  B21      P5E_CPU0_PE3_TX_C_DP<1> 
                                  B22      GND                     
                                  B23      P5E_CPU0_PE3_TX_C_DN<2> 
                                  B24      P5E_CPU0_PE3_TX_C_DP<2> 
                                  B25      GND                     
                                  B26      P5E_CPU0_PE3_TX_C_DN<3> 
                                  B27      P5E_CPU0_PE3_TX_C_DP<3> 
                                  B28      GND                     
                                  B29      GND                     
                                  B30      P5E_CPU0_PE3_TX_C_DN<4> 
                                  B31      P5E_CPU0_PE3_TX_C_DP<4> 
                                  B32      GND                     
                                  B33      P5E_CPU0_PE3_TX_C_DN<5> 
                                  B34      P5E_CPU0_PE3_TX_C_DP<5> 
                                  B35      GND                     
                                  B36      P5E_CPU0_PE3_TX_C_DN<6> 
                                  B37      P5E_CPU0_PE3_TX_C_DP<6> 
                                  B38      GND                     
                                  B39      P5E_CPU0_PE3_TX_C_DN<7> 
                                  B40      P5E_CPU0_PE3_TX_C_DP<7> 
                                  B41      GND                     
                                  B42      FM_PCIE_EDSFF1A_PRSNT_1_N
                                  G1       GND                     
                                  G2       GND                     
                                  G3       GND                     
                                  G4       GND                     
                                  G5       GND                     
J63              DELTA_L-DELTA-L,THLF,EMPTY,TP24 1        DELTA_L_85_5INCH_TOP_DP 
                                  2        DELTA_L_85_5INCH_TOP_DN 
                                  3        DELTA_R_GND             
J64              DELTA_L-DELTA-L,THLF,EMPTY,TP24 1        DELTA_L_85_5INCH_BOT_DP 
                                  2        DELTA_L_85_5INCH_BOT_DN 
                                  3        DELTA_R_GND             
J65              DELTA_L-DELTA-L,THLF,EMPTY,TP24 1        DELTA_L_85_5INCH_IN1_DP 
                                  2        DELTA_L_85_5INCH_IN1_DN 
                                  3        DELTA_L_GND             
J66              DELTA_L-DELTA-L,THLF,EMPTY,TP24 1        DELTA_L_85_5INCH_IN2_DP 
                                  2        DELTA_L_85_5INCH_IN2_DN 
                                  3        DELTA_L_GND             
J67              DELTA_L-DELTA-L,THLF,EMPTY,TP24 1        DELTA_L_85_5INCH_IN3_DP 
                                  2        DELTA_L_85_5INCH_IN3_DN 
                                  3        DELTA_L_GND             
J68              DELTA_L-DELTA-L,THLF,EMPTY,TP24 1        DELTA_L_85_5INCH_IN4_DP 
                                  2        DELTA_L_85_5INCH_IN4_DN 
                                  3        DELTA_R_GND             
J69              DELTA_L-DELTA-L,THLF,EMPTY,TP24 1        DELTA_L_85_5INCH_TOP_DN 
                                  2        DELTA_L_85_5INCH_TOP_DP 
                                  3        DELTA_R_GND             
J70              DELTA_L-DELTA-L,THLF,EMPTY,TP24 1        DELTA_L_85_5INCH_BOT_DN 
                                  2        DELTA_L_85_5INCH_BOT_DP 
                                  3        DELTA_R_GND             
J71              DELTA_L-DELTA-L,THLF,EMPTY,TP24 1        DELTA_L_85_5INCH_IN1_DN 
                                  2        DELTA_L_85_5INCH_IN1_DP 
                                  3        DELTA_L_GND             
J72              DELTA_L-DELTA-L,THLF,EMPTY,TP24 1        DELTA_L_85_5INCH_IN2_DN 
                                  2        DELTA_L_85_5INCH_IN2_DP 
                                  3        DELTA_L_GND             
J73              DELTA_L-DELTA-L,THLF,EMPTY,TP24 1        DELTA_L_85_5INCH_IN3_DN 
                                  2        DELTA_L_85_5INCH_IN3_DP 
                                  3        DELTA_L_GND             
J74              DELTA_L-DELTA-L,THLF,EMPTY,TP24 1        DELTA_L_85_5INCH_IN4_DN 
                                  2        DELTA_L_85_5INCH_IN4_DP 
                                  3        DELTA_R_GND             
J75              DELTA_L-DELTA-L,THLF,EMPTY,TP24 1        DELTA_L_85_10INCH_TOP_DP
                                  2        DELTA_L_85_10INCH_TOP_DN
                                  3        DELTA_R_GND             
J76              DELTA_L-DELTA-L,THLF,EMPTY,TP24 1        DELTA_L_85_10INCH_BOT_DP
                                  2        DELTA_L_85_10INCH_BOT_DN
                                  3        DELTA_R_GND             
J77              DELTA_L-DELTA-L,THLF,EMPTY,TP24 1        DELTA_L_85_10INCH_IN1_DP
                                  2        DELTA_L_85_10INCH_IN1_DN
                                  3        DELTA_L_GND             
J78              DELTA_L-DELTA-L,THLF,EMPTY,TP24 1        DELTA_L_85_10INCH_IN2_DP
                                  2        DELTA_L_85_10INCH_IN2_DN
                                  3        DELTA_R_GND             
J79              DELTA_L-DELTA-L,THLF,EMPTY,TP24 1        DELTA_L_85_10INCH_IN3_DP
                                  2        DELTA_L_85_10INCH_IN3_DN
                                  3        DELTA_R_GND             
J80              DELTA_L-DELTA-L,THLF,EMPTY,TP24 1        DELTA_L_85_10INCH_IN4_DP
                                  2        DELTA_L_85_10INCH_IN4_DN
                                  3        DELTA_L_GND             
J81              DELTA_L-DELTA-L,THLF,EMPTY,TP24 1        DELTA_L_85_10INCH_TOP_DN
                                  2        DELTA_L_85_10INCH_TOP_DP
                                  3        DELTA_R_GND             
J82              DELTA_L-DELTA-L,THLF,EMPTY,TP24 1        DELTA_L_85_10INCH_BOT_DN
                                  2        DELTA_L_85_10INCH_BOT_DP
                                  3        DELTA_R_GND             
J83              DELTA_L-DELTA-L,THLF,EMPTY,TP24 1        DELTA_L_85_10INCH_IN1_DN
                                  2        DELTA_L_85_10INCH_IN1_DP
                                  3        DELTA_L_GND             
J84              DELTA_L-DELTA-L,THLF,EMPTY,TP24 1        DELTA_L_85_10INCH_IN2_DN
                                  2        DELTA_L_85_10INCH_IN2_DP
                                  3        DELTA_R_GND             
J85              DELTA_L-DELTA-L,THLF,EMPTY,TP24 1        DELTA_L_85_10INCH_IN3_DN
                                  2        DELTA_L_85_10INCH_IN3_DP
                                  3        DELTA_R_GND             
J86              DELTA_L-DELTA-L,THLF,EMPTY,TP24 1        DELTA_L_85_10INCH_IN4_DN
                                  2        DELTA_L_85_10INCH_IN4_DP
                                  3        DELTA_L_GND             
J87              SCONN84_123318136-SCONN84_1-23A A1       GND                     
                                  A2       GND                     
                                  A3       GND                     
                                  A4       GND                     
                                  A5       GND                     
                                  A6       GND                     
                                  A7       SMB_EDSFF1B_3V3AUX_SCL_R
                                  A8       SMB_EDSFF1B_3V3AUX_SDA_R
                                  A9       RST_SMB_EDSFF1B_N       
                                  A10      SMB_PEHPCPU0_EDSFF1B_LVC3_R_SCL
                                  A11      PU_EDSFF1B_PERST1_CLKREQ_N
                                  A12      PD_PCIE_EDSFF1B_PRSNT_0_N
                                  A13      GND                     
                                  A14      CLK_100M_EDSFF1B_1_DN   
                                  A15      CLK_100M_EDSFF1B_1_DP   
                                  A16      GND                     
                                  A17      P5E_CPU0_PE3_RX_DN<8>   
                                  A18      P5E_CPU0_PE3_RX_DP<8>   
                                  A19      GND                     
                                  A20      P5E_CPU0_PE3_RX_DN<9>   
                                  A21      P5E_CPU0_PE3_RX_DP<9>   
                                  A22      GND                     
                                  A23      P5E_CPU0_PE3_RX_DN<10>  
                                  A24      P5E_CPU0_PE3_RX_DP<10>  
                                  A25      GND                     
                                  A26      P5E_CPU0_PE3_RX_DN<11>  
                                  A27      P5E_CPU0_PE3_RX_DP<11>  
                                  A28      GND                     
                                  A29      GND                     
                                  A30      P5E_CPU0_PE3_RX_DN<12>  
                                  A31      P5E_CPU0_PE3_RX_DP<12>  
                                  A32      GND                     
                                  A33      P5E_CPU0_PE3_RX_DN<13>  
                                  A34      P5E_CPU0_PE3_RX_DP<13>  
                                  A35      GND                     
                                  A36      P5E_CPU0_PE3_RX_DN<14>  
                                  A37      P5E_CPU0_PE3_RX_DP<14>  
                                  A38      GND                     
                                  A39      P5E_CPU0_PE3_RX_DN<15>  
                                  A40      P5E_CPU0_PE3_RX_DP<15>  
                                  A41      GND                     
                                  B1       P12V_REAR_CPU           
                                  B2       P12V_REAR_CPU           
                                  B3       P12V_REAR_CPU           
                                  B4       P12V_REAR_CPU           
                                  B5       P12V_REAR_CPU           
                                  B6       P12V_REAR_CPU           
                                  B7       FM_EDSFF1B_TYPE_ID      
                                  B8       FM_EDSFF1B_PWRBRK_N     
                                  B9       SMB_PEHPCPU0_EDSFF1B_LVC3_R_SDA
                                  B10      RST_PCIE_EDSFF1B_PERST_N
                                  B11      P3V3_AUX                
                                  B12      PD_EDSFF1B_PWRDIS       
                                  B13      GND                     
                                  B14      CLK_100M_EDSFF1B_DN     
                                  B15      CLK_100M_EDSFF1B_DP     
                                  B16      GND                     
                                  B17      P5E_CPU0_PE3_TX_C_DN<8> 
                                  B18      P5E_CPU0_PE3_TX_C_DP<8> 
                                  B19      GND                     
                                  B20      P5E_CPU0_PE3_TX_C_DN<9> 
                                  B21      P5E_CPU0_PE3_TX_C_DP<9> 
                                  B22      GND                     
                                  B23      P5E_CPU0_PE3_TX_C_DN<10>
                                  B24      P5E_CPU0_PE3_TX_C_DP<10>
                                  B25      GND                     
                                  B26      P5E_CPU0_PE3_TX_C_DN<11>
                                  B27      P5E_CPU0_PE3_TX_C_DP<11>
                                  B28      GND                     
                                  B29      GND                     
                                  B30      P5E_CPU0_PE3_TX_C_DN<12>
                                  B31      P5E_CPU0_PE3_TX_C_DP<12>
                                  B32      GND                     
                                  B33      P5E_CPU0_PE3_TX_C_DN<13>
                                  B34      P5E_CPU0_PE3_TX_C_DP<13>
                                  B35      GND                     
                                  B36      P5E_CPU0_PE3_TX_C_DN<14>
                                  B37      P5E_CPU0_PE3_TX_C_DP<14>
                                  B38      GND                     
                                  B39      P5E_CPU0_PE3_TX_C_DN<15>
                                  B40      P5E_CPU0_PE3_TX_C_DP<15>
                                  B41      GND                     
                                  B42      FM_PCIE_EDSFF1B_PRSNT_1_N
                                  G1       GND                     
                                  G2       GND                     
                                  G3       GND                     
                                  G4       GND                     
                                  G5       GND                     
J88              SCONN84_123318136-SCONN84_1-23A A1       GND                     
                                  A2       GND                     
                                  A3       GND                     
                                  A4       GND                     
                                  A5       GND                     
                                  A6       GND                     
                                  A7       SMB_EDSFF4A_3V3AUX_SCL_R
                                  A8       SMB_EDSFF4A_3V3AUX_SDA_R
                                  A9       RST_SMB_EDSFF4A_N       
                                  A10      SMB_PEHPCPU1_EDSFF4A_LVC3_R_SCL
                                  A11      EDSFF4A_PERST1_CLKREQ_N 
                                  A12      PD_PCIE_EDSFF4A_PRSNT_0_N
                                  A13      GND                     
                                  A16      GND                     
                                  A17      P5E_CPU1_PE4_RX_DP<0>   
                                  A18      P5E_CPU1_PE4_RX_DN<0>   
                                  A19      GND                     
                                  A20      P5E_CPU1_PE4_RX_DP<1>   
                                  A21      P5E_CPU1_PE4_RX_DN<1>   
                                  A22      GND                     
                                  A23      P5E_CPU1_PE4_RX_DN<2>   
                                  A24      P5E_CPU1_PE4_RX_DP<2>   
                                  A25      GND                     
                                  A26      P5E_CPU1_PE4_RX_DP<3>   
                                  A27      P5E_CPU1_PE4_RX_DN<3>   
                                  A28      GND                     
                                  A29      GND                     
                                  A30      P5E_CPU1_PE4_RX_DP<4>   
                                  A31      P5E_CPU1_PE4_RX_DN<4>   
                                  A32      GND                     
                                  A33      P5E_CPU1_PE4_RX_DN<5>   
                                  A34      P5E_CPU1_PE4_RX_DP<5>   
                                  A35      GND                     
                                  A36      P5E_CPU1_PE4_RX_DP<6>   
                                  A37      P5E_CPU1_PE4_RX_DN<6>   
                                  A38      GND                     
                                  A39      P5E_CPU1_PE4_RX_DN<7>   
                                  A40      P5E_CPU1_PE4_RX_DP<7>   
                                  A41      GND                     
                                  A42      IRQ_LVC3_WAKE_EDSFF4_N  
                                  B1       P12V_REAR_CPU           
                                  B2       P12V_REAR_CPU           
                                  B3       P12V_REAR_CPU           
                                  B4       P12V_REAR_CPU           
                                  B5       P12V_REAR_CPU           
                                  B6       P12V_REAR_CPU           
                                  B7       FM_EDSFF4A_TYPE_ID      
                                  B8       FM_EDSFF4A_PWRBRK_N     
                                  B9       SMB_PEHPCPU1_EDSFF4A_LVC3_R_SDA
                                  B10      RST_PCIE_EDSFF4A_PERST_N
                                  B11      P3V3_AUX                
                                  B12      PD_EDSFF4A_PWRDIS       
                                  B13      GND                     
                                  B14      CLK_100M_EDSFF4A_DN     
                                  B15      CLK_100M_EDSFF4A_DP     
                                  B16      GND                     
                                  B17      P5E_CPU1_PE4_TX_C_DN<0> 
                                  B18      P5E_CPU1_PE4_TX_C_DP<0> 
                                  B19      GND                     
                                  B20      P5E_CPU1_PE4_TX_C_DP<1> 
                                  B21      P5E_CPU1_PE4_TX_C_DN<1> 
                                  B22      GND                     
                                  B23      P5E_CPU1_PE4_TX_C_DP<2> 
                                  B24      P5E_CPU1_PE4_TX_C_DN<2> 
                                  B25      GND                     
                                  B26      P5E_CPU1_PE4_TX_C_DP<3> 
                                  B27      P5E_CPU1_PE4_TX_C_DN<3> 
                                  B28      GND                     
                                  B29      GND                     
                                  B30      P5E_CPU1_PE4_TX_C_DP<4> 
                                  B31      P5E_CPU1_PE4_TX_C_DN<4> 
                                  B32      GND                     
                                  B33      P5E_CPU1_PE4_TX_C_DP<5> 
                                  B34      P5E_CPU1_PE4_TX_C_DN<5> 
                                  B35      GND                     
                                  B36      P5E_CPU1_PE4_TX_C_DP<6> 
                                  B37      P5E_CPU1_PE4_TX_C_DN<6> 
                                  B38      GND                     
                                  B39      P5E_CPU1_PE4_TX_C_DP<7> 
                                  B40      P5E_CPU1_PE4_TX_C_DN<7> 
                                  B41      GND                     
                                  B42      FM_PCIE_EDSFF4A_PRSNT_1_N
                                  G1       GND                     
                                  G2       GND                     
                                  G3       GND                     
                                  G4       GND                     
                                  G5       GND                     
J89              SCONN280_ME1028040102011-SCONNA A1       PD_RISER2_PRSNT1        
                                  A2       P12V_FRONT_CPU0         
                                  A3       P12V_FRONT_CPU0         
                                  A4       P12V_FRONT_CPU0         
                                  A5       P12V_FRONT_CPU0         
                                  A6       P12V_FRONT_CPU0         
                                  A7       P12V_FRONT_CPU0         
                                  A8       GND                     
                                  A9       GND                     
                                  A10      GND                     
                                  A11      GND                     
                                  A12      GND                     
                                  A13      GND                     
                                  A14      GND                     
                                  A15      GND                     
                                  A16      GND                     
                                  A17      GND                     
                                  A18      GND                     
                                  A19      GND                     
                                  A20      SMB_RISER2_0_3V3AUX_SCL 
                                  A21      SMB_RISER2_0_3V3AUX_SDA 
                                  A22      FM_RISER2_JTAG_SEL_N    
                                  A23      JTAG_RISER2_TCK         
                                  A24      JTAG_RISER2_TDI         
                                  A25      JTAG_RISER2_TDO         
                                  A26      JTAG_RISER2_TMS         
                                  A27      JTAG_RISER2_TRST_N      
                                  A28      GND                     
                                  A29      GND                     
                                  A30      RST_PCIE_RISER2_N       
                                  A31      RISER2_CLK2_EN_N        
                                  A32      GND                     
                                  A33      CLK_100M_PE_2_DN        
                                  A34      CLK_100M_PE_2_DP        
                                  A35      GND                     
                                  A36      P5E_CPU1_PE0_RX_DP<15>  
                                  A37      P5E_CPU1_PE0_RX_DN<15>  
                                  A38      GND                     
                                  A39      P5E_CPU1_PE0_RX_DP<14>  
                                  A40      P5E_CPU1_PE0_RX_DN<14>  
                                  A41      GND                     
                                  A42      P5E_CPU1_PE0_RX_DP<13>  
                                  A43      P5E_CPU1_PE0_RX_DN<13>  
                                  A44      GND                     
                                  A45      P5E_CPU1_PE0_RX_DP<12>  
                                  A46      P5E_CPU1_PE0_RX_DN<12>  
                                  A47      GND                     
                                  A48      P5E_CPU1_PE0_RX_DP<11>  
                                  A49      P5E_CPU1_PE0_RX_DN<11>  
                                  A50      GND                     
                                  A51      P5E_CPU1_PE0_RX_DP<10>  
                                  A52      P5E_CPU1_PE0_RX_DN<10>  
                                  A53      GND                     
                                  A54      P5E_CPU1_PE0_RX_DP<9>   
                                  A55      P5E_CPU1_PE0_RX_DN<9>   
                                  A56      GND                     
                                  A57      GND                     
                                  A58      P5E_CPU1_PE0_RX_DP<8>   
                                  A59      P5E_CPU1_PE0_RX_DN<8>   
                                  A60      GND                     
                                  A61      P5E_CPU1_PE0_RX_DP<7>   
                                  A62      P5E_CPU1_PE0_RX_DN<7>   
                                  A63      GND                     
                                  A64      P5E_CPU1_PE0_RX_DP<6>   
                                  A65      P5E_CPU1_PE0_RX_DN<6>   
                                  A66      GND                     
                                  A67      P5E_CPU1_PE0_RX_DP<5>   
                                  A68      P5E_CPU1_PE0_RX_DN<5>   
                                  A69      GND                     
                                  A70      P5E_CPU1_PE0_RX_DP<4>   
                                  A71      P5E_CPU1_PE0_RX_DN<4>   
                                  A72      GND                     
                                  A73      P5E_CPU1_PE0_RX_DP<3>   
                                  A74      P5E_CPU1_PE0_RX_DN<3>   
                                  A75      GND                     
                                  A76      P5E_CPU1_PE0_RX_DP<2>   
                                  A77      P5E_CPU1_PE0_RX_DN<2>   
                                  A78      GND                     
                                  A79      P5E_CPU1_PE0_RX_DP<1>   
                                  A80      P5E_CPU1_PE0_RX_DN<1>   
                                  A81      GND                     
                                  A82      P5E_CPU1_PE0_RX_DP<0>   
                                  A83      P5E_CPU1_PE0_RX_DN<0>   
                                  A84      GND                     
                                  A85      GND                     
                                  A86      P5E_CPU1_PE2_RX_DP<15>  
                                  A87      P5E_CPU1_PE2_RX_DN<15>  
                                  A88      GND                     
                                  A89      P5E_CPU1_PE2_RX_DP<14>  
                                  A90      P5E_CPU1_PE2_RX_DN<14>  
                                  A91      GND                     
                                  A92      P5E_CPU1_PE2_RX_DP<13>  
                                  A93      P5E_CPU1_PE2_RX_DN<13>  
                                  A94      GND                     
                                  A95      P5E_CPU1_PE2_RX_DP<12>  
                                  A96      P5E_CPU1_PE2_RX_DN<12>  
                                  A97      GND                     
                                  A98      P5E_CPU1_PE2_RX_DP<11>  
                                  A99      P5E_CPU1_PE2_RX_DN<11>  
                                  A100     GND                     
                                  A101     P5E_CPU1_PE2_RX_DP<10>  
                                  A102     P5E_CPU1_PE2_RX_DN<10>  
                                  A103     GND                     
                                  A104     P5E_CPU1_PE2_RX_DP<9>   
                                  A105     P5E_CPU1_PE2_RX_DN<9>   
                                  A106     GND                     
                                  A107     P5E_CPU1_PE2_RX_DP<8>   
                                  A108     P5E_CPU1_PE2_RX_DN<8>   
                                  A109     GND                     
                                  A110     P5E_CPU1_PE2_RX_DP<7>   
                                  A111     P5E_CPU1_PE2_RX_DN<7>   
                                  A112     GND                     
                                  A113     GND                     
                                  A114     P5E_CPU1_PE2_RX_DP<6>   
                                  A115     P5E_CPU1_PE2_RX_DN<6>   
                                  A116     GND                     
                                  A117     P5E_CPU1_PE2_RX_DP<5>   
                                  A118     P5E_CPU1_PE2_RX_DN<5>   
                                  A119     GND                     
                                  A120     P5E_CPU1_PE2_RX_DP<4>   
                                  A121     P5E_CPU1_PE2_RX_DN<4>   
                                  A122     GND                     
                                  A123     P5E_CPU1_PE2_RX_DP<3>   
                                  A124     P5E_CPU1_PE2_RX_DN<3>   
                                  A125     GND                     
                                  A126     P5E_CPU1_PE2_RX_DP<2>   
                                  A127     P5E_CPU1_PE2_RX_DN<2>   
                                  A128     GND                     
                                  A129     P5E_CPU1_PE2_RX_DP<1>   
                                  A130     P5E_CPU1_PE2_RX_DN<1>   
                                  A131     GND                     
                                  A132     P5E_CPU1_PE2_RX_DP<0>   
                                  A133     P5E_CPU1_PE2_RX_DN<0>   
                                  A134     GND                     
                                  A135     GND                     
                                  A136     GND                     
                                  A137     GND                     
                                  A138     GND                     
                                  A139     GND                     
                                  A140     PCIE_RISER2_PRSNT_N     
                                  B1       P12V_FRONT_CPU          
                                  B2       P12V_FRONT_CPU          
                                  B3       P12V_FRONT_CPU          
                                  B4       P12V_FRONT_CPU          
                                  B5       P12V_FRONT_CPU          
                                  B6       P12V_FRONT_CPU          
                                  B7       P12V_FRONT_CPU          
                                  B8       GND                     
                                  B9       GND                     
                                  B10      GND                     
                                  B11      GND                     
                                  B12      GND                     
                                  B13      P12V_FRONT_CPU          
                                  B14      P12V_FRONT_CPU          
                                  B15      P12V_FRONT_CPU          
                                  B16      P12V_FRONT_CPU          
                                  B17      P12V_FRONT_CPU          
                                  B18      P12V_FRONT_CPU          
                                  B19      GND                     
                                  B20      RISER2_USB2_4_DN        
                                  B21      RISER2_USB2_4_DP        
                                  B22      P3V3_AUX                
                                  B23      GND                     
                                  B24      SMB_RISER2_1_3V3AUX_SCL 
                                  B25      SMB_RISER2_1_3V3AUX_SDA 
                                  B26      GND                     
                                  B27      RISER2_CLK3_EN_N        
                                  B28      FM_RISER2_PWRBRK_N      
                                  B29      GND                     
                                  B30      IRQ_LVC3_WAKE_R2_N      
                                  B31      RISER2_TYPE_ID          
                                  B32      GND                     
                                  B33      CLK_100M_PE_3_DN        
                                  B34      CLK_100M_PE_3_DP        
                                  B35      GND                     
                                  B36      P5E_CPU1_PE0_TX_C_DP<15>
                                  B37      P5E_CPU1_PE0_TX_C_DN<15>
                                  B38      GND                     
                                  B39      P5E_CPU1_PE0_TX_C_DP<14>
                                  B40      P5E_CPU1_PE0_TX_C_DN<14>
                                  B41      GND                     
                                  B42      P5E_CPU1_PE0_TX_C_DP<13>
                                  B43      P5E_CPU1_PE0_TX_C_DN<13>
                                  B44      GND                     
                                  B45      P5E_CPU1_PE0_TX_C_DP<12>
                                  B46      P5E_CPU1_PE0_TX_C_DN<12>
                                  B47      GND                     
                                  B48      P5E_CPU1_PE0_TX_C_DP<11>
                                  B49      P5E_CPU1_PE0_TX_C_DN<11>
                                  B50      GND                     
                                  B51      P5E_CPU1_PE0_TX_C_DP<10>
                                  B52      P5E_CPU1_PE0_TX_C_DN<10>
                                  B53      GND                     
                                  B54      P5E_CPU1_PE0_TX_C_DP<9> 
                                  B55      P5E_CPU1_PE0_TX_C_DN<9> 
                                  B56      GND                     
                                  B57      GND                     
                                  B58      P5E_CPU1_PE0_TX_C_DP<8> 
                                  B59      P5E_CPU1_PE0_TX_C_DN<8> 
                                  B60      GND                     
                                  B61      P5E_CPU1_PE0_TX_C_DP<7> 
                                  B62      P5E_CPU1_PE0_TX_C_DN<7> 
                                  B63      GND                     
                                  B64      P5E_CPU1_PE0_TX_C_DP<6> 
                                  B65      P5E_CPU1_PE0_TX_C_DN<6> 
                                  B66      GND                     
                                  B67      P5E_CPU1_PE0_TX_C_DP<5> 
                                  B68      P5E_CPU1_PE0_TX_C_DN<5> 
                                  B69      GND                     
                                  B70      P5E_CPU1_PE0_TX_C_DP<4> 
                                  B71      P5E_CPU1_PE0_TX_C_DN<4> 
                                  B72      GND                     
                                  B73      P5E_CPU1_PE0_TX_C_DP<3> 
                                  B74      P5E_CPU1_PE0_TX_C_DN<3> 
                                  B75      GND                     
                                  B76      P5E_CPU1_PE0_TX_C_DP<2> 
                                  B77      P5E_CPU1_PE0_TX_C_DN<2> 
                                  B78      GND                     
                                  B79      P5E_CPU1_PE0_TX_C_DP<1> 
                                  B80      P5E_CPU1_PE0_TX_C_DN<1> 
                                  B81      GND                     
                                  B82      P5E_CPU1_PE0_TX_C_DP<0> 
                                  B83      P5E_CPU1_PE0_TX_C_DN<0> 
                                  B84      GND                     
                                  B85      GND                     
                                  B86      P5E_CPU1_PE2_TX_C_DP<15>
                                  B87      P5E_CPU1_PE2_TX_C_DN<15>
                                  B88      GND                     
                                  B89      P5E_CPU1_PE2_TX_C_DP<14>
                                  B90      P5E_CPU1_PE2_TX_C_DN<14>
                                  B91      GND                     
                                  B92      P5E_CPU1_PE2_TX_C_DP<13>
                                  B93      P5E_CPU1_PE2_TX_C_DN<13>
                                  B94      GND                     
                                  B95      P5E_CPU1_PE2_TX_C_DP<12>
                                  B96      P5E_CPU1_PE2_TX_C_DN<12>
                                  B97      GND                     
                                  B98      P5E_CPU1_PE2_TX_C_DP<11>
                                  B99      P5E_CPU1_PE2_TX_C_DN<11>
                                  B100     GND                     
                                  B101     P5E_CPU1_PE2_TX_C_DP<10>
                                  B102     P5E_CPU1_PE2_TX_C_DN<10>
                                  B103     GND                     
                                  B104     P5E_CPU1_PE2_TX_C_DP<9> 
                                  B105     P5E_CPU1_PE2_TX_C_DN<9> 
                                  B106     GND                     
                                  B107     P5E_CPU1_PE2_TX_C_DP<8> 
                                  B108     P5E_CPU1_PE2_TX_C_DN<8> 
                                  B109     GND                     
                                  B110     P5E_CPU1_PE2_TX_C_DP<7> 
                                  B111     P5E_CPU1_PE2_TX_C_DN<7> 
                                  B112     GND                     
                                  B113     GND                     
                                  B114     P5E_CPU1_PE2_TX_C_DP<6> 
                                  B115     P5E_CPU1_PE2_TX_C_DN<6> 
                                  B116     GND                     
                                  B117     P5E_CPU1_PE2_TX_C_DP<5> 
                                  B118     P5E_CPU1_PE2_TX_C_DN<5> 
                                  B119     GND                     
                                  B120     P5E_CPU1_PE2_TX_C_DP<4> 
                                  B121     P5E_CPU1_PE2_TX_C_DN<4> 
                                  B122     GND                     
                                  B123     P5E_CPU1_PE2_TX_C_DP<3> 
                                  B124     P5E_CPU1_PE2_TX_C_DN<3> 
                                  B125     GND                     
                                  B126     P5E_CPU1_PE2_TX_C_DP<2> 
                                  B127     P5E_CPU1_PE2_TX_C_DN<2> 
                                  B128     GND                     
                                  B129     P5E_CPU1_PE2_TX_C_DP<1> 
                                  B130     P5E_CPU1_PE2_TX_C_DN<1> 
                                  B131     GND                     
                                  B132     P5E_CPU1_PE2_TX_C_DP<0> 
                                  B133     P5E_CPU1_PE2_TX_C_DN<0> 
                                  B134     GND                     
                                  B135     P3V3                    
                                  B136     P3V3                    
                                  B137     P3V3                    
                                  B138     P3V3                    
                                  B139     P3V3                    
                                  B140     P3V3                    
                                  G1       GND                     
                                  G2       GND                     
                                  G3       GND                     
                                  G4       GND                     
J90              CONN56_ME2005602311011-CONN56_A A1       GND                     
                                  A2       GND                     
                                  A3       GND                     
                                  A4       GND                     
                                  A5       GND                     
                                  A6       GND                     
                                  A7       SMB_E1S_0_3V3AUX_SCL    
                                  A8       SMB_E1S_0_3V3AUX_SDA    
                                  A9       RST_SMB_E1S_0_N         
                                  A10      E1S_0_LED_ACT_N         
                                  A12      E1S_0_PRSNT_N           
                                  A13      GND                     
                                  A16      GND                     
                                  A17      P5E_CPU0_PE0_RX_DN<0>   
                                  A18      P5E_CPU0_PE0_RX_DP<0>   
                                  A19      GND                     
                                  A20      P5E_CPU0_PE0_RX_DN<1>   
                                  A21      P5E_CPU0_PE0_RX_DP<1>   
                                  A22      GND                     
                                  A23      P5E_CPU0_PE0_RX_DN<2>   
                                  A24      P5E_CPU0_PE0_RX_DP<2>   
                                  A25      GND                     
                                  A26      P5E_CPU0_PE0_RX_DN<3>   
                                  A27      P5E_CPU0_PE0_RX_DP<3>   
                                  A28      GND                     
                                  B1       P12V_E1S_0              
                                  B2       P12V_E1S_0              
                                  B3       P12V_E1S_0              
                                  B4       P12V_E1S_0              
                                  B5       P12V_E1S_0              
                                  B6       P12V_E1S_0              
                                  B10      RST_PCIE_E1S_0_PERST_N  
                                  B11      P3V3_E1S_0              
                                  B13      GND                     
                                  B14      CLK_100M_E1S_0_DN       
                                  B15      CLK_100M_E1S_0_DP       
                                  B16      GND                     
                                  B17      P5E_CPU0_PE0_TX_C_DN<0> 
                                  B18      P5E_CPU0_PE0_TX_C_DP<0> 
                                  B19      GND                     
                                  B20      P5E_CPU0_PE0_TX_C_DN<1> 
                                  B21      P5E_CPU0_PE0_TX_C_DP<1> 
                                  B22      GND                     
                                  B23      P5E_CPU0_PE0_TX_C_DN<2> 
                                  B24      P5E_CPU0_PE0_TX_C_DP<2> 
                                  B25      GND                     
                                  B26      P5E_CPU0_PE0_TX_C_DN<3> 
                                  B27      P5E_CPU0_PE0_TX_C_DP<3> 
                                  B28      GND                     
J91              CONN56_ME2005602311011-CONN56_A A1       GND                     
                                  A2       GND                     
                                  A3       GND                     
                                  A4       GND                     
                                  A5       GND                     
                                  A6       GND                     
                                  A7       SMB_E1S_1_3V3AUX_SCL    
                                  A8       SMB_E1S_1_3V3AUX_SDA    
                                  A9       RST_SMB_E1S_1_N         
                                  A10      E1S_1_LED_ACT_N         
                                  A12      E1S_1_PRSNT_N           
                                  A13      GND                     
                                  A16      GND                     
                                  A17      P5E_CPU0_PE0_RX_DN<4>   
                                  A18      P5E_CPU0_PE0_RX_DP<4>   
                                  A19      GND                     
                                  A20      P5E_CPU0_PE0_RX_DN<5>   
                                  A21      P5E_CPU0_PE0_RX_DP<5>   
                                  A22      GND                     
                                  A23      P5E_CPU0_PE0_RX_DN<6>   
                                  A24      P5E_CPU0_PE0_RX_DP<6>   
                                  A25      GND                     
                                  A26      P5E_CPU0_PE0_RX_DN<7>   
                                  A27      P5E_CPU0_PE0_RX_DP<7>   
                                  A28      GND                     
                                  B1       P12V_E1S_1              
                                  B2       P12V_E1S_1              
                                  B3       P12V_E1S_1              
                                  B4       P12V_E1S_1              
                                  B5       P12V_E1S_1              
                                  B6       P12V_E1S_1              
                                  B10      RST_PCIE_E1S_1_PERST_N  
                                  B11      P3V3_E1S_1              
                                  B13      GND                     
                                  B14      CLK_100M_E1S_1_DN       
                                  B15      CLK_100M_E1S_1_DP       
                                  B16      GND                     
                                  B17      P5E_CPU0_PE0_TX_C_DN<4> 
                                  B18      P5E_CPU0_PE0_TX_C_DP<4> 
                                  B19      GND                     
                                  B20      P5E_CPU0_PE0_TX_C_DN<5> 
                                  B21      P5E_CPU0_PE0_TX_C_DP<5> 
                                  B22      GND                     
                                  B23      P5E_CPU0_PE0_TX_C_DN<6> 
                                  B24      P5E_CPU0_PE0_TX_C_DP<6> 
                                  B25      GND                     
                                  B26      P5E_CPU0_PE0_TX_C_DN<7> 
                                  B27      P5E_CPU0_PE0_TX_C_DP<7> 
                                  B28      GND                     
J92              CONN56_ME2005602311011-CONN56_A A1       GND                     
                                  A2       GND                     
                                  A3       GND                     
                                  A4       GND                     
                                  A5       GND                     
                                  A6       GND                     
                                  A7       SMB_E1S_2_3V3AUX_SCL    
                                  A8       SMB_E1S_2_3V3AUX_SDA    
                                  A9       RST_SMB_E1S_2_N         
                                  A10      E1S_2_LED_ACT_N         
                                  A12      E1S_2_PRSNT_N           
                                  A13      GND                     
                                  A16      GND                     
                                  A17      P5E_CPU0_PE0_RX_DN<8>   
                                  A18      P5E_CPU0_PE0_RX_DP<8>   
                                  A19      GND                     
                                  A20      P5E_CPU0_PE0_RX_DN<9>   
                                  A21      P5E_CPU0_PE0_RX_DP<9>   
                                  A22      GND                     
                                  A23      P5E_CPU0_PE0_RX_DN<10>  
                                  A24      P5E_CPU0_PE0_RX_DP<10>  
                                  A25      GND                     
                                  A26      P5E_CPU0_PE0_RX_DN<11>  
                                  A27      P5E_CPU0_PE0_RX_DP<11>  
                                  A28      GND                     
                                  B1       P12V_E1S_2              
                                  B2       P12V_E1S_2              
                                  B3       P12V_E1S_2              
                                  B4       P12V_E1S_2              
                                  B5       P12V_E1S_2              
                                  B6       P12V_E1S_2              
                                  B10      RST_PCIE_E1S_2_PERST_N  
                                  B11      P3V3_E1S_2              
                                  B13      GND                     
                                  B14      CLK_100M_E1S_2_DN       
                                  B15      CLK_100M_E1S_2_DP       
                                  B16      GND                     
                                  B17      P5E_CPU0_PE0_TX_C_DN<8> 
                                  B18      P5E_CPU0_PE0_TX_C_DP<8> 
                                  B19      GND                     
                                  B20      P5E_CPU0_PE0_TX_C_DN<9> 
                                  B21      P5E_CPU0_PE0_TX_C_DP<9> 
                                  B22      GND                     
                                  B23      P5E_CPU0_PE0_TX_C_DN<10>
                                  B24      P5E_CPU0_PE0_TX_C_DP<10>
                                  B25      GND                     
                                  B26      P5E_CPU0_PE0_TX_C_DN<11>
                                  B27      P5E_CPU0_PE0_TX_C_DP<11>
                                  B28      GND                     
J93              CONN56_ME2005602311011-CONN56_A A1       GND                     
                                  A2       GND                     
                                  A3       GND                     
                                  A4       GND                     
                                  A5       GND                     
                                  A6       GND                     
                                  A7       SMB_E1S_3_3V3AUX_SCL    
                                  A8       SMB_E1S_3_3V3AUX_SDA    
                                  A9       RST_SMB_E1S_3_N         
                                  A10      E1S_3_LED_ACT_N         
                                  A12      E1S_3_PRSNT_N           
                                  A13      GND                     
                                  A16      GND                     
                                  A17      P5E_CPU0_PE0_RX_DN<12>  
                                  A18      P5E_CPU0_PE0_RX_DP<12>  
                                  A19      GND                     
                                  A20      P5E_CPU0_PE0_RX_DN<13>  
                                  A21      P5E_CPU0_PE0_RX_DP<13>  
                                  A22      GND                     
                                  A23      P5E_CPU0_PE0_RX_DN<14>  
                                  A24      P5E_CPU0_PE0_RX_DP<14>  
                                  A25      GND                     
                                  A26      P5E_CPU0_PE0_RX_DN<15>  
                                  A27      P5E_CPU0_PE0_RX_DP<15>  
                                  A28      GND                     
                                  B1       P12V_E1S_3              
                                  B2       P12V_E1S_3              
                                  B3       P12V_E1S_3              
                                  B4       P12V_E1S_3              
                                  B5       P12V_E1S_3              
                                  B6       P12V_E1S_3              
                                  B10      RST_PCIE_E1S_3_PERST_N  
                                  B11      P3V3_E1S_3              
                                  B13      GND                     
                                  B14      CLK_100M_E1S_3_DN       
                                  B15      CLK_100M_E1S_3_DP       
                                  B16      GND                     
                                  B17      P5E_CPU0_PE0_TX_C_DN<12>
                                  B18      P5E_CPU0_PE0_TX_C_DP<12>
                                  B19      GND                     
                                  B20      P5E_CPU0_PE0_TX_C_DN<13>
                                  B21      P5E_CPU0_PE0_TX_C_DP<13>
                                  B22      GND                     
                                  B23      P5E_CPU0_PE0_TX_C_DN<14>
                                  B24      P5E_CPU0_PE0_TX_C_DP<14>
                                  B25      GND                     
                                  B26      P5E_CPU0_PE0_TX_C_DN<15>
                                  B27      P5E_CPU0_PE0_TX_C_DP<15>
                                  B28      GND                     
JP1              CONN3_210HP1030BR1-CONN3_210-HA 1        GND                     
                                  2        SMB_VR_3V3AUX_SDA_R     
                                  3        SMB_VR_3V3AUX_SCL_R     
JP5              CONN3_HFK1030G000LAF-CONN3_HFKA 1        P12V_FRONT_CPU          
                                  2        GND                     
                                  3        P5V                     
JP7              CONN3_210HP1030BR1-CONN3_210-HA 1        FM_SMB_PEHPCPU0_PCIE_ALERT_N
                                  2        GND                     
                                  3        FM_SMB_PEHPCPU1_PCIE_ALERT_N
JP8              CONN3_HFK1030G000LAF-CONN3_HFKA 1        GND                     
                                  2        FM_INTRUDER_HDR_PCH_N   
L1               Q_INDUCTOR_SMLF-FCM2012KF-601TA 1        P3V3_AUX                
                                  2        P3V3_AUX_CLK_GEN_VDD_CK440
L2               Q_INDUCTOR_SMLF-BLM18PG121SN1DA 1        P1V05_PCH_AUX           
                                  2        P1V05_PCH_PLL_AUX       
L3               Q_INDUCTOR_SMLF-BLM18SG331TN1DA 1        P3V3                    
                                  2        P3V3_DB2000_VDD         
L4               Q_INDUCTOR_SMLF-BLM18SG331TN1DA 1        P3V3                    
                                  2        P3V3_DB2000_FB_VDD      
L5               Q_INDUCTOR4P_12-67/320MA,320MAA 1        USB3_9_TX_DN_C          
                                  2        USB3_9_TX_DN_FB         
                                  3        USB3_9_TX_DP_FB         
                                  4        USB3_9_TX_DP_C          
L6               Q_INDUCTOR4P_12-67/320MA,320MAA 1        USB3_9_RX_DN            
                                  2        USB3_9_RX_DN_FB         
                                  3        USB3_9_RX_DP_FB         
                                  4        USB3_9_RX_DP            
L9               Q_INDUCTOR4P_12-67/320MA,320MAA 1        USB2_1_DP               
                                  2        USB2_1_F_DP             
                                  3        USB2_1_F_DN             
                                  4        USB2_1_DN               
L10              Q_INDUCTOR_SMLF-BLM18PG121SN1DA 1        P1V8_PCH_AUX            
                                  2        P1V8_PCH_PLL_AUX        
L11              Q_INDUCTOR_SMLF-BLM15AG121SN1DA 1        IRQ_PSU_ALERT_N         
L12              Q_INDUCTOR_SMLF-BLM15AG121SN1DA 1        PSU1_THROTTLE_R         
                                  2        FM_PSU_THROTTLE_L       
L13              Q_INDUCTOR_SMLF-FCM2012KF-601TA 1        P3V3_AUX                
                                  2        P3V3_AUX_CLK_GEN_VDDXTAL_CK440
L14              Q_INDUCTOR_SMLF-FCM2012KF-601TA 1        P3V3_AUX                
                                  2        P3V3_AUX_CLK_GEN_VDDMXCK_CK440
L36              Q_INDUCTOR_SMLF-BLM18PG121SN1DA 1        P3V3_AUX                
                                  2        PVCCA_AUX_PLD           
OSC1             OSC4_SIT1602AI2233E50000000D-5A 1        CLK_50M_EN              
                                  2        GND                     
                                  3        CLK_50M_RMII            
                                  4        P3V3_AUX                
OSC2             Q_OSC4P_SMLF-25MHZ,OSC,BF62500A 1        PU_CLK25M_OSC_FPGA_EN   
                                  2        GND                     
                                  3        CLK_25M_OSC_FPGA_R      
                                  4        P3V3_AUX                
PC16             Q_CAPP_THLF-560UF,2.5V,20%,OSCA 1        PVCCIN_CPU0             
                                  2        GND                     
PC27             Q_CAP_0402-3300PF,50V,10%,X7R,A 1        PVNN_MAIN_CPU0_REF      
                                  2        GND                     
PC28             Q_CAP_0402-3300PF,50V,10%,X7R,A 1        PVNN_MAIN_CPU1_REF      
                                  2        GND                     
PC71             Q_CAP_C0805-22UF,16V,20%,X6S,CA 1        SW_P3V3_AUX_FLT         
                                  2        GND                     
PC83             Q_CAPP_THLF-560UF,2.5V,20%,OSCA 1        PVCCIN_CPU1             
                                  2        GND                     
PC113            Q_CAP_C0402-1UF,25V,10%,X6S,CHA 1        P1V05_PCH_AUX_VCC       
                                  2        GND                     
PC117            Q_CAPP_SMLF-470UF,2V,20%,POSCAA 1        P1V05_PCH_AUX           
                                  2        GND                     
PC175            Q_CAP_C0402-2.2UF,10V,10%,X6S,A 1        PVCCFA_EHV_CPU0_VDD1    
                                  2        GND                     
PC176            Q_CAP_0402-3300PF,50V,10%,X7R,A 1        SW_P12V_PVCCINFAON_CPU0_FLT
                                  2        GND                     
PC177            Q_CAP_C0402-1UF,16V,10%,X6S,CHA 1        SW_P12V_PVCCINFAON_CPU0_FLT
                                  2        GND                     
PC178            Q_CAP_C0402-100NF,50V,10%,X7R,A 1        SW_PVCCFA_EHV_CPU0_BOOT1_R
                                  2        SW_PVCCFA_EHV_CPU0_BOOTR1
PC179            Q_CAP_C0805-22UF,16V,20%,X6S,CA 1        SW_P12V_PVCCINFAON_CPU0_FLT
                                  2        GND                     
PC180            Q_CAP_C0805-22UF,16V,20%,X6S,CA 1        SW_P12V_PVCCINFAON_CPU0_FLT
                                  2        GND                     
PC181            Q_CAP_C0402-100NF,50V,10%,X7R,A 1        PVCCFA_EHV_CPU0         
                                  2        GND                     
PC184            Q_CAP_0805-22UF,4V,20%,X6S,TMPA 1        PVCCFA_EHV_CPU0         
                                  2        GND                     
PC186            Q_CAP_0805-22UF,4V,20%,X6S,TMPA 1        PVCCFA_EHV_CPU0         
                                  2        GND                     
PC187            Q_CAP_C0402-2.2UF,10V,10%,X6S,A 1        PVCCINFAON_CPU0_VDD1    
                                  2        GND                     
PC188            Q_CAP_C0402-2.2UF,10V,10%,X6S,A 1        PVCCINFAON_CPU0_VDD2    
                                  2        GND                     
PC189            Q_CAPP_SMLF-470UF,2.5V,20%,EMPA 1        PVCCIN_CPU1             
                                  2        GND                     
PC189_P0_1       Q_CAP_0402-3300PF,50V,10%,X7R,A 1        SW_P12V_PVCCINFAON_CPU0_FLT
                                  2        GND                     
PC190_P0_2       Q_CAP_0402-3300PF,50V,10%,X7R,A 1        SW_P12V_PVCCINFAON_CPU0_FLT
                                  2        GND                     
PC191_P0_1       Q_CAP_C0402-1UF,16V,10%,X6S,CHA 1        SW_P12V_PVCCINFAON_CPU0_FLT
                                  2        GND                     
PC192_P0_2       Q_CAP_C0402-1UF,16V,10%,X6S,CHA 1        SW_P12V_PVCCINFAON_CPU0_FLT
                                  2        GND                     
PC193            Q_CAP_C0402-100NF,50V,10%,X7R,A 1        SW_PVCCINFAON_CPU0_BOOT1_R
                                  2        SW_PVCCINFAON_CPU0_BOOTR1
PC194            Q_CAP_C0402-100NF,50V,10%,X7R,A 1        SW_PVCCINFAON_CPU0_BOOT2_R
                                  2        SW_PVCCINFAON_CPU0_BOOTR2
PC195_P0_1       Q_CAP_C0805-22UF,16V,20%,X6S,CA 1        SW_P12V_PVCCINFAON_CPU0_FLT
                                  2        GND                     
PC196_P0_2       Q_CAP_C0805-22UF,16V,20%,X6S,CA 1        SW_P12V_PVCCINFAON_CPU0_FLT
                                  2        GND                     
PC197_P0_1       Q_CAP_C0805-22UF,16V,20%,X6S,CA 1        SW_P12V_PVCCINFAON_CPU0_FLT
                                  2        GND                     
PC198_P0_2       Q_CAP_C0805-22UF,16V,20%,X6S,CA 1        SW_P12V_PVCCINFAON_CPU0_FLT
                                  2        GND                     
PC199_P0_1       Q_CAP_C0402-100NF,50V,10%,X7R,A 1        PVCCINFAON_CPU0         
                                  2        GND                     
PC202_P0_1       Q_CAP_0805-22UF,4V,20%,X6S,TMPA 1        PVCCINFAON_CPU0         
                                  2        GND                     
PC203_P0_2       Q_CAP_0805-22UF,4V,20%,X6S,TMPA 1        PVCCINFAON_CPU0         
                                  2        GND                     
PC204_P0_1       Q_CAP_0805-22UF,4V,20%,X6S,TMPA 1        PVCCINFAON_CPU0         
                                  2        GND                     
PC205_P0_2       Q_CAP_0805-22UF,4V,20%,X6S,TMPA 1        PVCCINFAON_CPU0         
                                  2        GND                     
PC207            Q_CAPP_THLF-270UF,16V,20%,OSCOA 1        SW_P12V_PVCCINFAON_CPU0_FLT
                                  2        GND                     
PC208            Q_CAPP_THLF-270UF,16V,20%,OSCOA 1        SW_P12V_PVCCINFAON_CPU0_FLT
                                  2        GND                     
PC214            Q_CAP_0402-0.1UF,25V,10%,EMPTYA 1        PVCCINFAON_CPU0_CSPIN   
                                  2        GND                     
PC215            Q_CAP_0402-3300PF,50V,10%,X7R,A 1        SH_PVCCINFAON_CPU0_R    
                                  2        VSENSE_PVCCINFAON_CPU0_DN
PC216            Q_CAP_0402-3300PF,50V,10%,X7R,A 1        SH_PVCCFA_EHV_CPU0_R    
                                  2        VSENSE_PVCCFA_EHV_CPU0_DN
PC217            Q_CAP_0402-1000PF,50V,5%,X7R,TA 1        PVCCINFAON_CPU0_EN_R    
                                  2        GND                     
PC218            Q_CAP_0402-1000PF,50V,5%,EMPTYA 1        PWRGD_PVCCINFAON_CPU0_R 
                                  2        GND                     
PC219            Q_CAP_0402-1000PF,50V,5%,X7R,TA 1        PVCCFA_EHV_CPU0_EN_R    
                                  2        GND                     
PC220            Q_CAP_0402-1000PF,50V,5%,EMPTYA 1        PWRGD_PVCCFA_EHV_CPU0_R 
                                  2        GND                     
PC221            Q_CAP_0402-0.1UF,25V,10%,X7R,CA 1        PVCCINFAON_CPU0_VIN_CSNIN
                                  2        GND                     
PC222            Q_CAP_0402-470PF,50V,10%,X7R,TA 1        PVCCINFAON_CPU0_ATSEN   
                                  2        GND                     
PC223            Q_CAP_C0402-100NF,50V,10%,EMPTA 1        PVCCINFAON_CPU0_VCC     
                                  2        GND                     
PC224            Q_CAP_0402-4.7UF,6.3V,20%,X6S,A 1        PVCCINFAON_CPU0_VREF    
                                  2        GND                     
PC225            Q_CAP_C0402-1UF,16V,10%,X6S,CHA 1        PVCCINFAON_CPU0_VCC     
                                  2        GND                     
PC226            Q_CAP_C0402-2.2UF,10V,10%,X6S,A 1        PVCCIN_CPU0_VDD8        
                                  2        GND                     
PC227            Q_CAP_C0402-2.2UF,10V,10%,X6S,A 1        PVCCIN_CPU0_VDD7        
                                  2        GND                     
PC228_P0_8       Q_CAP_C0402-2.2UF,10V,10%,X6S,A 1        PVCCIN_CPU0_PVCC        
                                  2        GND                     
PC229_P0_7       Q_CAP_C0402-2.2UF,10V,10%,X6S,A 1        PVCCIN_CPU0_PVCC        
                                  2        GND                     
PC230_P0_8       Q_CAP_0402-3300PF,50V,10%,X7R,A 1        SW_P12V_PVCCIN_CPU0_FLT 
                                  2        GND                     
PC231_P0_7       Q_CAP_0402-3300PF,50V,10%,X7R,A 1        SW_P12V_PVCCIN_CPU0_FLT 
                                  2        GND                     
PC232_P0_8       Q_CAP_C0402-1UF,16V,10%,X6S,CHA 1        SW_P12V_PVCCIN_CPU0_FLT 
                                  2        GND                     
PC233_P0_7       Q_CAP_C0402-1UF,16V,10%,X6S,CHA 1        SW_P12V_PVCCIN_CPU0_FLT 
                                  2        GND                     
PC234            Q_CAP_C0402-100NF,50V,10%,X7R,A 1        SW_PVCCIN_CPU0_BOOT8_R  
                                  2        SW_PVCCIN_CPU0_BOOTR8   
PC235            Q_CAP_C0402-100NF,50V,10%,X7R,A 1        SW_PVCCIN_CPU0_BOOT7_R  
                                  2        SW_PVCCIN_CPU0_BOOTR7   
PC236_P0_8       Q_CAP_C0805-22UF,16V,20%,X6S,CA 1        SW_P12V_PVCCIN_CPU0_FLT 
                                  2        GND                     
PC237            Q_CAP_0402-680PF,50V,10%,X7R,TA 1        PVNN_MAIN_CPU0_FB_RC    
                                  2        PVNN_MAIN_CPU0          
PC237_P0_7       Q_CAP_C0805-22UF,16V,20%,X6S,CA 1        SW_P12V_PVCCIN_CPU0_FLT 
                                  2        GND                     
PC238            Q_CAP_0402-680PF,50V,10%,X7R,TA 1        PVNN_MAIN_CPU1_FB_RC    
                                  2        PVNN_MAIN_CPU1          
PC238_P0_8       Q_CAP_C0805-22UF,16V,20%,X6S,CA 1        SW_P12V_PVCCIN_CPU0_FLT 
                                  2        GND                     
PC239_P0_7       Q_CAP_C0805-22UF,16V,20%,X6S,CA 1        SW_P12V_PVCCIN_CPU0_FLT 
                                  2        GND                     
PC240_P0_8       Q_CAP_C0805-22UF,16V,20%,X6S,CA 1        SW_P12V_PVCCIN_CPU0_FLT 
                                  2        GND                     
PC241_P0_7       Q_CAP_C0805-22UF,16V,20%,X6S,CA 1        SW_P12V_PVCCIN_CPU0_FLT 
                                  2        GND                     
PC242_P0_8       Q_CAP_C0402-1UF,16V,10%,X6S,CHA 1        PVCCIN_CPU0             
                                  2        GND                     
PC243_P0_7       Q_CAP_C0402-1UF,16V,10%,X6S,CHA 1        PVCCIN_CPU0             
                                  2        GND                     
PC244_P0_8       Q_CAP_0805-22UF,4V,20%,X6S,TMPA 1        PVCCIN_CPU0             
                                  2        GND                     
PC245_P0_7       Q_CAP_0805-22UF,4V,20%,X6S,TMPA 1        PVCCIN_CPU0             
                                  2        GND                     
PC246_P0_8       Q_CAP_0805-22UF,4V,20%,X6S,TMPA 1        PVCCIN_CPU0             
                                  2        GND                     
PC247_P0_7       Q_CAP_0805-22UF,4V,20%,X6S,TMPA 1        PVCCIN_CPU0             
                                  2        GND                     
PC248            Q_CAP_C0402-2.2UF,10V,10%,X6S,A 1        PVCCIN_CPU0_VDD6        
                                  2        GND                     
PC249            Q_CAP_C0402-2.2UF,10V,10%,X6S,A 1        PVCCIN_CPU0_VDD5        
                                  2        GND                     
PC250_P0_6       Q_CAP_C0402-2.2UF,10V,10%,X6S,A 1        PVCCIN_CPU0_PVCC        
                                  2        GND                     
PC251_P0_5       Q_CAP_C0402-2.2UF,10V,10%,X6S,A 1        PVCCIN_CPU0_PVCC        
                                  2        GND                     
PC252_P0_6       Q_CAP_0402-3300PF,50V,10%,X7R,A 1        SW_P12V_PVCCIN_CPU0_FLT 
                                  2        GND                     
PC253_P0_5       Q_CAP_0402-3300PF,50V,10%,X7R,A 1        SW_P12V_PVCCIN_CPU0_FLT 
                                  2        GND                     
PC254_P0_6       Q_CAP_C0402-1UF,16V,10%,X6S,CHA 1        SW_P12V_PVCCIN_CPU0_FLT 
                                  2        GND                     
PC255_P0_5       Q_CAP_C0402-1UF,16V,10%,X6S,CHA 1        SW_P12V_PVCCIN_CPU0_FLT 
                                  2        GND                     
PC256            Q_CAP_C0402-100NF,50V,10%,X7R,A 1        SW_PVCCIN_CPU0_BOOT6_R  
                                  2        SW_PVCCIN_CPU0_BOOTR6   
PC257            Q_CAP_C0402-100NF,50V,10%,X7R,A 1        SW_PVCCIN_CPU0_BOOT5_R  
                                  2        SW_PVCCIN_CPU0_BOOTR5   
PC258_P0_6       Q_CAP_C0805-22UF,16V,20%,X6S,CA 1        SW_P12V_PVCCIN_CPU0_FLT 
                                  2        GND                     
PC259_P0_5       Q_CAP_C0805-22UF,16V,20%,X6S,CA 1        SW_P12V_PVCCIN_CPU0_FLT 
                                  2        GND                     
PC260_P0_6       Q_CAP_C0805-22UF,16V,20%,X6S,CA 1        SW_P12V_PVCCIN_CPU0_FLT 
                                  2        GND                     
PC261_P0_5       Q_CAP_C0805-22UF,16V,20%,X6S,CA 1        SW_P12V_PVCCIN_CPU0_FLT 
                                  2        GND                     
PC262_P0_6       Q_CAP_C0805-22UF,16V,20%,X6S,CA 1        SW_P12V_PVCCIN_CPU0_FLT 
                                  2        GND                     
PC263_P0_5       Q_CAP_C0805-22UF,16V,20%,X6S,CA 1        SW_P12V_PVCCIN_CPU0_FLT 
                                  2        GND                     
PC266_P0_6       Q_CAP_0805-22UF,4V,20%,X6S,TMPA 1        PVCCIN_CPU0             
                                  2        GND                     
PC267_P0_5       Q_CAP_0805-22UF,4V,20%,X6S,TMPA 1        PVCCIN_CPU0             
                                  2        GND                     
PC268_P0_6       Q_CAP_0805-22UF,4V,20%,X6S,TMPA 1        PVCCIN_CPU0             
                                  2        GND                     
PC269_P0_5       Q_CAP_0805-22UF,4V,20%,X6S,TMPA 1        PVCCIN_CPU0             
                                  2        GND                     
PC270            Q_CAP_C0402-2.2UF,10V,10%,X6S,A 1        PVCCIN_CPU0_VDD4        
                                  2        GND                     
PC271            Q_CAP_C0402-2.2UF,10V,10%,X6S,A 1        PVCCIN_CPU0_VDD3        
                                  2        GND                     
PC272_P0_4       Q_CAP_C0402-2.2UF,10V,10%,X6S,A 1        PVCCIN_CPU0_PVCC        
                                  2        GND                     
PC273_P0_3       Q_CAP_C0402-2.2UF,10V,10%,X6S,A 1        PVCCIN_CPU0_PVCC        
                                  2        GND                     
PC274_P0_4       Q_CAP_0402-3300PF,50V,10%,X7R,A 1        SW_P12V_PVCCIN_CPU0_FLT 
                                  2        GND                     
PC275_P0_3       Q_CAP_0402-3300PF,50V,10%,X7R,A 1        SW_P12V_PVCCIN_CPU0_FLT 
                                  2        GND                     
PC276_P0_4       Q_CAP_C0402-1UF,16V,10%,X6S,CHA 1        SW_P12V_PVCCIN_CPU0_FLT 
                                  2        GND                     
PC277_P0_3       Q_CAP_C0402-1UF,16V,10%,X6S,CHA 1        SW_P12V_PVCCIN_CPU0_FLT 
                                  2        GND                     
PC278            Q_CAP_C0402-100NF,50V,10%,X7R,A 1        SW_PVCCIN_CPU0_BOOT4_R  
                                  2        SW_PVCCIN_CPU0_BOOTR4   
PC279            Q_CAP_C0402-100NF,50V,10%,X7R,A 1        SW_PVCCIN_CPU0_BOOT3_R  
                                  2        SW_PVCCIN_CPU0_BOOTR3   
PC280_P0_4       Q_CAP_C0805-22UF,16V,20%,X6S,CA 1        SW_P12V_PVCCIN_CPU0_FLT 
                                  2        GND                     
PC281_P0_3       Q_CAP_C0805-22UF,16V,20%,X6S,CA 1        SW_P12V_PVCCIN_CPU0_FLT 
                                  2        GND                     
PC282_P0_4       Q_CAP_C0805-22UF,16V,20%,X6S,CA 1        SW_P12V_PVCCIN_CPU0_FLT 
                                  2        GND                     
PC283_P0_3       Q_CAP_C0805-22UF,16V,20%,X6S,CA 1        SW_P12V_PVCCIN_CPU0_FLT 
                                  2        GND                     
PC284_P0_4       Q_CAP_C0805-22UF,16V,20%,X6S,CA 1        SW_P12V_PVCCIN_CPU0_FLT 
                                  2        GND                     
PC285_P0_3       Q_CAP_C0805-22UF,16V,20%,X6S,CA 1        SW_P12V_PVCCIN_CPU0_FLT 
                                  2        GND                     
PC288_P0_4       Q_CAP_0805-22UF,4V,20%,X6S,TMPA 1        PVCCIN_CPU0             
                                  2        GND                     
PC289_P0_3       Q_CAP_0805-22UF,4V,20%,X6S,TMPA 1        PVCCIN_CPU0             
                                  2        GND                     
PC290_P0_4       Q_CAP_0805-22UF,4V,20%,X6S,TMPA 1        PVCCIN_CPU0             
                                  2        GND                     
PC291_P0_3       Q_CAP_0805-22UF,4V,20%,X6S,TMPA 1        PVCCIN_CPU0             
                                  2        GND                     
PC292            Q_CAP_C0402-2.2UF,10V,10%,X6S,A 1        PVCCIN_CPU0_VDD2        
                                  2        GND                     
PC293            Q_CAP_C0402-2.2UF,10V,10%,X6S,A 1        PVCCIN_CPU0_VDD1        
                                  2        GND                     
PC294_P0_2       Q_CAP_C0402-2.2UF,10V,10%,X6S,A 1        PVCCIN_CPU0_PVCC        
                                  2        GND                     
PC295_P0_1       Q_CAP_C0402-2.2UF,10V,10%,X6S,A 1        PVCCIN_CPU0_PVCC        
                                  2        GND                     
PC296_P0_2       Q_CAP_0402-3300PF,50V,10%,X7R,A 1        SW_P12V_PVCCIN_CPU0_FLT 
                                  2        GND                     
PC297_P0_1       Q_CAP_0402-3300PF,50V,10%,X7R,A 1        SW_P12V_PVCCIN_CPU0_FLT 
                                  2        GND                     
PC298_P0_2       Q_CAP_C0402-1UF,16V,10%,X6S,CHA 1        SW_P12V_PVCCIN_CPU0_FLT 
                                  2        GND                     
PC299_P0_1       Q_CAP_C0402-1UF,16V,10%,X6S,CHA 1        SW_P12V_PVCCIN_CPU0_FLT 
                                  2        GND                     
PC300            Q_CAP_C0402-100NF,50V,10%,X7R,A 1        SW_PVCCIN_CPU0_BOOT2_R  
                                  2        SW_PVCCIN_CPU0_BOOTR2   
PC301            Q_CAP_C0402-100NF,50V,10%,X7R,A 1        SW_PVCCIN_CPU0_BOOT1_R  
                                  2        SW_PVCCIN_CPU0_BOOTR1   
PC302_P0_2       Q_CAP_C0805-22UF,16V,20%,X6S,CA 1        SW_P12V_PVCCIN_CPU0_FLT 
                                  2        GND                     
PC303_P0_1       Q_CAP_C0805-22UF,16V,20%,X6S,CA 1        SW_P12V_PVCCIN_CPU0_FLT 
                                  2        GND                     
PC304_P0_2       Q_CAP_C0805-22UF,16V,20%,X6S,CA 1        SW_P12V_PVCCIN_CPU0_FLT 
                                  2        GND                     
PC305_P0_1       Q_CAP_C0805-22UF,16V,20%,X6S,CA 1        SW_P12V_PVCCIN_CPU0_FLT 
                                  2        GND                     
PC306_P0_2       Q_CAP_C0805-22UF,16V,20%,X6S,CA 1        SW_P12V_PVCCIN_CPU0_FLT 
                                  2        GND                     
PC307_P0_1       Q_CAP_C0805-22UF,16V,20%,X6S,CA 1        SW_P12V_PVCCIN_CPU0_FLT 
                                  2        GND                     
PC308_P0_1       Q_CAP_C0402-100NF,50V,10%,X7R,A 1        PVCCIN_CPU0             
                                  2        GND                     
PC310_P0_1       Q_CAP_C0402-1UF,16V,10%,X6S,CHA 1        PVCCIN_CPU0             
                                  2        GND                     
PC311_P0_2       Q_CAP_0805-22UF,4V,20%,X6S,TMPA 1        PVCCIN_CPU0             
                                  2        GND                     
PC312_P0_1       Q_CAP_0805-22UF,4V,20%,X6S,TMPA 1        PVCCIN_CPU0             
                                  2        GND                     
PC313_P0_2       Q_CAP_0805-22UF,4V,20%,X6S,TMPA 1        PVCCIN_CPU0             
                                  2        GND                     
PC314_P0_1       Q_CAP_0805-22UF,4V,20%,X6S,TMPA 1        PVCCIN_CPU0             
                                  2        GND                     
PC315            Q_CAPP_THLF-270UF,16V,20%,OSCOA 1        SW_P12V_PVCCIN_CPU0_FLT 
                                  2        GND                     
PC316            Q_CAPP_THLF-560UF,2.5V,20%,OSCA 1        PVCCIN_CPU0             
                                  2        GND                     
PC318            Q_CAPP_THLF-270UF,16V,20%,OSCOA 1        SW_P12V_PVCCIN_CPU0_FLT 
                                  2        GND                     
PC319            Q_CAPP_THLF-560UF,2.5V,20%,OSCA 1        PVCCIN_CPU0             
                                  2        GND                     
PC321            Q_CAPP_THLF-270UF,16V,20%,OSCOA 1        SW_P12V_PVCCIN_CPU0_FLT 
                                  2        GND                     
PC322            Q_CAPP_THLF-560UF,2.5V,20%,OSCA 1        PVCCIN_CPU0             
                                  2        GND                     
PC323            Q_CAPP_SMLF-470UF,2.5V,20%,EMPA 1        PVCCIN_CPU0             
                                  2        GND                     
PC324            Q_CAPP_THLF-270UF,16V,20%,OSCOA 1        SW_P12V_PVCCIN_CPU0_FLT 
                                  2        GND                     
PC325            Q_CAPP_THLF-560UF,2.5V,20%,OSCA 1        PVCCIN_CPU0             
                                  2        GND                     
PC326            Q_CAPP_SMLF-470UF,2.5V,20%,EMPA 1        PVCCIN_CPU0             
                                  2        GND                     
PC327            Q_CAP_C0603-10UF,4V,20%,EMPTY,A 1        PVNN_TERM_CPU0          
                                  2        GND                     
PC328            Q_CAP_C0402-100NF,50V,10%,X7R,A 1        PVNN_TERM_CPU0          
                                  2        GND                     
PC329            Q_CAP_0402-0.1UF,25V,10%,EMPTYA 1        PVCCIN_CPU0_CSPIN       
                                  2        GND                     
PC330            Q_CAP_0402-0.1UF,25V,10%,X7R,CA 1        PVCCIN_CPU0_VIN_CSNIN   
                                  2        GND                     
PC331            Q_CAP_0402-3300PF,50V,10%,X7R,A 1        SH_PVCCIN_CPU0_R        
                                  2        VSENSE_PVCCIN_CPU0_DN   
PC332            Q_CAP_0402-1000PF,50V,5%,X7R,TA 1        PVCCIN_CPU0_EN_R        
                                  2        GND                     
PC333            Q_CAP_0402-1000PF,50V,5%,EMPTYA 1        PWRGD_PVCCIN_CPU0_R     
                                  2        GND                     
PC334            Q_CAP_C0402-100NF,50V,10%,EMPTA 1        PVCCIN_CPU0_VCC         
                                  2        GND                     
PC335            Q_CAP_0402-4.7UF,6.3V,20%,X6S,A 1        PVCCIN_CPU0_VREF        
                                  2        GND                     
PC336            Q_CAP_0402-470PF,50V,10%,X7R,TA 1        PVCCIN_CPU0_ATSEN       
                                  2        GND                     
PC337            Q_CAP_C0402-1UF,16V,10%,X6S,CHA 1        PVCCIN_CPU0_VCC         
                                  2        GND                     
PC373            Q_CAP_C0402-2.2UF,10V,10%,X6S,A 1        PVCCD_HV_CPU1_VDD1      
                                  2        GND                     
PC374            Q_CAP_0402-3300PF,50V,10%,X7R,A 1        SW_P12V_PVCCINFAON_CPU1_FLT
                                  2        GND                     
PC375            Q_CAP_C0402-1UF,16V,10%,X6S,CHA 1        SW_P12V_PVCCINFAON_CPU1_FLT
                                  2        GND                     
PC376            Q_CAP_C0402-100NF,50V,10%,X7R,A 1        SW_PVCCD_HV_CPU1_BOOT1_R
                                  2        SW_PVCCD_HV_CPU1_BOOTR1 
PC377            Q_CAP_C0805-22UF,16V,20%,X6S,CA 1        SW_P12V_PVCCINFAON_CPU1_FLT
                                  2        GND                     
PC378            Q_CAP_C0805-22UF,16V,20%,X6S,CA 1        SW_P12V_PVCCINFAON_CPU1_FLT
                                  2        GND                     
PC379            Q_CAP_C0402-100NF,50V,10%,X7R,A 1        PVCCD_HV_CPU1           
                                  2        GND                     
PC381            Q_CAP_0805-22UF,4V,20%,X6S,TMPA 1        PVCCD_HV_CPU1           
                                  2        GND                     
PC382            Q_CAP_0805-22UF,4V,20%,X6S,TMPA 1        PVCCD_HV_CPU1           
                                  2        GND                     
PC384            Q_CAPP_THLF-560UF,2.5V,20%,OSCA 1        PVCCD_HV_CPU1           
                                  2        GND                     
PC385            Q_CAPP_THLF-560UF,2.5V,20%,OSCA 1        PVCCD_HV_CPU1           
                                  2        GND                     
PC386            Q_CAP_0402-0.1UF,25V,10%,X7R,CA 1        PVCCD_HV_CPU1_ISENSE_P  
                                  2        GND                     
PC388            Q_CAP_0402-1000PF,50V,5%,EMPTYA 1        PWRGD_PVCCD_HV_CPU1_R   
                                  2        GND                     
PC389            Q_CAP_0402-3300PF,50V,10%,X7R,A 1        SH_PVCCD_HV_CPU1_R      
                                  2        VSENSE_PVCCD_HV_CPU1_DN 
PC390            Q_CAP_0402-0.1UF,25V,10%,X7R,CA 1        PVCCD_HV_CPU1_ISENSE_N  
                                  2        GND                     
PC391            Q_CAP_C0402-100NF,50V,10%,EMPTA 1        PVCCD_HV_CPU1_VCC       
                                  2        GND                     
PC392            Q_CAP_0402-4.7UF,6.3V,20%,X6S,A 1        PVCCD_HV_CPU1_VREF      
                                  2        GND                     
PC393            Q_CAP_0402-470PF,50V,10%,X7R,TA 1        PVCCD_HV_CPU1_ATSEN     
                                  2        GND                     
PC394            Q_CAP_C0402-1UF,16V,10%,X6S,CHA 1        PVCCD_HV_CPU1_VCC       
                                  2        GND                     
PC395            Q_CAP_C0402-2.2UF,10V,10%,X6S,A 1        PVCCFA_EHV_FIVRA_CPU1_VDD1
                                  2        GND                     
PC396            Q_CAP_C0402-2.2UF,10V,10%,X6S,A 1        PVCCFA_EHV_FIVRA_CPU1_VDD2
                                  2        GND                     
PC397_P1_1       Q_CAP_0402-3300PF,50V,10%,X7R,A 1        SW_P12V_PVCCFA_EHV_FIVRA_CPU1_R
                                  2        GND                     
PC398_P1_2       Q_CAP_0402-3300PF,50V,10%,X7R,A 1        SW_P12V_PVCCFA_EHV_FIVRA_CPU1_L
                                  2        GND                     
PC399_P1_1       Q_CAP_C0402-1UF,16V,10%,X6S,CHA 1        SW_P12V_PVCCFA_EHV_FIVRA_CPU1_R
                                  2        GND                     
PC400_P1_2       Q_CAP_C0402-1UF,16V,10%,X6S,CHA 1        SW_P12V_PVCCFA_EHV_FIVRA_CPU1_L
                                  2        GND                     
PC401            Q_CAP_C0402-100NF,50V,10%,X7R,A 1        SW_PVCCFA_EHV_FIVRA_CPU1_BOOT1_
                                  2        SW_PVCCFA_EHV_FIVRA_CPU1_BOOTR1
PC402            Q_CAP_C0402-100NF,50V,10%,X7R,A 1        SW_PVCCFA_EHV_FIVRA_CPU1_BOOT2_
                                  2        SW_PVCCFA_EHV_FIVRA_CPU1_BOOTR2
PC403_P1_1       Q_CAP_C0805-22UF,16V,20%,X6S,CA 1        SW_P12V_PVCCFA_EHV_FIVRA_CPU1_R
                                  2        GND                     
PC404_P1_2       Q_CAP_C0805-22UF,16V,20%,X6S,CA 1        SW_P12V_PVCCFA_EHV_FIVRA_CPU1_L
                                  2        GND                     
PC405_P1_1       Q_CAP_C0805-22UF,16V,20%,X6S,CA 1        SW_P12V_PVCCFA_EHV_FIVRA_CPU1_R
                                  2        GND                     
PC406_P1_2       Q_CAP_C0805-22UF,16V,20%,X6S,CA 1        SW_P12V_PVCCFA_EHV_FIVRA_CPU1_L
                                  2        GND                     
PC408_P1_2       Q_CAP_C0402-1UF,16V,10%,X6S,CHA 1        PVCCFA_EHV_FIVRA_CPU1   
                                  2        GND                     
PC410_P1_1       Q_CAP_0805-22UF,4V,20%,X6S,TMPA 1        PVCCFA_EHV_FIVRA_CPU1   
                                  2        GND                     
PC411_P1_2       Q_CAP_0805-22UF,4V,20%,X6S,TMPA 1        PVCCFA_EHV_FIVRA_CPU1   
                                  2        GND                     
PC412_P1_1       Q_CAP_0805-22UF,4V,20%,X6S,TMPA 1        PVCCFA_EHV_FIVRA_CPU1   
                                  2        GND                     
PC413_P1_2       Q_CAP_0805-22UF,4V,20%,X6S,TMPA 1        PVCCFA_EHV_FIVRA_CPU1   
                                  2        GND                     
PC414            Q_CAPP_THLF-560UF,2.5V,20%,OSCA 1        PVCCFA_EHV_FIVRA_CPU1   
                                  2        GND                     
PC415            Q_CAPP_THLF-560UF,2.5V,20%,OSCA 1        PVCCFA_EHV_FIVRA_CPU1   
                                  2        GND                     
PC416            Q_CAPP_THLF-560UF,2.5V,20%,OSCA 1        PVCCFA_EHV_FIVRA_CPU1   
                                  2        GND                     
PC417            Q_CAPP_THLF-270UF,16V,20%,OSCOA 1        SW_P12V_PVCCFA_EHV_FIVRA_CPU1_L
                                  2        GND                     
PC418            Q_CAPP_SMLF-470UF,2.5V,20%,SPCA 1        PVCCFA_EHV_FIVRA_CPU1   
                                  2        GND                     
PC420            Q_CAP_0402-1000PF,50V,5%,X7R,TA 1        PVCCFA_EHV_FIVRA_CPU1_EN_R
                                  2        GND                     
PC421            Q_CAP_0402-1000PF,50V,5%,EMPTYA 1        PWRGD_PVCCFA_EHV_FIVRA_CPU1_R
                                  2        GND                     
PC422            Q_CAP_0402-3300PF,50V,10%,X7R,A 1        SH_PVCCFA_EHV_FIVRA_CPU1_R
                                  2        VSENSE_PVCCFA_EHV_FIVRA_CPU1_DN
PC428            Q_CAP_C0402-2.2UF,10V,10%,X6S,A 1        PVCCFA_EHV_CPU1_VDD1    
                                  2        GND                     
PC429            Q_CAP_0402-3300PF,50V,10%,X7R,A 1        SW_P12V_PVCCINFAON_CPU1_FLT
                                  2        GND                     
PC430            Q_CAP_C0402-1UF,16V,10%,X6S,CHA 1        SW_P12V_PVCCINFAON_CPU1_FLT
                                  2        GND                     
PC431            Q_CAP_C0402-100NF,50V,10%,X7R,A 1        SW_PVCCFA_EHV_CPU1_BOOT1_R
                                  2        SW_PVCCFA_EHV_CPU1_BOOTR1
PC432            Q_CAP_C0805-22UF,16V,20%,X6S,CA 1        SW_P12V_PVCCINFAON_CPU1_FLT
                                  2        GND                     
PC433            Q_CAP_C0805-22UF,16V,20%,X6S,CA 1        SW_P12V_PVCCINFAON_CPU1_FLT
                                  2        GND                     
PC434            Q_CAP_C0402-100NF,50V,10%,X7R,A 1        PVCCFA_EHV_CPU1         
                                  2        GND                     
PC435            Q_CAP_0805-22UF,4V,20%,X6S,TMPA 1        PVCCFA_EHV_CPU1         
                                  2        GND                     
PC437            Q_CAP_0805-22UF,4V,20%,X6S,TMPA 1        PVCCFA_EHV_CPU1         
                                  2        GND                     
PC440            Q_CAP_C0402-2.2UF,10V,10%,X6S,A 1        PVCCINFAON_CPU1_VDD1    
                                  2        GND                     
PC441            Q_CAP_C0402-2.2UF,10V,10%,X6S,A 1        PVCCINFAON_CPU1_VDD2    
                                  2        GND                     
PC442_P1_1       Q_CAP_0402-3300PF,50V,10%,X7R,A 1        SW_P12V_PVCCINFAON_CPU1_FLT
                                  2        GND                     
PC443_P1_2       Q_CAP_0402-3300PF,50V,10%,X7R,A 1        SW_P12V_PVCCINFAON_CPU1_FLT
                                  2        GND                     
PC444_P1_1       Q_CAP_C0402-1UF,16V,10%,X6S,CHA 1        SW_P12V_PVCCINFAON_CPU1_FLT
                                  2        GND                     
PC445_P1_2       Q_CAP_C0402-1UF,16V,10%,X6S,CHA 1        SW_P12V_PVCCINFAON_CPU1_FLT
                                  2        GND                     
PC446            Q_CAP_C0402-100NF,50V,10%,X7R,A 1        SW_PVCCINFAON_CPU1_BOOT1_R
                                  2        SW_PVCCINFAON_CPU1_BOOTR1
PC447            Q_CAP_C0402-100NF,50V,10%,X7R,A 1        SW_PVCCINFAON_CPU1_BOOT2_R
                                  2        SW_PVCCINFAON_CPU1_BOOTR2
PC448_P1_1       Q_CAP_C0805-22UF,16V,20%,X6S,CA 1        SW_P12V_PVCCINFAON_CPU1_FLT
                                  2        GND                     
PC449_P1_2       Q_CAP_C0805-22UF,16V,20%,X6S,CA 1        SW_P12V_PVCCINFAON_CPU1_FLT
                                  2        GND                     
PC450_P1_1       Q_CAP_C0805-22UF,16V,20%,X6S,CA 1        SW_P12V_PVCCINFAON_CPU1_FLT
                                  2        GND                     
PC451_P1_2       Q_CAP_C0805-22UF,16V,20%,X6S,CA 1        SW_P12V_PVCCINFAON_CPU1_FLT
                                  2        GND                     
PC452_P1_1       Q_CAP_C0402-100NF,50V,10%,X7R,A 1        PVCCINFAON_CPU1         
                                  2        GND                     
PC455_P1_1       Q_CAP_0805-22UF,4V,20%,X6S,TMPA 1        PVCCINFAON_CPU1         
                                  2        GND                     
PC456_P1_2       Q_CAP_0805-22UF,4V,20%,X6S,TMPA 1        PVCCINFAON_CPU1         
                                  2        GND                     
PC457_P1_1       Q_CAP_0805-22UF,4V,20%,X6S,TMPA 1        PVCCINFAON_CPU1         
                                  2        GND                     
PC458_P1_2       Q_CAP_0805-22UF,4V,20%,X6S,TMPA 1        PVCCINFAON_CPU1         
                                  2        GND                     
PC460            Q_CAPP_THLF-270UF,16V,20%,OSCOA 1        SW_P12V_PVCCINFAON_CPU1_FLT
                                  2        GND                     
PC461            Q_CAPP_THLF-270UF,16V,20%,OSCOA 1        SW_P12V_PVCCINFAON_CPU1_FLT
                                  2        GND                     
PC467            Q_CAP_0402-0.1UF,25V,10%,EMPTYA 1        PVCCINFAON_CPU1_CSPIN   
                                  2        GND                     
PC468            Q_CAP_0402-3300PF,50V,10%,X7R,A 1        SH_PVCCINFAON_CPU1_R    
                                  2        VSENSE_PVCCINFAON_CPU1_DN
PC469            Q_CAP_0402-3300PF,50V,10%,X7R,A 1        SH_PVCCFA_EHV_CPU1_R    
                                  2        VSENSE_PVCCFA_EHV_CPU1_DN
PC470            Q_CAP_0402-1000PF,50V,5%,X7R,TA 1        PVCCINFAON_CPU1_EN_R    
                                  2        GND                     
PC471            Q_CAP_0402-1000PF,50V,5%,EMPTYA 1        PWRGD_PVCCINFAON_CPU1_R 
                                  2        GND                     
PC472            Q_CAP_0402-1000PF,50V,5%,X7R,TA 1        PVCCFA_EHV_CPU1_EN_R    
                                  2        GND                     
PC473            Q_CAP_0402-1000PF,50V,5%,EMPTYA 1        PWRGD_PVCCFA_EHV_CPU1_R 
                                  2        GND                     
PC474            Q_CAP_0402-0.1UF,25V,10%,X7R,CA 1        PVCCINFAON_CPU1_VIN_CSNIN
                                  2        GND                     
PC475            Q_CAP_0402-470PF,50V,10%,X7R,TA 1        PVCCINFAON_CPU1_ATSEN   
                                  2        GND                     
PC476            Q_CAP_C0402-100NF,50V,10%,EMPTA 1        PVCCINFAON_CPU1_VCC     
                                  2        GND                     
PC477            Q_CAP_0402-4.7UF,6.3V,20%,X6S,A 1        PVCCINFAON_CPU1_VREF    
                                  2        GND                     
PC478            Q_CAP_C0402-1UF,16V,10%,X6S,CHA 1        PVCCINFAON_CPU1_VCC     
                                  2        GND                     
PC479            Q_CAP_C0402-2.2UF,10V,10%,X6S,A 1        PVCCIN_CPU1_VDD8        
                                  2        GND                     
PC480            Q_CAP_C0402-2.2UF,10V,10%,X6S,A 1        PVCCIN_CPU1_VDD7        
                                  2        GND                     
PC481_P1_8       Q_CAP_C0402-2.2UF,10V,10%,X6S,A 1        PVCCIN_CPU1_PVCC        
                                  2        GND                     
PC482_P1_7       Q_CAP_C0402-2.2UF,10V,10%,X6S,A 1        PVCCIN_CPU1_PVCC        
                                  2        GND                     
PC483_P1_8       Q_CAP_0402-3300PF,50V,10%,X7R,A 1        SW_P12V_PVCCIN_CPU1_FLT 
                                  2        GND                     
PC484_P1_7       Q_CAP_0402-3300PF,50V,10%,X7R,A 1        SW_P12V_PVCCIN_CPU1_FLT 
                                  2        GND                     
PC485_P1_8       Q_CAP_C0402-1UF,16V,10%,X6S,CHA 1        SW_P12V_PVCCIN_CPU1_FLT 
                                  2        GND                     
PC486_P1_7       Q_CAP_C0402-1UF,16V,10%,X6S,CHA 1        SW_P12V_PVCCIN_CPU1_FLT 
                                  2        GND                     
PC487            Q_CAP_C0402-100NF,50V,10%,X7R,A 1        SW_PVCCIN_CPU1_BOOT8_R  
                                  2        SW_PVCCIN_CPU1_BOOTR8   
PC488            Q_CAP_C0402-100NF,50V,10%,X7R,A 1        SW_PVCCIN_CPU1_BOOT7_R  
                                  2        SW_PVCCIN_CPU1_BOOTR7   
PC489_P1_8       Q_CAP_C0805-22UF,16V,20%,X6S,CA 1        SW_P12V_PVCCIN_CPU1_FLT 
                                  2        GND                     
PC490_P1_7       Q_CAP_C0805-22UF,16V,20%,X6S,CA 1        SW_P12V_PVCCIN_CPU1_FLT 
                                  2        GND                     
PC491_P1_8       Q_CAP_C0805-22UF,16V,20%,X6S,CA 1        SW_P12V_PVCCIN_CPU1_FLT 
                                  2        GND                     
PC492_P1_7       Q_CAP_C0805-22UF,16V,20%,X6S,CA 1        SW_P12V_PVCCIN_CPU1_FLT 
                                  2        GND                     
PC493_P1_8       Q_CAP_C0805-22UF,16V,20%,X6S,CA 1        SW_P12V_PVCCIN_CPU1_FLT 
                                  2        GND                     
PC494_P1_7       Q_CAP_C0805-22UF,16V,20%,X6S,CA 1        SW_P12V_PVCCIN_CPU1_FLT 
                                  2        GND                     
PC495_P1_8       Q_CAP_C0402-1UF,16V,10%,X6S,CHA 1        PVCCIN_CPU1             
                                  2        GND                     
PC496_P1_7       Q_CAP_C0402-1UF,16V,10%,X6S,CHA 1        PVCCIN_CPU1             
                                  2        GND                     
PC497_P1_8       Q_CAP_0805-22UF,4V,20%,X6S,TMPA 1        PVCCIN_CPU1             
                                  2        GND                     
PC498_P1_7       Q_CAP_0805-22UF,4V,20%,X6S,TMPA 1        PVCCIN_CPU1             
                                  2        GND                     
PC499_P1_8       Q_CAP_0805-22UF,4V,20%,X6S,TMPA 1        PVCCIN_CPU1             
                                  2        GND                     
PC500_P1_7       Q_CAP_0805-22UF,4V,20%,X6S,TMPA 1        PVCCIN_CPU1             
                                  2        GND                     
PC501            Q_CAP_C0402-2.2UF,10V,10%,X6S,A 1        PVCCIN_CPU1_VDD6        
                                  2        GND                     
PC502            Q_CAP_C0402-2.2UF,10V,10%,X6S,A 1        PVCCIN_CPU1_VDD5        
                                  2        GND                     
PC503_P1_6       Q_CAP_C0402-2.2UF,10V,10%,X6S,A 1        PVCCIN_CPU1_PVCC        
                                  2        GND                     
PC504_P1_5       Q_CAP_C0402-2.2UF,10V,10%,X6S,A 1        PVCCIN_CPU1_PVCC        
                                  2        GND                     
PC505_P1_6       Q_CAP_0402-3300PF,50V,10%,X7R,A 1        SW_P12V_PVCCIN_CPU1_FLT 
                                  2        GND                     
PC506_P1_5       Q_CAP_0402-3300PF,50V,10%,X7R,A 1        SW_P12V_PVCCIN_CPU1_FLT 
                                  2        GND                     
PC507_P1_6       Q_CAP_C0402-1UF,16V,10%,X6S,CHA 1        SW_P12V_PVCCIN_CPU1_FLT 
                                  2        GND                     
PC508_P1_5       Q_CAP_C0402-1UF,16V,10%,X6S,CHA 1        SW_P12V_PVCCIN_CPU1_FLT 
                                  2        GND                     
PC509            Q_CAP_C0402-100NF,50V,10%,X7R,A 1        SW_PVCCIN_CPU1_BOOT6_R  
                                  2        SW_PVCCIN_CPU1_BOOTR6   
PC510            Q_CAP_C0402-100NF,50V,10%,X7R,A 1        SW_PVCCIN_CPU1_BOOT5_R  
                                  2        SW_PVCCIN_CPU1_BOOTR5   
PC511_P1_6       Q_CAP_C0805-22UF,16V,20%,X6S,CA 1        SW_P12V_PVCCIN_CPU1_FLT 
                                  2        GND                     
PC512_P1_5       Q_CAP_C0805-22UF,16V,20%,X6S,CA 1        SW_P12V_PVCCIN_CPU1_FLT 
                                  2        GND                     
PC513_P1_6       Q_CAP_C0805-22UF,16V,20%,X6S,CA 1        SW_P12V_PVCCIN_CPU1_FLT 
                                  2        GND                     
PC514_P1_5       Q_CAP_C0805-22UF,16V,20%,X6S,CA 1        SW_P12V_PVCCIN_CPU1_FLT 
                                  2        GND                     
PC515_P1_6       Q_CAP_C0805-22UF,16V,20%,X6S,CA 1        SW_P12V_PVCCIN_CPU1_FLT 
                                  2        GND                     
PC516_P1_5       Q_CAP_C0805-22UF,16V,20%,X6S,CA 1        SW_P12V_PVCCIN_CPU1_FLT 
                                  2        GND                     
PC519_P1_6       Q_CAP_0805-22UF,4V,20%,X6S,TMPA 1        PVCCIN_CPU1             
                                  2        GND                     
PC520_P1_5       Q_CAP_0805-22UF,4V,20%,X6S,TMPA 1        PVCCIN_CPU1             
                                  2        GND                     
PC521_P1_6       Q_CAP_0805-22UF,4V,20%,X6S,TMPA 1        PVCCIN_CPU1             
                                  2        GND                     
PC522_P1_5       Q_CAP_0805-22UF,4V,20%,X6S,TMPA 1        PVCCIN_CPU1             
                                  2        GND                     
PC523            Q_CAP_C0402-2.2UF,10V,10%,X6S,A 1        PVCCIN_CPU1_VDD4        
                                  2        GND                     
PC524            Q_CAP_C0402-2.2UF,10V,10%,X6S,A 1        PVCCIN_CPU1_VDD3        
                                  2        GND                     
PC525_P1_4       Q_CAP_C0402-2.2UF,10V,10%,X6S,A 1        PVCCIN_CPU1_PVCC        
                                  2        GND                     
PC526_P1_3       Q_CAP_C0402-2.2UF,10V,10%,X6S,A 1        PVCCIN_CPU1_PVCC        
                                  2        GND                     
PC527_P1_4       Q_CAP_0402-3300PF,50V,10%,X7R,A 1        SW_P12V_PVCCIN_CPU1_FLT 
                                  2        GND                     
PC528_P1_3       Q_CAP_0402-3300PF,50V,10%,X7R,A 1        SW_P12V_PVCCIN_CPU1_FLT 
                                  2        GND                     
PC529_P1_4       Q_CAP_C0402-1UF,16V,10%,X6S,CHA 1        SW_P12V_PVCCIN_CPU1_FLT 
                                  2        GND                     
PC530_P1_3       Q_CAP_C0402-1UF,16V,10%,X6S,CHA 1        SW_P12V_PVCCIN_CPU1_FLT 
                                  2        GND                     
PC531            Q_CAP_C0402-100NF,50V,10%,X7R,A 1        SW_PVCCIN_CPU1_BOOT4_R  
                                  2        SW_PVCCIN_CPU1_BOOTR4   
PC532            Q_CAP_C0402-100NF,50V,10%,X7R,A 1        SW_PVCCIN_CPU1_BOOT3_R  
                                  2        SW_PVCCIN_CPU1_BOOTR3   
PC533_P1_4       Q_CAP_C0805-22UF,16V,20%,X6S,CA 1        SW_P12V_PVCCIN_CPU1_FLT 
                                  2        GND                     
PC534_P1_3       Q_CAP_C0805-22UF,16V,20%,X6S,CA 1        SW_P12V_PVCCIN_CPU1_FLT 
                                  2        GND                     
PC535_P1_4       Q_CAP_C0805-22UF,16V,20%,X6S,CA 1        SW_P12V_PVCCIN_CPU1_FLT 
                                  2        GND                     
PC536_P1_3       Q_CAP_C0805-22UF,16V,20%,X6S,CA 1        SW_P12V_PVCCIN_CPU1_FLT 
                                  2        GND                     
PC537_P1_4       Q_CAP_C0805-22UF,16V,20%,X6S,CA 1        SW_P12V_PVCCIN_CPU1_FLT 
                                  2        GND                     
PC538_P1_3       Q_CAP_C0805-22UF,16V,20%,X6S,CA 1        SW_P12V_PVCCIN_CPU1_FLT 
                                  2        GND                     
PC541_P1_4       Q_CAP_0805-22UF,4V,20%,X6S,TMPA 1        PVCCIN_CPU1             
                                  2        GND                     
PC542_P1_3       Q_CAP_0805-22UF,4V,20%,X6S,TMPA 1        PVCCIN_CPU1             
                                  2        GND                     
PC543_P1_4       Q_CAP_0805-22UF,4V,20%,X6S,TMPA 1        PVCCIN_CPU1             
                                  2        GND                     
PC544_P1_3       Q_CAP_0805-22UF,4V,20%,X6S,TMPA 1        PVCCIN_CPU1             
                                  2        GND                     
PC545            Q_CAP_C0603-10UF,4V,20%,EMPTY,A 1        PVNN_TERM_CPU1          
                                  2        GND                     
PC546            Q_CAP_C0402-100NF,50V,10%,X7R,A 1        PVNN_TERM_CPU1          
                                  2        GND                     
PC547            Q_CAP_0402-0.1UF,25V,10%,EMPTYA 1        PVCCIN_CPU1_CSPIN       
                                  2        GND                     
PC548            Q_CAP_0402-0.1UF,25V,10%,X7R,CA 1        PVCCIN_CPU1_VIN_CSNIN   
                                  2        GND                     
PC549            Q_CAP_0402-3300PF,50V,10%,X7R,A 1        SH_PVCCIN_CPU1_R        
                                  2        VSENSE_PVCCIN_CPU1_DN   
PC550            Q_CAP_0402-1000PF,50V,5%,X7R,TA 1        PVCCIN_CPU1_EN_R        
                                  2        GND                     
PC551            Q_CAP_0402-1000PF,50V,5%,EMPTYA 1        PWRGD_PVCCIN_CPU1_R     
                                  2        GND                     
PC552            Q_CAP_C0402-100NF,50V,10%,EMPTA 1        PVCCIN_CPU1_VCC         
                                  2        GND                     
PC553            Q_CAP_0402-4.7UF,6.3V,20%,X6S,A 1        PVCCIN_CPU1_VREF        
                                  2        GND                     
PC554            Q_CAP_0402-470PF,50V,10%,X7R,TA 1        PVCCIN_CPU1_ATSEN       
                                  2        GND                     
PC555            Q_CAP_C0402-1UF,16V,10%,X6S,CHA 1        PVCCIN_CPU1_VCC         
                                  2        GND                     
PC556            Q_CAP_C0402-2.2UF,10V,10%,X6S,A 1        PVCCIN_CPU1_VDD2        
                                  2        GND                     
PC557            Q_CAP_C0402-2.2UF,10V,10%,X6S,A 1        PVCCIN_CPU1_VDD1        
                                  2        GND                     
PC558_P1_2       Q_CAP_C0402-2.2UF,10V,10%,X6S,A 1        PVCCIN_CPU1_PVCC        
                                  2        GND                     
PC559_P1_1       Q_CAP_C0402-2.2UF,10V,10%,X6S,A 1        PVCCIN_CPU1_PVCC        
                                  2        GND                     
PC560_P1_2       Q_CAP_0402-3300PF,50V,10%,X7R,A 1        SW_P12V_PVCCIN_CPU1_FLT 
                                  2        GND                     
PC561_P1_1       Q_CAP_0402-3300PF,50V,10%,X7R,A 1        SW_P12V_PVCCIN_CPU1_FLT 
                                  2        GND                     
PC562_P1_2       Q_CAP_C0402-1UF,16V,10%,X6S,CHA 1        SW_P12V_PVCCIN_CPU1_FLT 
                                  2        GND                     
PC563_P1_1       Q_CAP_C0402-1UF,16V,10%,X6S,CHA 1        SW_P12V_PVCCIN_CPU1_FLT 
                                  2        GND                     
PC564            Q_CAP_C0402-100NF,50V,10%,X7R,A 1        SW_PVCCIN_CPU1_BOOT2_R  
                                  2        SW_PVCCIN_CPU1_BOOTR2   
PC565            Q_CAP_C0402-100NF,50V,10%,X7R,A 1        SW_PVCCIN_CPU1_BOOT1_R  
                                  2        SW_PVCCIN_CPU1_BOOTR1   
PC566            Q_CAPP_SMLF-100UF,16V,20%,OSCOA 1        SW_P3V3_AUX_FLT         
                                  2        GND                     
PC566_P1_2       Q_CAP_C0805-22UF,16V,20%,X6S,CA 1        SW_P12V_PVCCIN_CPU1_FLT 
                                  2        GND                     
PC567            Q_CAP_C0805-22UF,16V,20%,X6S,CA 1        SW_P3V3_AUX_FLT         
                                  2        GND                     
PC567_P1_1       Q_CAP_C0805-22UF,16V,20%,X6S,CA 1        SW_P12V_PVCCIN_CPU1_FLT 
                                  2        GND                     
PC568            Q_CAP_0402-0.22UF,16V,10%,X7R,A 1        SW_P3V3_AUX_BOOTR       
                                  2        SW_P3V3_AUX_BOOT_R      
PC568_P1_2       Q_CAP_C0805-22UF,16V,20%,X6S,CA 1        SW_P12V_PVCCIN_CPU1_FLT 
                                  2        GND                     
PC569            Q_CAP_0402-10PF,50V,1%,NPO,TMPA 1        P3V3_AUX_FB             
                                  2        P3V3_AUX                
PC569_P1_1       Q_CAP_C0805-22UF,16V,20%,X6S,CA 1        SW_P12V_PVCCIN_CPU1_FLT 
                                  2        GND                     
PC570            Q_CAP_C0805-22UF,16V,20%,X6S,CA 1        SW_P3V3_AUX_FLT         
                                  2        GND                     
PC570_P1_2       Q_CAP_C0805-22UF,16V,20%,X6S,CA 1        SW_P12V_PVCCIN_CPU1_FLT 
                                  2        GND                     
PC571            Q_CAP_C0805-22UF,16V,20%,X6S,CA 1        SW_P3V3_AUX_FLT         
                                  2        GND                     
PC571_P1_1       Q_CAP_C0805-22UF,16V,20%,X6S,CA 1        SW_P12V_PVCCIN_CPU1_FLT 
                                  2        GND                     
PC572_P1_1       Q_CAP_C0402-100NF,50V,10%,X7R,A 1        PVCCIN_CPU1             
                                  2        GND                     
PC574_P1_1       Q_CAP_C0402-1UF,16V,10%,X6S,CHA 1        PVCCIN_CPU1             
                                  2        GND                     
PC575_P1_2       Q_CAP_0805-22UF,4V,20%,X6S,TMPA 1        PVCCIN_CPU1             
                                  2        GND                     
PC576            Q_CAP_C0805-22UF,16V,20%,X6S,CA 1        SW_P3V3_AUX_FLT         
                                  2        GND                     
PC576_P1_1       Q_CAP_0805-22UF,4V,20%,X6S,TMPA 1        PVCCIN_CPU1             
                                  2        GND                     
PC577            Q_CAP_0402-0.1UF,25V,10%,X7R,CA 1        SW_P3V3_AUX_FLT         
                                  2        GND                     
PC577_P1_2       Q_CAP_0805-22UF,4V,20%,X6S,TMPA 1        PVCCIN_CPU1             
                                  2        GND                     
PC578_P1_1       Q_CAP_0805-22UF,4V,20%,X6S,TMPA 1        PVCCIN_CPU1             
                                  2        GND                     
PC579            Q_CAPP_THLF-270UF,16V,20%,OSCOA 1        SW_P12V_PVCCIN_CPU1_FLT 
                                  2        GND                     
PC580            Q_CAPP_THLF-560UF,2.5V,20%,OSCA 1        PVCCIN_CPU1             
                                  2        GND                     
PC581            Q_CAP_C0603-4.7UF,16V,10%,X6S,A 1        P5V_AUX                 
                                  2        GND                     
PC582            Q_CAPP_THLF-270UF,16V,20%,OSCOA 1        SW_P12V_PVCCIN_CPU1_FLT 
                                  2        GND                     
PC583            Q_CAPP_THLF-560UF,2.5V,20%,OSCA 1        PVCCIN_CPU1             
                                  2        GND                     
PC585            Q_CAPP_THLF-270UF,16V,20%,OSCOA 1        SW_P12V_PVCCIN_CPU1_FLT 
                                  2        GND                     
PC586            Q_CAPP_THLF-560UF,2.5V,20%,OSCA 1        PVCCIN_CPU1             
                                  2        GND                     
PC587            Q_CAPP_SMLF-470UF,2.5V,20%,EMPA 1        PVCCIN_CPU1             
                                  2        GND                     
PC588            Q_CAPP_THLF-270UF,16V,20%,OSCOA 1        SW_P12V_PVCCIN_CPU1_FLT 
                                  2        GND                     
PC589            Q_CAPP_THLF-560UF,2.5V,20%,OSCA 1        PVCCIN_CPU1             
                                  2        GND                     
PC590            Q_CAPP_SMLF-470UF,2.5V,20%,EMPA 1        PVCCIN_CPU1             
                                  2        GND                     
PC591            Q_CAP_C0603-2.2UF,16V,10%,X6S,A 1        P3V3_AUX_VCC            
                                  2        GND                     
PC592            Q_CAP_0402-1000PF,50V,5%,X7R,TA 1        PVCCFA_EHV_FIVRA_CPU0_EN_R
                                  2        GND                     
PC593            Q_CAP_0402-1000PF,50V,5%,EMPTYA 1        PWRGD_PVCCFA_EHV_FIVRA_CPU0_R
                                  2        GND                     
PC594            Q_CAP_0402-3300PF,50V,10%,X7R,A 1        SH_PVCCFA_EHV_FIVRA_CPU0_R
                                  2        VSENSE_PVCCFA_EHV_FIVRA_CPU0_DN
PC600            Q_CAP_C0402-2.2UF,10V,10%,X6S,A 1        PVCCFA_EHV_FIVRA_CPU0_VDD1
                                  2        GND                     
PC601            Q_CAP_C0402-2.2UF,10V,10%,X6S,A 1        PVCCFA_EHV_FIVRA_CPU0_VDD2
                                  2        GND                     
PC602_P0_1       Q_CAP_0402-3300PF,50V,10%,X7R,A 1        SW_P12V_PVCCFA_EHV_FIVRA_CPU0_R
                                  2        GND                     
PC603_P0_2       Q_CAP_0402-3300PF,50V,10%,X7R,A 1        SW_P12V_PVCCFA_EHV_FIVRA_CPU0_L
                                  2        GND                     
PC604_P0_1       Q_CAP_C0402-1UF,16V,10%,X6S,CHA 1        SW_P12V_PVCCFA_EHV_FIVRA_CPU0_R
                                  2        GND                     
PC605_P0_2       Q_CAP_C0402-1UF,16V,10%,X6S,CHA 1        SW_P12V_PVCCFA_EHV_FIVRA_CPU0_L
                                  2        GND                     
PC606            Q_CAP_C0402-100NF,50V,10%,X7R,A 1        SW_PVCCFA_EHV_FIVRA_CPU0_BOOT1_
                                  2        SW_PVCCFA_EHV_FIVRA_CPU0_BOOTR1
PC607            Q_CAP_C0402-100NF,50V,10%,X7R,A 1        SW_PVCCFA_EHV_FIVRA_CPU0_BOOT2_
                                  2        SW_PVCCFA_EHV_FIVRA_CPU0_BOOTR2
PC608_P0_1       Q_CAP_C0805-22UF,16V,20%,X6S,CA 1        SW_P12V_PVCCFA_EHV_FIVRA_CPU0_R
                                  2        GND                     
PC609_P0_2       Q_CAP_C0805-22UF,16V,20%,X6S,CA 1        SW_P12V_PVCCFA_EHV_FIVRA_CPU0_L
                                  2        GND                     
PC610_P0_1       Q_CAP_C0805-22UF,16V,20%,X6S,CA 1        SW_P12V_PVCCFA_EHV_FIVRA_CPU0_R
                                  2        GND                     
PC611_P0_2       Q_CAP_C0805-22UF,16V,20%,X6S,CA 1        SW_P12V_PVCCFA_EHV_FIVRA_CPU0_L
                                  2        GND                     
PC612_P0_1       Q_CAP_C0402-100NF,50V,10%,X7R,A 1        PVCCFA_EHV_FIVRA_CPU0   
                                  2        GND                     
PC613_P0_2       Q_CAP_C0402-1UF,16V,10%,X6S,CHA 1        PVCCFA_EHV_FIVRA_CPU0   
                                  2        GND                     
PC615_P0_1       Q_CAP_0805-22UF,4V,20%,X6S,TMPA 1        PVCCFA_EHV_FIVRA_CPU0   
                                  2        GND                     
PC616_P0_2       Q_CAP_0805-22UF,4V,20%,X6S,TMPA 1        PVCCFA_EHV_FIVRA_CPU0   
                                  2        GND                     
PC617_P0_1       Q_CAP_0805-22UF,4V,20%,X6S,TMPA 1        PVCCFA_EHV_FIVRA_CPU0   
                                  2        GND                     
PC618_P0_2       Q_CAP_0805-22UF,4V,20%,X6S,TMPA 1        PVCCFA_EHV_FIVRA_CPU0   
                                  2        GND                     
PC619            Q_CAPP_THLF-560UF,2.5V,20%,OSCA 1        PVCCFA_EHV_FIVRA_CPU0   
                                  2        GND                     
PC620            Q_CAPP_THLF-560UF,2.5V,20%,OSCA 1        PVCCFA_EHV_FIVRA_CPU0   
                                  2        GND                     
PC621            Q_CAPP_THLF-560UF,2.5V,20%,EMPA 1        PVCCFA_EHV_FIVRA_CPU0   
                                  2        GND                     
PC621_P1_1       Q_CAP_C0402-100NF,50V,10%,X7R,A 1        PVCCFA_EHV_FIVRA_CPU1   
                                  2        GND                     
PC622            Q_CAPP_THLF-270UF,16V,20%,OSCOA 1        SW_P12V_PVCCFA_EHV_FIVRA_CPU0_L
                                  2        GND                     
PC623            Q_CAPP_SMLF-470UF,2.5V,20%,EMPA 1        PVCCFA_EHV_FIVRA_CPU0   
                                  2        GND                     
PC624            Q_CAP_0402-0.1UF,25V,10%,X7R,CA 1        PVCCD_HV_CPU0_ISENSE_P  
                                  2        GND                     
PC626            Q_CAP_0402-1000PF,50V,5%,EMPTYA 1        PWRGD_PVCCD_HV_CPU0_R   
                                  2        GND                     
PC627            Q_CAP_0402-3300PF,50V,10%,X7R,A 1        SH_PVCCD_HV_CPU0_R      
                                  2        VSENSE_PVCCD_HV_CPU0_DN 
PC628            Q_CAP_0402-0.1UF,25V,10%,X7R,CA 1        PVCCD_HV_CPU0_ISENSE_N  
                                  2        GND                     
PC629            Q_CAP_C0402-100NF,50V,10%,EMPTA 1        PVCCD_HV_CPU0_VCC       
                                  2        GND                     
PC630            Q_CAP_0402-4.7UF,6.3V,20%,X6S,A 1        PVCCD_HV_CPU0_VREF      
                                  2        GND                     
PC631            Q_CAP_0402-470PF,50V,10%,X7R,TA 1        PVCCD_HV_CPU0_ATSEN     
                                  2        GND                     
PC632            Q_CAP_C0402-1UF,16V,10%,X6S,CHA 1        PVCCD_HV_CPU0_VCC       
                                  2        GND                     
PC633            Q_CAP_C0402-2.2UF,10V,10%,X6S,A 1        PVCCD_HV_CPU0_VDD1      
                                  2        GND                     
PC634            Q_CAP_0402-3300PF,50V,10%,X7R,A 1        SW_P12V_PVCCINFAON_CPU0_FLT
                                  2        GND                     
PC635            Q_CAP_C0402-1UF,16V,10%,X6S,CHA 1        SW_P12V_PVCCINFAON_CPU0_FLT
                                  2        GND                     
PC636            Q_CAP_C0402-100NF,50V,10%,X7R,A 1        SW_PVCCD_HV_CPU0_BOOT1_R
                                  2        SW_PVCCD_HV_CPU0_BOOTR1 
PC637            Q_CAP_C0805-22UF,16V,20%,X6S,CA 1        SW_P12V_PVCCINFAON_CPU0_FLT
                                  2        GND                     
PC638            Q_CAP_C0805-22UF,16V,20%,X6S,CA 1        SW_P12V_PVCCINFAON_CPU0_FLT
                                  2        GND                     
PC639            Q_CAP_C0402-100NF,50V,10%,X7R,A 1        PVCCD_HV_CPU0           
                                  2        GND                     
PC641            Q_CAP_0805-22UF,4V,20%,X6S,TMPA 1        PVCCD_HV_CPU0           
                                  2        GND                     
PC642            Q_CAP_0805-22UF,4V,20%,X6S,TMPA 1        PVCCD_HV_CPU0           
                                  2        GND                     
PC644            Q_CAP_C0402-1UF,25V,10%,X6S,CHA 1        PVPP_HBM_CPU1_VCC       
                                  2        GND                     
PC720_P0_1       Q_CAP_C0805-22UF,16V,20%,X6S,CA 1        SW_P12V_PVCCFA_EHV_FIVRA_CPU0_R
                                  2        GND                     
PC721_P0_2       Q_CAP_C0805-22UF,16V,20%,X6S,CA 1        SW_P12V_PVCCFA_EHV_FIVRA_CPU0_L
                                  2        GND                     
PC722_P0_3       Q_CAP_C0805-22UF,16V,20%,EMPTYA 1        SW_P12V_PVCCFA_EHV_FIVRA_CPU0_R
                                  2        GND                     
PC723_P0_4       Q_CAP_C0805-22UF,16V,20%,EMPTYA 1        SW_P12V_PVCCFA_EHV_FIVRA_CPU0_L
                                  2        GND                     
PC724_P1_1       Q_CAP_C0805-22UF,16V,20%,X6S,CA 1        SW_P12V_PVCCFA_EHV_FIVRA_CPU1_R
                                  2        GND                     
PC725_P1_2       Q_CAP_C0805-22UF,16V,20%,X6S,CA 1        SW_P12V_PVCCFA_EHV_FIVRA_CPU1_L
                                  2        GND                     
PC726_P1_3       Q_CAP_C0805-22UF,16V,20%,X6S,CA 1        SW_P12V_PVCCFA_EHV_FIVRA_CPU1_R
                                  2        GND                     
PC727_P1_4       Q_CAP_C0805-22UF,16V,20%,X6S,CA 1        SW_P12V_PVCCFA_EHV_FIVRA_CPU1_L
                                  2        GND                     
PC813            Q_CAP_C0402-1UF,16V,10%,X6S,CHA 1        PVCCD_HV_CPU0_ISENSE_N  
                                  2        PVCCD_HV_CPU0_ISENSE_P  
PC814            Q_CAP_C0402-1UF,16V,10%,X6S,CHA 1        PVCCD_HV_CPU1_ISENSE_N  
                                  2        PVCCD_HV_CPU1_ISENSE_P  
PC831            Q_CAP_C0805-22UF,16V,20%,EMPTYA 1        SW_P12V_PVCCIN_CPU0_FLT 
                                  2        GND                     
PC1171           Q_CAP_C0402-2.2UF,10V,10%,EMPTA 1        PVCCFA_EHV_FIVRA_CPU0_VDD3
                                  2        GND                     
PC1172           Q_CAP_C0402-2.2UF,10V,10%,EMPTA 1        PVCCFA_EHV_FIVRA_CPU0_VDD4
                                  2        GND                     
PC1173           Q_CAP_C0402-1UF,16V,10%,X6S,CHA 1        PVCCIN_CPU0_VREF        
                                  2        GND                     
PC1173_P0_3      Q_CAP_0402-3300PF,50V,10%,EMPTA 1        SW_P12V_PVCCFA_EHV_FIVRA_CPU0_R
                                  2        GND                     
PC1174_P0_4      Q_CAP_0402-3300PF,50V,10%,EMPTA 1        SW_P12V_PVCCFA_EHV_FIVRA_CPU0_L
                                  2        GND                     
PC1175_P0_3      Q_CAP_C0402-1UF,16V,10%,EMPTY,A 1        SW_P12V_PVCCFA_EHV_FIVRA_CPU0_R
                                  2        GND                     
PC1176_P0_4      Q_CAP_C0402-1UF,16V,10%,EMPTY,A 1        SW_P12V_PVCCFA_EHV_FIVRA_CPU0_L
                                  2        GND                     
PC1177           Q_CAP_C0402-100NF,50V,10%,EMPTA 1        SW_PVCCFA_EHV_FIVRA_CPU0_BOOT3_
                                  2        SW_PVCCFA_EHV_FIVRA_CPU0_BOOTR3
PC1178           Q_CAP_C0402-100NF,50V,10%,EMPTA 1        SW_PVCCFA_EHV_FIVRA_CPU0_BOOT4_
                                  2        SW_PVCCFA_EHV_FIVRA_CPU0_BOOTR4
PC1179_P0_3      Q_CAP_C0805-22UF,16V,20%,EMPTYA 1        SW_P12V_PVCCFA_EHV_FIVRA_CPU0_R
                                  2        GND                     
PC1180_P0_4      Q_CAP_C0805-22UF,16V,20%,EMPTYA 1        SW_P12V_PVCCFA_EHV_FIVRA_CPU0_L
                                  2        GND                     
PC1181_P0_3      Q_CAP_C0805-22UF,16V,20%,EMPTYA 1        SW_P12V_PVCCFA_EHV_FIVRA_CPU0_R
                                  2        GND                     
PC1182_P0_4      Q_CAP_C0805-22UF,16V,20%,EMPTYA 1        SW_P12V_PVCCFA_EHV_FIVRA_CPU0_L
                                  2        GND                     
PC1183           Q_CAPP_THLF-560UF,2.5V,20%,OSCA 1        PVCCFA_EHV_FIVRA_CPU0   
                                  2        GND                     
PC1183_P0_3      Q_CAP_C0402-1UF,16V,10%,EMPTY,A 1        PVCCFA_EHV_FIVRA_CPU0   
                                  2        GND                     
PC1183_P0_4      Q_CAP_C0402-100NF,50V,10%,EMPTA 1        PVCCFA_EHV_FIVRA_CPU0   
                                  2        GND                     
PC1185           Q_CAPP_THLF-560UF,2.5V,20%,OSCA 1        PVCCFA_EHV_FIVRA_CPU0   
                                  2        GND                     
PC1185_P0_3      Q_CAP_0805-22UF,4V,20%,EMPTY,TA 1        PVCCFA_EHV_FIVRA_CPU0   
                                  2        GND                     
PC1186           Q_CAPP_THLF-560UF,2.5V,20%,EMPA 1        PVCCFA_EHV_FIVRA_CPU0   
                                  2        GND                     
PC1186_P0_4      Q_CAP_0805-22UF,4V,20%,EMPTY,TA 1        PVCCFA_EHV_FIVRA_CPU0   
                                  2        GND                     
PC1187           Q_CAPP_SMLF-470UF,2.5V,20%,EMPA 1        PVCCFA_EHV_FIVRA_CPU0   
                                  2        GND                     
PC1187_P0_3      Q_CAP_0805-22UF,4V,20%,EMPTY,TA 1        PVCCFA_EHV_FIVRA_CPU0   
                                  2        GND                     
PC1188_P0_4      Q_CAP_0805-22UF,4V,20%,EMPTY,TA 1        PVCCFA_EHV_FIVRA_CPU0   
                                  2        GND                     
PC1189           Q_CAPP_THLF-270UF,16V,20%,OSCOA 1        SW_P12V_PVCCFA_EHV_FIVRA_CPU0_R
                                  2        GND                     
PC1191           Q_CAP_C0402-2.2UF,10V,10%,X6S,A 1        PVCCFA_EHV_FIVRA_CPU1_VDD3
                                  2        GND                     
PC1192           Q_CAP_C0402-2.2UF,10V,10%,X6S,A 1        PVCCFA_EHV_FIVRA_CPU1_VDD4
                                  2        GND                     
PC1193           Q_CAP_C0402-1UF,16V,10%,X6S,CHA 1        PVCCINFAON_CPU1_VREF    
                                  2        GND                     
PC1193_P1_3      Q_CAP_0402-3300PF,50V,10%,X7R,A 1        SW_P12V_PVCCFA_EHV_FIVRA_CPU1_R
                                  2        GND                     
PC1194           Q_CAP_C0402-1UF,16V,10%,X6S,CHA 1        PVCCIN_CPU1_VREF        
                                  2        GND                     
PC1194_P1_4      Q_CAP_0402-3300PF,50V,10%,X7R,A 1        SW_P12V_PVCCFA_EHV_FIVRA_CPU1_L
                                  2        GND                     
PC1195_P1_3      Q_CAP_C0402-1UF,16V,10%,X6S,CHA 1        SW_P12V_PVCCFA_EHV_FIVRA_CPU1_R
                                  2        GND                     
PC1196           Q_CAP_C0402-1UF,16V,10%,X6S,CHA 1        PVCCD_HV_CPU0_VREF      
                                  2        GND                     
PC1196_P1_4      Q_CAP_C0402-1UF,16V,10%,X6S,CHA 1        SW_P12V_PVCCFA_EHV_FIVRA_CPU1_L
                                  2        GND                     
PC1197           Q_CAP_C0402-100NF,50V,10%,X7R,A 1        SW_PVCCFA_EHV_FIVRA_CPU1_BOOT3_
                                  2        SW_PVCCFA_EHV_FIVRA_CPU1_BOOTR3
PC1198           Q_CAP_C0402-100NF,50V,10%,X7R,A 1        SW_PVCCFA_EHV_FIVRA_CPU1_BOOT4_
                                  2        SW_PVCCFA_EHV_FIVRA_CPU1_BOOTR4
PC1199_P1_3      Q_CAP_C0805-22UF,16V,20%,X6S,CA 1        SW_P12V_PVCCFA_EHV_FIVRA_CPU1_R
                                  2        GND                     
PC1200_P1_4      Q_CAP_C0805-22UF,16V,20%,X6S,CA 1        SW_P12V_PVCCFA_EHV_FIVRA_CPU1_L
                                  2        GND                     
PC1201           Q_CAPP_THLF-560UF,2.5V,20%,OSCA 1        PVCCFA_EHV_FIVRA_CPU1   
                                  2        GND                     
PC1201_P1_3      Q_CAP_C0805-22UF,16V,20%,X6S,CA 1        SW_P12V_PVCCFA_EHV_FIVRA_CPU1_R
                                  2        GND                     
PC1202_P1_4      Q_CAP_C0805-22UF,16V,20%,X6S,CA 1        SW_P12V_PVCCFA_EHV_FIVRA_CPU1_L
                                  2        GND                     
PC1203           Q_CAPP_THLF-560UF,2.5V,20%,OSCA 1        PVCCFA_EHV_FIVRA_CPU1   
                                  2        GND                     
PC1203_P1_4      Q_CAP_C0402-100NF,50V,10%,X7R,A 1        PVCCFA_EHV_FIVRA_CPU1   
                                  2        GND                     
PC1204           Q_CAPP_THLF-560UF,2.5V,20%,OSCA 1        PVCCFA_EHV_FIVRA_CPU1   
                                  2        GND                     
PC1204_P1_3      Q_CAP_C0402-1UF,16V,10%,X6S,CHA 1        PVCCFA_EHV_FIVRA_CPU1   
                                  2        GND                     
PC1205           Q_CAPP_SMLF-470UF,2.5V,20%,EMPA 1        PVCCFA_EHV_FIVRA_CPU1   
                                  2        GND                     
PC1206           Q_CAP_0805-22UF,4V,20%,X6S,TMPA 1        PVNN_MAIN_CPU0          
                                  2        GND                     
PC1206_P1_3      Q_CAP_0805-22UF,4V,20%,X6S,TMPA 1        PVCCFA_EHV_FIVRA_CPU1   
                                  2        GND                     
PC1207           Q_CAP_0805-22UF,4V,20%,X6S,TMPA 1        PVNN_MAIN_CPU1          
                                  2        GND                     
PC1207_P1_4      Q_CAP_0805-22UF,4V,20%,X6S,TMPA 1        PVCCFA_EHV_FIVRA_CPU1   
                                  2        GND                     
PC1208_P1_3      Q_CAP_0805-22UF,4V,20%,X6S,TMPA 1        PVCCFA_EHV_FIVRA_CPU1   
                                  2        GND                     
PC1209_P1_4      Q_CAP_0805-22UF,4V,20%,X6S,TMPA 1        PVCCFA_EHV_FIVRA_CPU1   
                                  2        GND                     
PC1210           Q_CAPP_THLF-270UF,16V,20%,OSCOA 1        SW_P12V_PVCCFA_EHV_FIVRA_CPU1_R
                                  2        GND                     
PC1211_P0_1      Q_CAP_C0402-2.2UF,10V,10%,X6S,A 1        PVCCFA_EHV_FIVRA_CPU0_PVCC1
                                  2        GND                     
PC1212_P0_2      Q_CAP_C0402-2.2UF,10V,10%,X6S,A 1        PVCCFA_EHV_FIVRA_CPU0_PVCC2
                                  2        GND                     
PC1213_P0_3      Q_CAP_C0402-2.2UF,10V,10%,EMPTA 1        PVCCFA_EHV_FIVRA_CPU0_PVCC1
                                  2        GND                     
PC1214_P0_4      Q_CAP_C0402-2.2UF,10V,10%,EMPTA 1        PVCCFA_EHV_FIVRA_CPU0_PVCC2
                                  2        GND                     
PC1215           Q_CAPP_SMLF-100UF,16V,20%,OSCOA 1        SW_P12V_AUX_P1V05_PCH_AUX_FLT
                                  2        GND                     
PC1216           Q_CAP_C0805-22UF,16V,20%,X6S,CA 1        SW_P12V_AUX_P1V05_PCH_AUX_FLT
                                  2        GND                     
PC1217           Q_CAP_C0805-22UF,16V,20%,X6S,CA 1        SW_P12V_AUX_P1V05_PCH_AUX_FLT
                                  2        GND                     
PC1218           Q_CAP_C0805-22UF,16V,20%,X6S,CA 1        SW_P12V_AUX_P1V05_PCH_AUX_FLT
                                  2        GND                     
PC1219           Q_CAP_0402-0.1UF,25V,10%,X7R,CA 1        SW_P12V_AUX_P1V05_PCH_AUX_FLT
                                  2        GND                     
PC1221           Q_CAP_0402-0.1UF,25V,10%,X7R,CA 1        P1V05_PCH_AUX_REF       
                                  2        SH_P1V05_PCH_AUX_N      
PC1222           Q_CAP_0402-0.22UF,16V,10%,X7R,A 1        SW_P1V05_PCH_AUX_BST    
                                  2        SW_P1V05_PCH_AUX_SW     
PC1223           Q_CAP_C0402-470PF,50V,5%,NPO,CA 1        P1V05_PCH_AUX_FB        
                                  2        SH_P1V05_PCH_AUX_P      
PC1224           Q_CAP_0402-0.1UF,25V,10%,X7R,CA 1        P1V05_PCH_AUX           
                                  2        GND                     
PC1225           Q_CAP_0805-47UF,4V,20%,X6S,CH6A 1        P1V05_PCH_AUX           
                                  2        GND                     
PC1226           Q_CAP_0805-47UF,4V,20%,X6S,CH6A 1        P1V05_PCH_AUX           
                                  2        GND                     
PC1227           Q_CAPP_THLF-560UF,2.5V,20%,OSCA 1        P1V05_PCH_AUX           
                                  2        GND                     
PC1229           Q_CAPP_SMLF-470UF,2V,20%,EMPTYA 1        P1V05_PCH_AUX           
                                  2        GND                     
PC1230           Q_CAPP_THLF-560UF,2.5V,20%,OSCA 1        P1V05_PCH_AUX           
                                  2        GND                     
PC1232           Q_CAP_C0805-10UF,16V,10%,X6S,CA 1        SW_P1V8_PCH_AUX_FLT     
                                  2        GND                     
PC1233           Q_CAP_C0805-10UF,16V,10%,X6S,CA 1        SW_P1V8_PCH_AUX_FLT     
                                  2        GND                     
PC1234           Q_CAP_C0402-100NF,50V,10%,X7R,A 1        SW_P1V8_PCH_AUX_FLT     
                                  2        GND                     
PC1235           Q_CAP_0402-0.22UF,16V,10%,X7R,A 1        SW_P1V8_PCH_AUX_BST     
                                  2        SW_P1V8_PCH_AUX_SW      
PC1236           Q_CAP_C0402-100NF,50V,10%,X7R,A 1        P1V8_PCH_AUX            
                                  2        GND                     
PC1237           Q_CAP_0805-22UF,4V,20%,X6S,TMPA 1        P1V8_PCH_AUX            
                                  2        GND                     
PC1238           Q_CAP_0805-22UF,4V,20%,X6S,TMPA 1        P1V8_PCH_AUX            
                                  2        GND                     
PC1239           Q_CAP_0805-22UF,4V,20%,X6S,TMPA 1        P1V8_PCH_AUX            
                                  2        GND                     
PC1240           Q_CAP_0805-22UF,4V,20%,X6S,TMPA 1        P1V8_PCH_AUX            
                                  2        GND                     
PC1241           Q_CAP_0805-22UF,4V,20%,X6S,TMPA 1        P1V8_PCH_AUX            
                                  2        GND                     
PC1242_P1_1      Q_CAP_C0402-2.2UF,10V,10%,X6S,A 1        PVCCFA_EHV_FIVRA_CPU1_PVCC1
                                  2        GND                     
PC1243_P1_2      Q_CAP_C0402-2.2UF,10V,10%,X6S,A 1        PVCCFA_EHV_FIVRA_CPU1_PVCC2
                                  2        GND                     
PC1244_P1_3      Q_CAP_C0402-2.2UF,10V,10%,X6S,A 1        PVCCFA_EHV_FIVRA_CPU1_PVCC1
                                  2        GND                     
PC1245_P1_4      Q_CAP_C0402-2.2UF,10V,10%,X6S,A 1        PVCCFA_EHV_FIVRA_CPU1_PVCC2
                                  2        GND                     
PC1247           Q_CAP_C0805-22UF,16V,20%,EMPTYA 1        SW_P12V_PVCCIN_CPU0_FLT 
                                  2        GND                     
PC1248           Q_CAP_C0805-22UF,16V,20%,EMPTYA 1        SW_P12V_PVCCIN_CPU0_FLT 
                                  2        GND                     
PC1249           Q_CAP_0402-0.1UF,25V,10%,EMPTYA 1        SW_P12V_PVCCIN_CPU0_FLT 
                                  2        GND                     
PC1251           Q_CAP_0402-0.1UF,25V,10%,EMPTYA 1        PVPP_HBM_CPU0_REF       
                                  2        SH_PVPP_HBM_CPU0_N      
PC1252           Q_CAP_0402-0.22UF,16V,10%,EMPTA 1        SW_PVPP_HBM_CPU0_BST    
                                  2        SW_PVPP_HBM_CPU0_SW     
PC1253           Q_CAP_0402-100PF,50V,5%,EMPTY,A 1        PVPP_HBM_CPU0_FB        
                                  2        SH_PVPP_HBM_CPU0_P      
PC1254           Q_CAP_0402-0.1UF,25V,10%,EMPTYA 1        PVPP_HBM_CPU0           
                                  2        GND                     
PC1255           Q_CAP_0805-22UF,4V,20%,EMPTY,TA 1        PVPP_HBM_CPU0           
                                  2        GND                     
PC1256           Q_CAP_0805-22UF,4V,20%,EMPTY,TA 1        PVPP_HBM_CPU0           
                                  2        GND                     
PC1257           Q_CAP_0805-22UF,4V,20%,EMPTY,TA 1        PVPP_HBM_CPU0           
                                  2        GND                     
PC1258           Q_CAPP_THLF-560UF,6.3V,20%,EMPA 1        PVPP_HBM_CPU0           
                                  2        GND                     
PC1259           Q_CAP_C0805-22UF,16V,20%,X6S,CA 1        SW_P12V_PVCCIN_CPU1_FLT 
                                  2        GND                     
PC1260           Q_CAP_C0805-22UF,16V,20%,X6S,CA 1        SW_P12V_PVCCIN_CPU1_FLT 
                                  2        GND                     
PC1261           Q_CAP_C0805-22UF,16V,20%,X6S,CA 1        SW_P12V_PVCCIN_CPU1_FLT 
                                  2        GND                     
PC1262           Q_CAP_0402-0.1UF,25V,10%,X7R,CA 1        SW_P12V_PVCCIN_CPU1_FLT 
                                  2        GND                     
PC1264           Q_CAP_0402-0.1UF,25V,10%,X7R,CA 1        PVPP_HBM_CPU1_REF       
                                  2        SH_PVPP_HBM_CPU1_N      
PC1265           Q_CAP_0402-0.22UF,16V,10%,X7R,A 1        SW_PVPP_HBM_CPU1_BST    
                                  2        SW_PVPP_HBM_CPU1_SW     
PC1266           Q_CAP_0402-100PF,50V,5%,NPO,CHA 1        PVPP_HBM_CPU1_FB        
                                  2        SH_PVPP_HBM_CPU1_P      
PC1267           Q_CAP_0402-0.1UF,25V,10%,X7R,CA 1        PVPP_HBM_CPU1           
                                  2        GND                     
PC1268           Q_CAP_0805-22UF,4V,20%,X6S,TMPA 1        PVPP_HBM_CPU1           
                                  2        GND                     
PC1269           Q_CAP_0805-22UF,4V,20%,X6S,TMPA 1        PVPP_HBM_CPU1           
                                  2        GND                     
PC1270           Q_CAP_0805-22UF,4V,20%,X6S,TMPA 1        PVPP_HBM_CPU1           
                                  2        GND                     
PC1271           Q_CAP_0402-470PF,50V,10%,X7R,TA 1        PVCCFA_EHV_CPU0_BTSEN   
                                  2        GND                     
PC1272           Q_CAP_C0805-22UF,16V,20%,X6S,CA 1        SW_P12V_PVCCINFAON_CPU0_FLT
                                  2        GND                     
PC1273           Q_CAP_C0805-22UF,16V,20%,X6S,CA 1        SW_P12V_PVCCINFAON_CPU0_FLT
                                  2        GND                     
PC1274           Q_CAP_C0402-100NF,50V,10%,X7R,A 1        SW_P12V_PVCCINFAON_CPU0_FLT
                                  2        GND                     
PC1275           Q_CAP_0402-0.22UF,16V,10%,X7R,A 1        SW_PVNN_MAIN_CPU0_BST   
                                  2        SW_PVNN_MAIN_CPU0_SW    
PC1276           Q_CAP_C0402-100NF,50V,10%,X7R,A 1        PVNN_MAIN_CPU0          
                                  2        GND                     
PC1277           Q_CAP_0805-22UF,4V,20%,X6S,TMPA 1        PVNN_MAIN_CPU0          
                                  2        GND                     
PC1278           Q_CAP_0805-22UF,4V,20%,X6S,TMPA 1        PVNN_MAIN_CPU0          
                                  2        GND                     
PC1279           Q_CAP_0805-22UF,4V,20%,X6S,TMPA 1        PVNN_MAIN_CPU0          
                                  2        GND                     
PC1280           Q_CAP_C0805-22UF,16V,20%,X6S,CA 1        SW_P12V_PVCCINFAON_CPU1_FLT
                                  2        GND                     
PC1281           Q_CAP_C0805-22UF,16V,20%,X6S,CA 1        SW_P12V_PVCCINFAON_CPU1_FLT
                                  2        GND                     
PC1282           Q_CAP_C0402-100NF,50V,10%,X7R,A 1        SW_P12V_PVCCINFAON_CPU1_FLT
                                  2        GND                     
PC1283           Q_CAP_0402-0.22UF,16V,10%,X7R,A 1        SW_PVNN_MAIN_CPU1_BST   
                                  2        SW_PVNN_MAIN_CPU1_SW    
PC1284           Q_CAP_C0402-100NF,50V,10%,X7R,A 1        PVNN_MAIN_CPU1          
                                  2        GND                     
PC1285           Q_CAP_0805-22UF,4V,20%,X6S,TMPA 1        PVNN_MAIN_CPU1          
                                  2        GND                     
PC1286           Q_CAP_0805-22UF,4V,20%,X6S,TMPA 1        PVNN_MAIN_CPU1          
                                  2        GND                     
PC1287           Q_CAP_0805-22UF,4V,20%,X6S,TMPA 1        PVNN_MAIN_CPU1          
                                  2        GND                     
PC1289           Q_CAP_C0402-1UF,16V,10%,X6S,CHA 1        PVCCD_HV_CPU1_VREF      
                                  2        GND                     
PC1292           Q_CAP_0402-470PF,50V,10%,X7R,TA 1        PVCCFA_EHV_CPU1_BTSEN   
                                  2        GND                     
PC1336           Q_CAP_C0402-10UF,6.3V,20%,X6S,A 1        PVNN_TERM_CPU1          
                                  2        GND                     
PC1337           Q_CAP_0402-0.1UF,25V,10%,X7R,CA 1        PVNN_TERM_CPU1          
                                  2        GND                     
PC1338           Q_CAP_0402-0.1UF,25V,10%,X7R,CA 1        GND                     
                                  2        PVCCIN_CPU1_VREF        
PC1339           Q_CAP_0402-0.1UF,25V,10%,X7R,CA 1        GND                     
                                  2        PVCCIN_CPU1_VREF        
PC1340           Q_CAP_0402-0.1UF,25V,10%,X7R,CA 1        GND                     
                                  2        PVCCIN_CPU0_VREF        
PC1341           Q_CAP_0402-0.1UF,25V,10%,X7R,CA 1        GND                     
                                  2        PVCCIN_CPU0_VREF        
PC1342           Q_CAP_0402-0.1UF,25V,10%,X7R,CA 1        GND                     
                                  2        PVCCIN_CPU0_VREF        
PC1343           Q_CAP_0402-0.1UF,25V,10%,X7R,CA 1        GND                     
                                  2        PVCCIN_CPU0_VREF        
PC1344           Q_CAP_0402-0.1UF,25V,10%,X7R,CA 1        GND                     
                                  2        PVCCIN_CPU0_VREF        
PC1345           Q_CAP_0402-0.1UF,25V,10%,X7R,CA 1        GND                     
                                  2        PVCCIN_CPU0_VREF        
PC1346           Q_CAP_0402-0.1UF,25V,10%,X7R,CA 1        GND                     
                                  2        PVCCINFAON_CPU0_VREF    
PC1347           Q_CAP_0402-0.1UF,25V,10%,X7R,CA 1        GND                     
                                  2        PVCCINFAON_CPU0_VREF    
PC1348           Q_CAP_0402-0.1UF,25V,10%,X7R,CA 1        GND                     
                                  2        PVCCINFAON_CPU0_VREF    
PC1349           Q_CAP_0402-0.1UF,25V,10%,X7R,CA 1        GND                     
                                  2        PVCCIN_CPU0_VREF        
PC1350           Q_CAP_0402-0.1UF,25V,10%,X7R,CA 1        GND                     
                                  2        PVCCIN_CPU0_VREF        
PC1351           Q_CAP_0402-0.1UF,25V,10%,EMPTYA 1        GND                     
                                  2        PVCCIN_CPU0_VREF        
PC1352           Q_CAP_0402-0.1UF,25V,10%,EMPTYA 1        GND                     
                                  2        PVCCIN_CPU0_VREF        
PC1354           Q_CAP_0402-0.1UF,25V,10%,X7R,CA 1        GND                     
                                  2        PVCCD_HV_CPU0_VREF      
PC1355           Q_CAP_0402-0.1UF,25V,10%,X7R,CA 1        GND                     
                                  2        PVCCIN_CPU0_VREF        
PC1356           Q_CAP_0402-0.1UF,25V,10%,X7R,CA 1        GND                     
                                  2        PVCCIN_CPU0_VREF        
PC1358           Q_CAP_0402-0.1UF,25V,10%,X7R,CA 1        GND                     
                                  2        PVCCIN_CPU1_VREF        
PC1359           Q_CAP_0402-0.1UF,25V,10%,X7R,CA 1        GND                     
                                  2        PVCCIN_CPU1_VREF        
PC1360           Q_CAP_0402-0.1UF,25V,10%,X7R,CA 1        GND                     
                                  2        PVCCIN_CPU1_VREF        
PC1361           Q_CAP_0402-0.1UF,25V,10%,X7R,CA 1        GND                     
                                  2        PVCCIN_CPU1_VREF        
PC1362           Q_CAP_0402-0.1UF,25V,10%,X7R,CA 1        GND                     
                                  2        PVCCIN_CPU1_VREF        
PC1363           Q_CAP_0402-0.1UF,25V,10%,X7R,CA 1        GND                     
                                  2        PVCCIN_CPU1_VREF        
PC1364           Q_CAP_0402-0.1UF,25V,10%,X7R,CA 1        GND                     
                                  2        PVCCINFAON_CPU1_VREF    
PC1365           Q_CAP_0402-0.1UF,25V,10%,X7R,CA 1        GND                     
                                  2        PVCCINFAON_CPU1_VREF    
PC1366           Q_CAP_0402-0.1UF,25V,10%,X7R,CA 1        GND                     
                                  2        PVCCINFAON_CPU1_VREF    
PC1367           Q_CAP_0402-0.1UF,25V,10%,X7R,CA 1        GND                     
                                  2        PVCCIN_CPU1_VREF        
PC1368           Q_CAP_0402-0.1UF,25V,10%,X7R,CA 1        GND                     
                                  2        PVCCIN_CPU1_VREF        
PC1369           Q_CAP_0402-0.1UF,25V,10%,X7R,CA 1        GND                     
                                  2        PVCCIN_CPU1_VREF        
PC1370           Q_CAP_0402-0.1UF,25V,10%,X7R,CA 1        GND                     
                                  2        PVCCIN_CPU1_VREF        
PC1371           Q_CAP_0402-0.1UF,25V,10%,X7R,CA 1        GND                     
                                  2        PVCCD_HV_CPU1_VREF      
PC1372           Q_CAP_C0402-1UF,16V,10%,X6S,CHA 1        PVCCINFAON_CPU0_VREF    
                                  2        GND                     
PC1573           Q_CAPP_SMLF-330UF,2V,35%,SPCAPA 1        PVCCINFAON_CPU0         
                                  2        GND                     
PC1574           Q_CAPP_THLF-560UF,2.5V,20%,OSCA 1        PVCCINFAON_CPU0         
                                  2        GND                     
PC1575           Q_CAPP_SMLF-330UF,2V,35%,SPCAPA 1        PVCCINFAON_CPU0         
                                  2        GND                     
PC1576           Q_CAPP_THLF-560UF,2.5V,20%,OSCA 1        PVCCINFAON_CPU0         
                                  2        GND                     
PC1579           Q_CAPP_THLF-560UF,2.5V,20%,OSCA 1        PVCCINFAON_CPU0         
                                  2        GND                     
PC1588           Q_CAPP_SMLF-330UF,2V,35%,SPCAPA 1        PVCCINFAON_CPU1         
                                  2        GND                     
PC1593           Q_CAPP_THLF-560UF,2.5V,20%,OSCA 1        PVCCINFAON_CPU1         
                                  2        GND                     
PC1594           Q_CAPP_SMLF-330UF,2V,35%,SPCAPA 1        PVCCINFAON_CPU1         
                                  2        GND                     
PC1595           Q_CAPP_THLF-560UF,2.5V,20%,OSCA 1        PVCCINFAON_CPU1         
                                  2        GND                     
PC1596           Q_CAPP_THLF-560UF,2.5V,20%,OSCA 1        PVCCINFAON_CPU1         
                                  2        GND                     
PC1642           Q_CAP_C0402-1UF,25V,10%,X6S,CHA 1        P1V8_PCH_AUX_VCC        
                                  2        GND                     
PC1644           Q_CAPP_THLF-560UF,2.5V,20%,OSCA 1        PVCCD_HV_CPU0           
                                  2        GND                     
PC1645           Q_CAPP_THLF-560UF,2.5V,20%,OSCA 1        PVCCD_HV_CPU0           
                                  2        GND                     
PC1771           Q_CAPP_THLF-560UF,6.3V,20%,OSCA 1        PVPP_HBM_CPU1           
                                  2        GND                     
PC1845           Q_CAPP_SMLF-220UF,6.3V,20%,ALUA 1        P5V_AUX                 
                                  2        GND                     
PC1846           Q_CAP_0402-0.1UF,25V,10%,X7R,CA 1        SW_P5V_AUX_FLT          
                                  2        GND                     
PC1847           Q_CAP_0402-0.22UF,16V,10%,X7R,A 1        SW_P5V_AUX_BST          
                                  2        SW_P5V_AUX_SW           
PC1848           Q_CAP_C0402-1UF,25V,10%,X6S,CHA 1        P5V_AUX_VCC             
                                  2        GND                     
PC1849           Q_CAP_C0805-22UF,16V,20%,X6S,CA 1        SW_P5V_AUX_FLT          
                                  2        GND                     
PC1850           Q_CAP_C0805-22UF,16V,20%,X6S,CA 1        SW_P5V_AUX_FLT          
                                  2        GND                     
PC1852           Q_CAP_0402-0.1UF,25V,10%,X7R,CA 1        P5V_AUX                 
                                  2        GND                     
PC1853           Q_CAP_0402-0.1UF,25V,10%,X7R,CA 1        P5V_AUX_REF             
                                  2        GND                     
PC1855           Q_CAP_C0805-22UF,10V,20%,X6S,CA 1        P5V_AUX                 
                                  2        GND                     
PC1856           Q_CAP_C0805-22UF,10V,20%,X6S,CA 1        P5V_AUX                 
                                  2        GND                     
PC1866           Q_CAPP_THLF-560UF,6.3V,20%,OSCA 1        P3V3_AUX                
                                  2        GND                     
PC1867           Q_CAPP_THLF-560UF,6.3V,20%,OSCA 1        P3V3_AUX                
                                  2        GND                     
PC1868           Q_CAP_C0805-22UF,10V,20%,X6S,CA 1        P3V3_AUX                
                                  2        GND                     
PC1869           Q_CAP_0402-0.1UF,25V,10%,X7R,CA 1        P3V3_AUX                
                                  2        GND                     
PC1870           Q_CAP_0402-0.1UF,25V,10%,EMPTYA 1        P5V_AUX_EN              
                                  2        GND                     
PC1877           Q_CAP_0402-47PF,50V,5%,NPO,TMPA 1        P5V_AUX_FB              
                                  2        P5V_AUX                 
PC1898           Q_CAP_C0805-22UF,16V,20%,X6S,CA 1        SW_P5V_AUX_FLT          
                                  2        GND                     
PC1900           Q_CAPP_SMLF-470UF,2.5V,20%,SPCA 1        PVCCFA_EHV_CPU0         
                                  2        GND                     
PC1910           Q_CAPP_SMLF-330UF,2V,35%,SPCAPA 1        PVCCD_HV_CPU0           
                                  2        GND                     
PC1920           Q_CAPP_SMLF-470UF,2.5V,20%,EMPA 1        PVCCIN_CPU0             
                                  2        GND                     
PC1930           Q_CAPP_SMLF-470UF,2.5V,20%,SPCA 1        PVCCFA_EHV_CPU1         
                                  2        GND                     
PC1940           Q_CAPP_SMLF-330UF,2V,35%,SPCAPA 1        PVCCD_HV_CPU1           
                                  2        GND                     
PC1990           Q_CAPP_SMLF-470UF,2.5V,20%,EMPA 1        PVCCIN_CPU1             
                                  2        GND                     
PC2000           Q_CAP_0402-0.022UF,16V,10%,X7RA 1        P1V05_PCH_AUX_REF       
                                  2        GND                     
PC2001           Q_CAP_0402-0.022UF,16V,10%,EMPA 1        PVPP_HBM_CPU0_REF       
                                  2        GND                     
PC2002           Q_CAP_0402-0.022UF,16V,10%,X7RA 1        PVPP_HBM_CPU1_REF       
                                  2        GND                     
PC2170           Q_CAPP_SMLF-470UF,2.5V,20%,EMPA 1        PVCCFA_EHV_FIVRA_CPU0   
                                  2        GND                     
PC2171           Q_CAPP_SMLF-470UF,2.5V,20%,EMPA 1        PVCCFA_EHV_FIVRA_CPU1   
                                  2        GND                     
PC2172           Q_CAPP_SMLF-470UF,2.5V,20%,SPCA 1        PVCCFA_EHV_FIVRA_CPU1   
                                  2        GND                     
PC2180           Q_CAPP_THLF-560UF,2.5V,20%,OSCA 1        PVCCFA_EHV_CPU0         
                                  2        GND                     
PC2199           Q_CAPP_THLF-560UF,2.5V,20%,OSCA 1        PVCCFA_EHV_CPU1         
                                  2        GND                     
PC2221           Q_CAP_C0402-1UF,25V,10%,X6S,CHA 1        PVNN_MAIN_CPU0_VCC      
                                  2        GND                     
PC2222           Q_CAP_C0402-1UF,25V,10%,X6S,CHA 1        PVNN_MAIN_CPU1_VCC      
                                  2        GND                     
PC2287           Q_CAP_0402-0.01UF,25V,10%,X7R,A 1        PWRGD_P1V8_PCH_AUX      
                                  2        GND                     
PC2336           Q_CAPP_SMLF-470UF,2.5V,20%,EMPA 1        PVCCIN_CPU0             
                                  2        GND                     
PC2643           Q_CAP_C0402-1UF,25V,10%,EMPTY,A 1        PVPP_HBM_CPU0_VCC       
                                  2        GND                     
PC2645           Q_CAPP_SMLF-470UF,2.5V,20%,EMPA 1        PVCCFA_EHV_FIVRA_CPU0   
                                  2        GND                     
PJ45             Q_SHORT_SM-EMPTY,SHORT6 1        VSENSE_PVCCINFAON_CPU0_DP
                                  2        SH_PVCCINFAON_CPU0      
PJ46             Q_SHORT_SM-EMPTY,SHORT6 1        VSENSE_PVCCFA_EHV_CPU0_DP
                                  2        SH_PVCCFA_EHV_CPU0      
PJ47             Q_SHORT_SM-EMPTY,SHORT6 1        VSENSE_PVCCIN_CPU0_DP   
                                  2        SH_PVCCIN_CPU0          
PJ48             Q_SHORT_SM-EMPTY,SHORT6 1        VSENSE_PVCCD_HV_CPU1_DP 
                                  2        SH_PVCCD_HV_CPU1        
PJ49             Q_SHORT_SM-EMPTY,SHORT6 1        VSENSE_PVCCFA_EHV_FIVRA_CPU1_DP
                                  2        SH_PVCCFA_EHV_FIVRA_CPU1
PJ50             Q_SHORT_SM-EMPTY,SHORT6 1        VSENSE_PVCCINFAON_CPU1_DP
                                  2        SH_PVCCINFAON_CPU1      
PJ51             Q_SHORT_SM-EMPTY,SHORT6 1        VSENSE_PVCCFA_EHV_CPU1_DP
                                  2        SH_PVCCFA_EHV_CPU1      
PJ52             Q_SHORT_SM-EMPTY,SHORT6 1        VSENSE_PVCCIN_CPU1_DP   
                                  2        SH_PVCCIN_CPU1          
PJ53             Q_SHORT_SM-EMPTY,SHORT6 1        VSENSE_PVCCFA_EHV_FIVRA_CPU0_DP
                                  2        SH_PVCCFA_EHV_FIVRA_CPU0
PJ54             Q_SHORT_SM-EMPTY,SHORT6 1        VSENSE_PVCCD_HV_CPU0_DP 
                                  2        SH_PVCCD_HV_CPU0        
PJ62             Q_SHORT_SM-EMPTY,SHORT6 1        SH_P1V05_PCH_AUX_P      
                                  2        P1V05_PCH_AUX           
PJ63             Q_SHORT_SM-EMPTY,SHORT6 1        SH_P1V05_PCH_AUX_N      
                                  2        GND                     
PJ64             Q_SHORT_SM-EMPTY,SHORT6 1        SH_PVPP_HBM_CPU0_P      
                                  2        PVPP_HBM_CPU0           
PJ65             Q_SHORT_SM-EMPTY,SHORT6 1        SH_PVPP_HBM_CPU0_N      
                                  2        GND                     
PJ66             Q_SHORT_SM-EMPTY,SHORT6 1        SH_PVPP_HBM_CPU1_P      
                                  2        PVPP_HBM_CPU1           
PJ67             Q_SHORT_SM-EMPTY,SHORT6 1        SH_PVPP_HBM_CPU1_N      
                                  2        GND                     
PL2              Q_INDUCTOR_SMLF-130NH/106A,EMPA 1        SW_PVCCFA_EHV_FIVRA_CPU0_SW3
                                  2        PVCCFA_EHV_FIVRA_CPU0   
PL3              Q_INDUCTOR_SMLF-300NH/33A,IND,A 1        SW_PVCCFA_EHV_CPU0_SW1  
                                  2        PVCCFA_EHV_CPU0         
PL4              Q_INDUCTOR_SMLF-120NH/94A,IND,A 1        SW_PVCCINFAON_CPU0_SW1  
                                  2        PVCCINFAON_CPU0         
PL5              Q_INDUCTOR_SMLF-120NH/94A,IND,A 1        SW_PVCCINFAON_CPU0_SW2  
                                  2        PVCCINFAON_CPU0         
PL6              Q_INDUCTOR_SMLF-100NH/16A,IND,A 1        P12V_AUX                
                                  2        SW_P12V_PVCCINFAON_CPU0_FLT
PL7              Q_INDUCTOR4P_14-150NH,SMLF,INDA 1        SW_PVCCIN_CPU0_SW8      
                                  2        IND_P0_CPL8             
                                  3        GND                     
                                  4        PVCCIN_CPU0             
PL8              Q_INDUCTOR4P_14-150NH,SMLF,INDA 1        SW_PVCCIN_CPU0_SW7      
                                  2        IND_P0_CPL7             
                                  3        IND_P0_CPL6             
                                  4        PVCCIN_CPU0             
PL9              Q_INDUCTOR4P_14-150NH,SMLF,INDA 1        SW_PVCCIN_CPU0_SW6      
                                  2        IND_P0_CPL6             
                                  3        IND_P0_CPL1             
                                  4        PVCCIN_CPU0             
PL10             Q_INDUCTOR4P_14-150NH,SMLF,INDA 1        SW_PVCCIN_CPU0_SW5      
                                  2        IND_P0_CPL5             
                                  3        IND_P0_CPL8             
                                  4        PVCCIN_CPU0             
PL11             Q_INDUCTOR4P_14-150NH,SMLF,INDA 1        SW_PVCCIN_CPU0_SW4      
                                  2        IND_P0_CPL4             
                                  3        IND_P0_CPL5             
                                  4        PVCCIN_CPU0             
PL12             Q_INDUCTOR_SMLF-130NH/106A,INDA 1        SW_PVCCFA_EHV_FIVRA_CPU1_SW3
                                  2        PVCCFA_EHV_FIVRA_CPU1   
PL13             Q_INDUCTOR4P_14-150NH,SMLF,INDA 1        SW_PVCCIN_CPU0_SW2      
                                  2        IND_P0_CPL2             
                                  3        IND_P0_CPL3             
                                  4        PVCCIN_CPU0             
PL14             Q_INDUCTOR_SMLF-100NH/16A,IND,A 1        P12V_AUX                
                                  2        SW_P12V_PVCCFA_EHV_FIVRA_CPU1_R
PL15             Q_INDUCTOR_SMLF-50NH/148A,IND,A 1        P12V_AUX                
                                  2        SW_P12V_PVCCIN_CPU0_FLT 
PL16             Q_INDUCTOR_SMLF-BLM18SN220TN1DA 1        P12V_AUX                
                                  2        SW_P1V8_PCH_AUX_FLT     
PL17             Q_INDUCTOR_SMLF-120NH/94A,IND,A 1        SW_PVCCD_HV_CPU1_SW1    
                                  2        PVCCD_HV_CPU1           
PL18             Q_INDUCTOR_SMLF-130NH/106A,INDA 1        SW_PVCCFA_EHV_FIVRA_CPU1_SW1
                                  2        PVCCFA_EHV_FIVRA_CPU1   
PL19             Q_INDUCTOR_SMLF-130NH/106A,INDA 1        SW_PVCCFA_EHV_FIVRA_CPU1_SW2
                                  2        PVCCFA_EHV_FIVRA_CPU1   
PL20             Q_INDUCTOR_SMLF-300NH/33A,IND,A 1        SW_PVCCFA_EHV_CPU1_SW1  
                                  2        PVCCFA_EHV_CPU1         
PL21             Q_INDUCTOR_SMLF-120NH/94A,IND,A 1        SW_PVCCINFAON_CPU1_SW1  
                                  2        PVCCINFAON_CPU1         
PL22             Q_INDUCTOR_SMLF-120NH/94A,IND,A 1        SW_PVCCINFAON_CPU1_SW2  
                                  2        PVCCINFAON_CPU1         
PL23             Q_INDUCTOR_SMLF-100NH/16A,IND,A 1        P12V_AUX                
                                  2        SW_P12V_PVCCINFAON_CPU1_FLT
PL24             Q_INDUCTOR4P_14-150NH,SMLF,INDA 1        SW_PVCCIN_CPU1_SW8      
                                  2        IND_P1_CPL8             
                                  3        IND_P1_CPL5             
                                  4        PVCCIN_CPU1             
PL25             Q_INDUCTOR4P_14-150NH,SMLF,INDA 1        SW_PVCCIN_CPU1_SW7      
                                  2        IND_P1_CPL7             
                                  3        GND                     
                                  4        PVCCIN_CPU1             
PL26             Q_INDUCTOR4P_14-150NH,SMLF,INDA 1        SW_PVCCIN_CPU1_SW6      
                                  2        IND_P1_CPL6             
                                  3        IND_P1_CPL7             
                                  4        PVCCIN_CPU1             
PL27             Q_INDUCTOR4P_14-150NH,SMLF,INDA 1        SW_PVCCIN_CPU1_SW5      
                                  2        IND_P1_CPL5             
                                  3        IND_P1_CPL4             
                                  4        PVCCIN_CPU1             
PL28             Q_INDUCTOR4P_14-150NH,SMLF,INDA 1        SW_PVCCIN_CPU1_SW4      
                                  2        IND_P1_CPL4             
                                  3        IND_P1_CPL3             
                                  4        PVCCIN_CPU1             
PL29             Q_INDUCTOR4P_14-150NH,SMLF,INDA 1        SW_PVCCIN_CPU1_SW3      
                                  2        IND_P1_CPL3             
                                  3        IND_P1_CPL2             
                                  4        PVCCIN_CPU1             
PL30             Q_INDUCTOR4P_14-150NH,SMLF,INDA 1        SW_PVCCIN_CPU1_SW2      
                                  2        IND_P1_CPL2             
                                  3        IND_P1_CPL1             
                                  4        PVCCIN_CPU1             
PL31             Q_INDUCTOR4P_14-150NH,SMLF,INDA 1        SW_PVCCIN_CPU1_SW1      
                                  2        IND_P1_CPL1             
                                  3        IND_P1_CPL6             
                                  4        PVCCIN_CPU1             
PL32             Q_INDUCTOR_SMLF-50NH/148A,IND,A 1        P12V_AUX                
                                  2        SW_P12V_PVCCIN_CPU1_FLT 
PL33             Q_INDUCTOR_SMLF-130NH/106A,INDA 1        SW_PVCCFA_EHV_FIVRA_CPU0_SW1
                                  2        PVCCFA_EHV_FIVRA_CPU0   
PL34             Q_INDUCTOR_SMLF-130NH/106A,INDA 1        SW_PVCCFA_EHV_FIVRA_CPU0_SW2
                                  2        PVCCFA_EHV_FIVRA_CPU0   
PL35             Q_INDUCTOR_SMLF-120NH/94A,IND,A 1        SW_PVCCD_HV_CPU0_SW1    
                                  2        PVCCD_HV_CPU0           
PL43             Q_INDUCTOR_SMLF-100NH/16A,IND,A 1        P12V_AUX                
                                  2        SW_P12V_PVCCFA_EHV_FIVRA_CPU1_L
PL44             Q_INDUCTOR_SMLF-100NH/16A,IND,A 1        P12V_AUX                
                                  2        SW_P12V_PVCCFA_EHV_FIVRA_CPU0_L
PL45             Q_INDUCTOR_SMLF-100NH/16A,IND,A 1        P12V_AUX                
                                  2        SW_P3V3_AUX_FLT         
PL64             Q_INDUCTOR_SMLF-BLM18SN220TN1DA 1        P12V_AUX                
                                  2        SW_P5V_AUX_FLT          
PL65             Q_INDUCTOR_SMLF-3.3UH/10A,IND,A 1        SW_P5V_AUX_SW           
                                  2        P5V_AUX                 
PL66             Q_INDUCTOR_SMLF-1.5UH/53A,IND,A 1        SW_P3V3_AUX_SW          
                                  2        P3V3_AUX                
PL101            Q_INDUCTOR_SMLF-100NH/16A,IND,A 1        P12V_AUX                
                                  2        SW_P12V_PVCCFA_EHV_FIVRA_CPU0_R
PL105            Q_INDUCTOR_SMLF-120NH/76A,IND,A 1        IND_P0_CPL7             
                                  2        GND                     
PL106            Q_INDUCTOR_SMLF-120NH/76A,IND,A 1        IND_P1_CPL8             
                                  2        GND                     
PL110            Q_INDUCTOR_SMLF-100NH/16A,IND,A 1        P12V_AUX                
                                  2        SW_P12V_AUX_P1V05_PCH_AUX_FLT
PL112            Q_INDUCTOR4P_14-150NH,SMLF,INDA 1        SW_PVCCIN_CPU0_SW3      
                                  2        IND_P0_CPL3             
                                  3        IND_P0_CPL4             
                                  4        PVCCIN_CPU0             
PL113            Q_INDUCTOR_SMLF-130NH/106A,INDA 1        SW_PVCCFA_EHV_FIVRA_CPU1_SW4
                                  2        PVCCFA_EHV_FIVRA_CPU1   
PL114            Q_INDUCTOR4P_14-150NH,SMLF,INDA 1        SW_PVCCIN_CPU0_SW1      
                                  2        IND_P0_CPL1             
                                  3        IND_P0_CPL2             
                                  4        PVCCIN_CPU0             
PL118            Q_INDUCTOR_SMLF-1UH,EMPTY,CV-1A 1        SW_PVPP_HBM_CPU0_SW     
                                  2        PVPP_HBM_CPU0           
PL119            Q_INDUCTOR_SMLF-1UH,IND,CV-10BA 1        SW_PVPP_HBM_CPU1_SW     
                                  2        PVPP_HBM_CPU1           
PL120            Q_INDUCTOR_SMLF-1UH,IND,CV-10BA 1        SW_PVNN_MAIN_CPU0_SW    
                                  2        PVNN_MAIN_CPU0          
PL121            Q_INDUCTOR_SMLF-1UH,IND,CV-10BA 1        SW_PVNN_MAIN_CPU1_SW    
                                  2        PVNN_MAIN_CPU1          
PL150            Q_INDUCTOR_SMLF-300NH/33A,IND,A 1        SW_P1V05_PCH_AUX_SW     
                                  2        P1V05_PCH_AUX           
PL170            Q_INDUCTOR_SMLF-1UH,IND,CV-10BA 1        SW_P1V8_PCH_AUX_SW      
                                  2        P1V8_PCH_AUX            
PL210            Q_INDUCTOR_SMLF-130NH/106A,EMPA 1        SW_PVCCFA_EHV_FIVRA_CPU0_SW4
                                  2        PVCCFA_EHV_FIVRA_CPU0   
PQ1              MOSFET_NCH_1D3S-PSMNR58-30YLH,A 1        P5V                     
                                  2        P5V                     
                                  3        P5V                     
                                  4        VR_P5V_EN_D_R           
                                  5        P5V_AUX                 
PQ2              MOSFET_NCH_1D3S-PSMNR58-30YLH,A 1        P3V3                    
                                  2        P3V3                    
                                  3        P3V3                    
                                  4        VR_P3V3_EN_D_R          
                                  5        P3V3_AUX                
PR50             Q_RES_0402LF-12.4K,1%,1/16W,CHA 1        PVNN_MAIN_CPU0_FB_RC    
                                  2        GND                     
PR51             Q_RES_0402LF-12.4K,1%,1/16W,CHA 1        PVNN_MAIN_CPU1_FB_RC    
                                  2        GND                     
PR73             Q_RES_0402LF-10K,5%,1/16W,CHIPA 1        P3V3_AUX                
                                  2        PWRGD_P3V3_AUX          
PR89             Q_RES_0402LF-15K,1%,1/16W,CHIPA 1        P5V_AUX_CS              
                                  2        GND                     
PR90             Q_RES_0402LF-10K,5%,1/16W,CHIPA 1        P5V_AUX_VCC             
                                  2        PWRGD_P5V_AUX           
PR91             Q_RES_0402LF-11.8K,1%,1/16W,CHA 1        P5V_AUX_FB              
                                  2        GND                     
PR92             Q_RES_0402LF-86.6K,1%,1/16W,CHA 1        P5V_AUX_FB              
                                  2        P5V_AUX                 
PR97             Q_RES_0402LF-2.2,1%,1/16W,CHIPA 1        PVCCFA_EHV_CPU0_PVCC    
                                  2        PVCCFA_EHV_CPU0_VDD1    
PR101            Q_RES_0402LF-2.2,1%,1/16W,CHIPA 1        PVCCINFAON_CPU0_PVCC    
                                  2        PVCCINFAON_CPU0_VDD1    
PR102            Q_RES_0402LF-2.2,1%,1/16W,CHIPA 1        PVCCINFAON_CPU0_PVCC    
                                  2        PVCCINFAON_CPU0_VDD2    
PR105            Q_RES_0402LF-28K,1%,1/16W,EMPTA 1        PVCCINFAON_CPU0_VREF    
                                  2        PVCCINFAON_CPU0_ADDR    
PR106            Q_RES_R0402LF-887,1%,1/16W,CHIA 1        PVCCINFAON_CPU0_ADDR    
                                  2        GND                     
PR107            Q_RES_0402LF-0,5%,1/16W,EMPTY,A 1        P12V_AUX                
                                  2        PVCCINFAON_CPU0_CSPIN   
PR108            Q_RES_0402LF-0,5%,1/16W,CHIP,CA 1        P12V_AUX                
                                  2        PVCCINFAON_CPU0_VIN_CSNIN
PR109            Q_RES_0402LF-1K,1%,1/16W,CHIP,A 1        P3V3_AUX                
                                  2        PWRGD_PVCCINFAON_CPU0_R 
PR110            Q_RES_0402LF-0,5%,1/16W,CHIP,CA 1        PWRGD_PVCCINFAON_CPU0   
                                  2        PWRGD_PVCCINFAON_CPU0_R 
PR111            Q_RES_0402LF-0,5%,1/16W,CHIP,CA 1        FM_PVCCINFAON_CPU0_EN   
                                  2        PVCCINFAON_CPU0_EN_R    
PR112            Q_RES_0402LF-150,1%,1/16W,CHIPA 1        SVID_CLK0_CPU0_R        
                                  2        SVID_CLK_PVCCINFAON_CPU0_R
PR113            Q_RES_0402LF-0,5%,1/16W,CHIP,CA 1        SVID_DIO0_CPU0_R        
                                  2        SVID_DIO_PVCCINFAON_CPU0_R
PR114            Q_RES_0402LF-0,5%,1/16W,CHIP,CA 1        SVID_ALERT0_CPU0_R_N    
                                  2        SVID_ALERT_PVCCINFAON_CPU0_R
PR115            Q_RES_0402LF-0,5%,1/16W,CHIP,CA 1        SMB_VR_3V3AUX_SCL_R     
                                  2        SMB_CLK_PVCCINFAON_CPU0 
PR116            Q_RES_0402LF-0,5%,1/16W,CHIP,CA 1        SMB_VR_3V3AUX_SDA_R     
                                  2        SMB_DIO_PVCCINFAON_CPU0 
PR117            Q_RES_0402LF-1K,1%,1/16W,CHIP,A 1        P3V3_AUX                
                                  2        PWRGD_PVCCFA_EHV_CPU0_R 
PR118            Q_RES_0402LF-0,5%,1/16W,CHIP,CA 1        PWRGD_PVCCFA_EHV_CPU0   
                                  2        PWRGD_PVCCFA_EHV_CPU0_R 
PR119            Q_RES_0402LF-0,5%,1/16W,CHIP,CA 1        FM_PVCCFA_EHV_CPU0_EN   
                                  2        PVCCFA_EHV_CPU0_EN_R    
PR120            Q_RES_0402LF-0,5%,1/16W,CHIP,CA 1        SH_PVCCINFAON_CPU0      
                                  2        SH_PVCCINFAON_CPU0_R    
PR121            Q_RES_0402LF-0,5%,1/16W,CHIP,CA 1        SH_PVCCFA_EHV_CPU0      
                                  2        SH_PVCCFA_EHV_CPU0_R    
PR122            Q_RES_0402LF-0,5%,1/16W,CHIP,CA 1        PVCCINFAON_CPU0_CSPIN   
                                  2        GND                     
PR123            Q_RES_0402LF-1K,1%,1/16W,EMPTYA 1        PVCCINFAON_CPU0_VIN_CSNIN
                                  2        GND                     
PR130            Q_RES_0402LF-1,1%,1/16W,CHIP,CA 1        PVCCINFAON_CPU0_VCC     
                                  2        P3V3_AUX                
PR131            Q_RES_0402LF-1K,1%,1/16W,CHIP,A 1        P3V3_AUX                
                                  2        IRQ_CPU0_VRHOT_N        
PR132            Q_RES_0402LF-8.87K,1%,1/16W,EMA 1        PVCCIN_CPU0_LSET8       
                                  2        GND                     
PR133            Q_RES_0402LF-8.87K,1%,1/16W,EMA 1        PVCCIN_CPU0_LSET7       
                                  2        GND                     
PR134            Q_RES_0402LF-2.2,1%,1/16W,CHIPA 1        PVCCIN_CPU0_PVCC        
                                  2        PVCCIN_CPU0_VDD8        
PR135            Q_RES_0402LF-2.2,1%,1/16W,CHIPA 1        PVCCIN_CPU0_PVCC        
                                  2        PVCCIN_CPU0_VDD7        
PR136            Q_RES_0402LF-0,5%,1/16W,CHIP,CA 1        PVCCIN_CPU0_VOS8        
                                  2        PVCCIN_CPU0             
PR137            Q_RES_0402LF-0,5%,1/16W,CHIP,CA 1        PVCCIN_CPU0_VOS7        
                                  2        PVCCIN_CPU0             
PR138            Q_RES_0402LF-8.87K,1%,1/16W,EMA 1        PVCCIN_CPU0_LSET6       
                                  2        GND                     
PR139            Q_RES_0402LF-8.87K,1%,1/16W,EMA 1        PVCCIN_CPU0_LSET5       
                                  2        GND                     
PR140            Q_RES_0402LF-2.2,1%,1/16W,CHIPA 1        PVCCIN_CPU0_PVCC        
                                  2        PVCCIN_CPU0_VDD6        
PR141            Q_RES_0402LF-2.2,1%,1/16W,CHIPA 1        PVCCIN_CPU0_PVCC        
                                  2        PVCCIN_CPU0_VDD5        
PR142            Q_RES_0402LF-0,5%,1/16W,CHIP,CA 1        PVCCIN_CPU0_VOS6        
                                  2        PVCCIN_CPU0             
PR143            Q_RES_0402LF-0,5%,1/16W,CHIP,CA 1        PVCCIN_CPU0_VOS5        
                                  2        PVCCIN_CPU0             
PR144            Q_RES_0402LF-8.87K,1%,1/16W,EMA 1        PVCCIN_CPU0_LSET4       
                                  2        GND                     
PR145            Q_RES_0402LF-8.87K,1%,1/16W,EMA 1        PVCCIN_CPU0_LSET3       
                                  2        GND                     
PR146            Q_RES_0402LF-2.2,1%,1/16W,CHIPA 1        PVCCIN_CPU0_PVCC        
                                  2        PVCCIN_CPU0_VDD4        
PR147            Q_RES_0402LF-2.2,1%,1/16W,CHIPA 1        PVCCIN_CPU0_PVCC        
                                  2        PVCCIN_CPU0_VDD3        
PR148            Q_RES_0402LF-0,5%,1/16W,CHIP,CA 1        PVCCIN_CPU0_VOS4        
                                  2        PVCCIN_CPU0             
PR149            Q_RES_0402LF-0,5%,1/16W,CHIP,CA 1        PVCCIN_CPU0_VOS3        
                                  2        PVCCIN_CPU0             
PR150            Q_RES_0402LF-8.87K,1%,1/16W,EMA 1        PVCCIN_CPU0_LSET2       
                                  2        GND                     
PR151            Q_RES_0402LF-8.87K,1%,1/16W,EMA 1        PVCCIN_CPU0_LSET1       
                                  2        GND                     
PR152            Q_RES_0402LF-2.2,1%,1/16W,CHIPA 1        PVCCIN_CPU0_PVCC        
                                  2        PVCCIN_CPU0_VDD2        
PR153            Q_RES_0402LF-2.2,1%,1/16W,CHIPA 1        PVCCIN_CPU0_PVCC        
                                  2        PVCCIN_CPU0_VDD1        
PR154            Q_RES_0402LF-0,5%,1/16W,CHIP,CA 1        PVCCIN_CPU0_VOS2        
                                  2        PVCCIN_CPU0             
PR155            Q_RES_0402LF-0,5%,1/16W,CHIP,CA 1        PVCCIN_CPU0_VOS1        
                                  2        PVCCIN_CPU0             
PR156            Q_RES_0402LF-0,5%,1/16W,CHIP,CA 1        P12V_AUX                
                                  2        PVCCIN_CPU0_VIN_CSNIN   
PR157            Q_RES_0402LF-0,5%,1/16W,EMPTY,A 1        P12V_AUX                
                                  2        PVCCIN_CPU0_CSPIN       
PR158            Q_RES_0402LF-0,5%,1/16W,CHIP,CA 1        PVCCIN_CPU0_CSPIN       
                                  2        GND                     
PR159            Q_RES_0402LF-28K,1%,1/16W,EMPTA 1        PVCCIN_CPU0_VREF        
                                  2        PVCCIN_CPU0_ADDR        
PR160            Q_RES_0402LF-1K,1%,1/16W,CHIP,A 1        P3V3_AUX                
                                  2        PWRGD_PVCCIN_CPU0_R     
PR161            Q_RES_0402LF-0,5%,1/16W,CHIP,CA 1        PWRGD_PVCCIN_CPU0       
                                  2        PWRGD_PVCCIN_CPU0_R     
PR162            Q_RES_0402LF-0,5%,1/16W,CHIP,CA 1        FM_PVCCIN_CPU0_EN       
                                  2        PVCCIN_CPU0_EN_R        
PR163            Q_RES_0402LF-150,1%,1/16W,CHIPA 1        SVID_CLK0_CPU0_R        
                                  2        SVID_CLK_PVCCIN_CPU0_R  
PR164            Q_RES_0402LF-0,5%,1/16W,CHIP,CA 1        SVID_DIO0_CPU0_R        
                                  2        SVID_DIO_PVCCIN_CPU0_R  
PR165            Q_RES_0402LF-0,5%,1/16W,CHIP,CA 1        SVID_ALERT0_CPU0_R_N    
                                  2        SVID_ALERT_PVCCIN_CPU0_R
PR166            Q_RES_0402LF-1K,1%,1/16W,EMPTYA 1        PVCCIN_CPU0_VIN_CSNIN   
                                  2        GND                     
PR167            Q_RES_0402LF-0,5%,1/16W,CHIP,CA 1        SMB_VR_3V3AUX_SCL_R     
                                  2        SMB_CLK_PVCCIN_CPU0     
PR168            Q_RES_0402LF-0,5%,1/16W,CHIP,CA 1        SMB_VR_3V3AUX_SDA_R     
                                  2        SMB_DIO_PVCCIN_CPU0     
PR169            Q_RES_0402LF-1K,1%,1/16W,CHIP,A 1        P3V3_AUX                
                                  2        PVCCIN_CPU0_PIN_ALERT   
PR170            Q_RES_0402LF-0,5%,1/16W,CHIP,CA 1        SH_PVCCIN_CPU0          
                                  2        SH_PVCCIN_CPU0_R        
PR171            Q_RES_0402LF-0,5%,1/16W,CHIP,CA 1        PVCCIN_CPU0_ADDR        
                                  2        GND                     
PR172            Q_RES_0402LF-1K,1%,1/16W,CHIP,A 1        P3V3_AUX                
                                  2        PVCCIN_CPU0_VR_FAULT    
PR176            Q_RES_0402LF-1,1%,1/16W,CHIP,CA 1        PVCCIN_CPU0_VCC         
                                  2        P3V3_AUX                
PR177            Q_RES_0402LF-1K,1%,1/16W,CHIP,A 1        P3V3_AUX                
                                  2        IRQ_CPU0_VRHOT_N        
PR186            Q_RES_0402LF-10K,1%,1/16W,CHIPA 1        P3V3_AUX                
                                  2        PWRGD_P1V05_PCH_AUX_R   
PR187            Q_RES_0402LF-10K,1%,1/16W,CHIPA 1        P1V05_PCH_AUX_FB        
                                  2        SH_P1V05_PCH_AUX_N      
PR200            Q_RES_0402LF-2.2,1%,1/16W,CHIPA 1        PVCCD_HV_CPU1_PVCC      
                                  2        PVCCD_HV_CPU1_VDD1      
PR202            Q_RES_0402LF-28K,1%,1/16W,EMPTA 1        PVCCD_HV_CPU1_VREF      
                                  2        PVCCD_HV_CPU1_ADDR      
PR203            Q_RES_0402LF-30.1K    ,1%  ,1/A 1        GND                     
                                  2        PVCCD_HV_CPU1_ADDR      
PR206            Q_RES_0402LF-1K,1%,1/16W,CHIP,A 1        P3V3_AUX                
                                  2        PWRGD_PVCCD_HV_CPU1_R   
PR207            Q_RES_0402LF-0,5%,1/16W,CHIP,CA 1        PWRGD_PVCCD_HV_CPU1     
                                  2        PWRGD_PVCCD_HV_CPU1_R   
PR208            Q_RES_0402LF-0,5%,1/16W,CHIP,CA 1        FM_PVCCD_HV_CPU1_EN     
                                  2        PVCCD_HV_CPU1_EN_R      
PR209            Q_RES_0402LF-150,1%,1/16W,CHIPA 1        SVID_CLK1_CPU1_R        
                                  2        SVID_CLK_PVCCD_HV_CPU1_R
PR210            Q_RES_0402LF-0,5%,1/16W,CHIP,CA 1        SVID_DIO1_CPU1_R        
                                  2        SVID_DIO_PVCCD_HV_CPU1_R
PR211            Q_RES_0402LF-0,5%,1/16W,CHIP,CA 1        SVID_ALERT1_CPU1_R_N    
                                  2        SVID_ALERT_PVCCD_HV_CPU1_R
PR212            Q_RES_0402LF-0,5%,1/16W,CHIP,CA 1        SMB_VR_3V3AUX_SCL_R     
                                  2        SMB_CLK_PVCCD_HV_CPU1   
PR213            Q_RES_0402LF-0,5%,1/16W,CHIP,CA 1        SMB_VR_3V3AUX_SDA_R     
                                  2        SMB_DIO_PVCCD_HV_CPU1   
PR214            Q_RES_0402LF-1K,1%,1/16W,EMPTYA 1        PVCCD_HV_CPU1_ISENSE_P  
                                  2        GND                     
PR215            Q_RES_0402LF-1K,1%,1/16W,CHIP,A 1        P3V3_AUX                
                                  2        PVCCD_HV_CPU1_PIN_ALT   
PR216            Q_RES_0402LF-0,5%,1/16W,CHIP,CA 1        SH_PVCCD_HV_CPU1        
                                  2        SH_PVCCD_HV_CPU1_R      
PR217            Q_RES_0402LF-1K,1%,1/16W,CHIP,A 1        P3V3_AUX                
                                  2        PVCCD_HV_CPU1_FAULT     
PR218            Q_RES_0402LF-1K,1%,1/16W,EMPTYA 1        PVCCD_HV_CPU1_ISENSE_N  
                                  2        GND                     
PR220            Q_RES_0402LF-1,1%,1/16W,CHIP,CA 1        PVCCD_HV_CPU1_VCC       
                                  2        P3V3_AUX                
PR223            Q_RES_0402LF-1K,1%,1/16W,CHIP,A 1        P3V3_AUX                
                                  2        IRQ_PVCCD_CPU1_VRHOT_LVC3_N
PR224            Q_RES_0402LF-8.87K,1%,1/16W,EMA 1        PVCCFA_EHV_FIVRA_CPU1_LSET2
                                  2        GND                     
PR225            Q_RES_0402LF-8.87K,1%,1/16W,EMA 1        PVCCFA_EHV_FIVRA_CPU1_LSET1
                                  2        GND                     
PR226            Q_RES_0402LF-2.2,1%,1/16W,CHIPA 1        PVCCFA_EHV_FIVRA_CPU1_PVCC1
                                  2        PVCCFA_EHV_FIVRA_CPU1_VDD1
PR227            Q_RES_0402LF-2.2,1%,1/16W,CHIPA 1        PVCCFA_EHV_FIVRA_CPU1_PVCC2
                                  2        PVCCFA_EHV_FIVRA_CPU1_VDD2
PR232            Q_RES_0402LF-1K,1%,1/16W,CHIP,A 1        P3V3_AUX                
                                  2        PWRGD_PVCCFA_EHV_FIVRA_CPU1_R
PR233            Q_RES_0402LF-0,5%,1/16W,CHIP,CA 1        PWRGD_PVCCFA_EHV_FIVRA_CPU1
                                  2        PWRGD_PVCCFA_EHV_FIVRA_CPU1_R
PR234            Q_RES_0402LF-0,5%,1/16W,CHIP,CA 1        FM_PVCCFA_EHV_FIVRA_CPU1_EN
                                  2        PVCCFA_EHV_FIVRA_CPU1_EN_R
PR241            Q_RES_0402LF-1K,1%,1/16W,CHIP,A 1        P3V3_AUX                
                                  2        PVCCIN_CPU1_PIN_ALERT   
PR242            Q_RES_0402LF-0,5%,1/16W,CHIP,CA 1        SH_PVCCFA_EHV_FIVRA_CPU1
                                  2        SH_PVCCFA_EHV_FIVRA_CPU1_R
PR243            Q_RES_0402LF-1K,1%,1/16W,CHIP,A 1        P3V3_AUX                
                                  2        PVCCIN_CPU1_VR_FAULT    
PR249            Q_RES_0402LF-1K,1%,1/16W,CHIP,A 1        P3V3_AUX                
                                  2        IRQ_CPU1_VRHOT_N        
PR250            Q_RES_0402LF-2.2,1%,1/16W,CHIPA 1        PVCCFA_EHV_CPU1_PVCC    
                                  2        PVCCFA_EHV_CPU1_VDD1    
PR254            Q_RES_0402LF-2.2,1%,1/16W,CHIPA 1        PVCCINFAON_CPU1_PVCC    
                                  2        PVCCINFAON_CPU1_VDD1    
PR255            Q_RES_0402LF-2.2,1%,1/16W,CHIPA 1        PVCCINFAON_CPU1_PVCC    
                                  2        PVCCINFAON_CPU1_VDD2    
PR258            Q_RES_0402LF-28K,1%,1/16W,EMPTA 1        PVCCINFAON_CPU1_VREF    
                                  2        PVCCINFAON_CPU1_ADDR    
PR259            Q_RES_0402LF -9.53K,1%,1/16W ,A 1        PVCCINFAON_CPU1_ADDR    
                                  2        GND                     
PR260            Q_RES_0402LF-0,5%,1/16W,EMPTY,A 1        P12V_AUX                
                                  2        PVCCINFAON_CPU1_CSPIN   
PR261            Q_RES_0402LF-0,5%,1/16W,CHIP,CA 1        P12V_AUX                
                                  2        PVCCINFAON_CPU1_VIN_CSNIN
PR262            Q_RES_0402LF-1K,1%,1/16W,CHIP,A 1        P3V3_AUX                
                                  2        PWRGD_PVCCINFAON_CPU1_R 
PR263            Q_RES_0402LF-0,5%,1/16W,CHIP,CA 1        PWRGD_PVCCINFAON_CPU1   
                                  2        PWRGD_PVCCINFAON_CPU1_R 
PR264            Q_RES_0402LF-0,5%,1/16W,CHIP,CA 1        FM_PVCCINFAON_CPU1_EN   
                                  2        PVCCINFAON_CPU1_EN_R    
PR265            Q_RES_0402LF-150,1%,1/16W,CHIPA 1        SVID_CLK0_CPU1_R        
                                  2        SVID_CLK_PVCCINFAON_CPU1_R
PR266            Q_RES_0402LF-0,5%,1/16W,CHIP,CA 1        SVID_DIO0_CPU1_R        
                                  2        SVID_DIO_PVCCINFAON_CPU1_R
PR267            Q_RES_0402LF-0,5%,1/16W,CHIP,CA 1        SVID_ALERT0_CPU1_R_N    
                                  2        SVID_ALERT_PVCCINFAON_CPU1_R
PR268            Q_RES_0402LF-0,5%,1/16W,CHIP,CA 1        SMB_VR_3V3AUX_SCL_R     
                                  2        SMB_CLK_PVCCINFAON_CPU1 
PR269            Q_RES_0402LF-0,5%,1/16W,CHIP,CA 1        SMB_VR_3V3AUX_SDA_R     
                                  2        SMB_DIO_PVCCINFAON_CPU1 
PR270            Q_RES_0402LF-1K,1%,1/16W,CHIP,A 1        P3V3_AUX                
                                  2        PWRGD_PVCCFA_EHV_CPU1_R 
PR271            Q_RES_0402LF-0,5%,1/16W,CHIP,CA 1        PWRGD_PVCCFA_EHV_CPU1   
                                  2        PWRGD_PVCCFA_EHV_CPU1_R 
PR272            Q_RES_0402LF-0,5%,1/16W,CHIP,CA 1        FM_PVCCFA_EHV_CPU1_EN   
                                  2        PVCCFA_EHV_CPU1_EN_R    
PR273            Q_RES_0402LF-0,5%,1/16W,CHIP,CA 1        SH_PVCCINFAON_CPU1      
                                  2        SH_PVCCINFAON_CPU1_R    
PR274            Q_RES_0402LF-0,5%,1/16W,CHIP,CA 1        SH_PVCCFA_EHV_CPU1      
                                  2        SH_PVCCFA_EHV_CPU1_R    
PR275            Q_RES_0402LF-0,5%,1/16W,CHIP,CA 1        PVCCINFAON_CPU1_CSPIN   
                                  2        GND                     
PR276            Q_RES_0402LF-1K,1%,1/16W,EMPTYA 1        PVCCINFAON_CPU1_VIN_CSNIN
                                  2        GND                     
PR283            Q_RES_0402LF-1,1%,1/16W,CHIP,CA 1        PVCCINFAON_CPU1_VCC     
                                  2        P3V3_AUX                
PR284            Q_RES_0402LF-1K,1%,1/16W,CHIP,A 1        P3V3_AUX                
                                  2        IRQ_CPU1_VRHOT_N        
PR285            Q_RES_0402LF-8.87K,1%,1/16W,EMA 1        PVCCIN_CPU1_LSET8       
                                  2        GND                     
PR286            Q_RES_0402LF-8.87K,1%,1/16W,EMA 1        PVCCIN_CPU1_LSET7       
                                  2        GND                     
PR287            Q_RES_0402LF-2.2,1%,1/16W,CHIPA 1        PVCCIN_CPU1_PVCC        
                                  2        PVCCIN_CPU1_VDD8        
PR288            Q_RES_0402LF-2.2,1%,1/16W,CHIPA 1        PVCCIN_CPU1_PVCC        
                                  2        PVCCIN_CPU1_VDD7        
PR289            Q_RES_0402LF-0,5%,1/16W,CHIP,CA 1        PVCCIN_CPU1_VOS8        
                                  2        PVCCIN_CPU1             
PR290            Q_RES_0402LF-0,5%,1/16W,CHIP,CA 1        PVCCIN_CPU1_VOS7        
                                  2        PVCCIN_CPU1             
PR291            Q_RES_0402LF-8.87K,1%,1/16W,EMA 1        PVCCIN_CPU1_LSET6       
                                  2        GND                     
PR292            Q_RES_0402LF-8.87K,1%,1/16W,EMA 1        PVCCIN_CPU1_LSET5       
                                  2        GND                     
PR293            Q_RES_0402LF-2.2,1%,1/16W,CHIPA 1        PVCCIN_CPU1_PVCC        
                                  2        PVCCIN_CPU1_VDD6        
PR294            Q_RES_0402LF-2.2,1%,1/16W,CHIPA 1        PVCCIN_CPU1_PVCC        
                                  2        PVCCIN_CPU1_VDD5        
PR295            Q_RES_0402LF-0,5%,1/16W,CHIP,CA 1        PVCCIN_CPU1_VOS6        
                                  2        PVCCIN_CPU1             
PR296            Q_RES_0402LF-0,5%,1/16W,CHIP,CA 1        PVCCIN_CPU1_VOS5        
                                  2        PVCCIN_CPU1             
PR297            Q_RES_0402LF-8.87K,1%,1/16W,EMA 1        PVCCIN_CPU1_LSET4       
                                  2        GND                     
PR298            Q_RES_0402LF-8.87K,1%,1/16W,EMA 1        PVCCIN_CPU1_LSET3       
                                  2        GND                     
PR299            Q_RES_0402LF-2.2,1%,1/16W,CHIPA 1        PVCCIN_CPU1_PVCC        
                                  2        PVCCIN_CPU1_VDD4        
PR300            Q_RES_0402LF-2.2,1%,1/16W,CHIPA 1        PVCCIN_CPU1_PVCC        
                                  2        PVCCIN_CPU1_VDD3        
PR301            Q_RES_0402LF-0,5%,1/16W,CHIP,CA 1        PVCCIN_CPU1_VOS4        
                                  2        PVCCIN_CPU1             
PR302            Q_RES_0402LF-0,5%,1/16W,CHIP,CA 1        PVCCIN_CPU1_VOS3        
                                  2        PVCCIN_CPU1             
PR303            Q_RES_0402LF-0,5%,1/16W,CHIP,CA 1        P12V_AUX                
                                  2        PVCCIN_CPU1_VIN_CSNIN   
PR304            Q_RES_0402LF-0,5%,1/16W,EMPTY,A 1        P12V_AUX                
                                  2        PVCCIN_CPU1_CSPIN       
PR305            Q_RES_0402LF-0,5%,1/16W,CHIP,CA 1        PVCCIN_CPU1_CSPIN       
                                  2        GND                     
PR306            Q_RES_0402LF-28K,1%,1/16W,EMPTA 1        PVCCIN_CPU1_VREF        
                                  2        PVCCIN_CPU1_ADDR        
PR307            Q_RES_0402LF-1K,1%,1/16W,CHIP,A 1        P3V3_AUX                
                                  2        PWRGD_PVCCIN_CPU1_R     
PR308            Q_RES_0402LF-0,5%,1/16W,CHIP,CA 1        PWRGD_PVCCIN_CPU1       
                                  2        PWRGD_PVCCIN_CPU1_R     
PR309            Q_RES_0402LF-0,5%,1/16W,CHIP,CA 1        FM_PVCCIN_CPU1_EN       
                                  2        PVCCIN_CPU1_EN_R        
PR310            Q_RES_0402LF-150,1%,1/16W,CHIPA 1        SVID_CLK0_CPU1_R        
                                  2        SVID_CLK_PVCCIN_CPU1_R  
PR311            Q_RES_0402LF-0,5%,1/16W,CHIP,CA 1        SVID_DIO0_CPU1_R        
                                  2        SVID_DIO_PVCCIN_CPU1_R  
PR312            Q_RES_0402LF-0,5%,1/16W,CHIP,CA 1        SVID_ALERT0_CPU1_R_N    
                                  2        SVID_ALERT_PVCCIN_CPU1_R
PR313            Q_RES_0402LF-1K,1%,1/16W,EMPTYA 1        PVCCIN_CPU1_VIN_CSNIN   
                                  2        GND                     
PR314            Q_RES_0402LF-0,5%,1/16W,CHIP,CA 1        SMB_VR_3V3AUX_SCL_R     
                                  2        SMB_CLK_PVCCIN_CPU1     
PR315            Q_RES_0402LF-0,5%,1/16W,CHIP,CA 1        SMB_VR_3V3AUX_SDA_R     
                                  2        SMB_DIO_PVCCIN_CPU1     
PR317            Q_RES_0402LF-0,5%,1/16W,CHIP,CA 1        SH_PVCCIN_CPU1          
                                  2        SH_PVCCIN_CPU1_R        
PR318            Q_RES_0402LF-5.23K,1%,1/16W,CHA 1        PVCCIN_CPU1_ADDR        
                                  2        GND                     
PR323            Q_RES_0402LF-1,1%,1/16W,CHIP,CA 1        PVCCIN_CPU1_VCC         
                                  2        P3V3_AUX                
PR325            Q_RES_0402LF-8.87K,1%,1/16W,EMA 1        PVCCIN_CPU1_LSET2       
                                  2        GND                     
PR326            Q_RES_0402LF-8.87K,1%,1/16W,EMA 1        PVCCIN_CPU1_LSET1       
                                  2        GND                     
PR327            Q_RES_0402LF-2.2,1%,1/16W,CHIPA 1        PVCCIN_CPU1_PVCC        
                                  2        PVCCIN_CPU1_VDD2        
PR328            Q_RES_0402LF-2.2,1%,1/16W,CHIPA 1        PVCCIN_CPU1_PVCC        
                                  2        PVCCIN_CPU1_VDD1        
PR329            Q_RES_0402LF-0,5%,1/16W,CHIP,CA 1        PVCCIN_CPU1_VOS2        
                                  2        PVCCIN_CPU1             
PR330            Q_RES_0402LF-0,5%,1/16W,CHIP,CA 1        PVCCIN_CPU1_VOS1        
                                  2        PVCCIN_CPU1             
PR335            Q_RES_0402LF-1K,1%,1/16W,CHIP,A 1        P3V3_AUX                
                                  2        PWRGD_PVCCFA_EHV_FIVRA_CPU0_R
PR336            Q_RES_0402LF-0,5%,1/16W,CHIP,CA 1        PWRGD_PVCCFA_EHV_FIVRA_CPU0
                                  2        PWRGD_PVCCFA_EHV_FIVRA_CPU0_R
PR337            Q_RES_0402LF-0,5%,1/16W,CHIP,CA 1        FM_PVCCFA_EHV_FIVRA_CPU0_EN
                                  2        PVCCFA_EHV_FIVRA_CPU0_EN_R
PR345            Q_RES_0402LF-0,5%,1/16W,CHIP,CA 1        SH_PVCCFA_EHV_FIVRA_CPU0
                                  2        SH_PVCCFA_EHV_FIVRA_CPU0_R
PR353            Q_RES_0402LF-8.87K,1%,1/16W,EMA 1        PVCCFA_EHV_FIVRA_CPU0_LSET2
                                  2        GND                     
PR354            Q_RES_0402LF-8.87K,1%,1/16W,EMA 1        PVCCFA_EHV_FIVRA_CPU0_LSET1
                                  2        GND                     
PR355            Q_RES_0402LF-2.2,1%,1/16W,CHIPA 1        PVCCFA_EHV_FIVRA_CPU0_PVCC1
                                  2        PVCCFA_EHV_FIVRA_CPU0_VDD1
PR356            Q_RES_0402LF-2.2,1%,1/16W,CHIPA 1        PVCCFA_EHV_FIVRA_CPU0_PVCC2
                                  2        PVCCFA_EHV_FIVRA_CPU0_VDD2
PR357            Q_RES_0402LF-28K,1%,1/16W,EMPTA 1        PVCCD_HV_CPU0_VREF      
                                  2        PVCCD_HV_CPU0_ADDR      
PR358            Q_RES_0402LF-4.64K,0.5%,1/16W,A 1        GND                     
                                  2        PVCCD_HV_CPU0_ADDR      
PR361            Q_RES_0402LF-1K,1%,1/16W,CHIP,A 1        P3V3_AUX                
                                  2        PWRGD_PVCCD_HV_CPU0_R   
PR362            Q_RES_0402LF-0,5%,1/16W,CHIP,CA 1        PWRGD_PVCCD_HV_CPU0     
                                  2        PWRGD_PVCCD_HV_CPU0_R   
PR363            Q_RES_0402LF-0,5%,1/16W,CHIP,CA 1        FM_PVCCD_HV_CPU0_EN     
                                  2        PVCCD_HV_CPU0_EN_R      
PR364            Q_RES_0402LF-150,1%,1/16W,CHIPA 1        SVID_CLK1_CPU0_R        
                                  2        SVID_CLK_PVCCD_HV_CPU0_R
PR365            Q_RES_0402LF-0,5%,1/16W,CHIP,CA 1        SVID_DIO1_CPU0_R        
                                  2        SVID_DIO_PVCCD_HV_CPU0_R
PR366            Q_RES_0402LF-0,5%,1/16W,CHIP,CA 1        SVID_ALERT1_CPU0_R_N    
                                  2        SVID_ALERT_PVCCD_HV_CPU0_R
PR367            Q_RES_0402LF-0,5%,1/16W,CHIP,CA 1        SMB_VR_3V3AUX_SCL_R     
                                  2        SMB_CLK_PVCCD_HV_CPU0   
PR368            Q_RES_0402LF-0,5%,1/16W,CHIP,CA 1        SMB_VR_3V3AUX_SDA_R     
                                  2        SMB_DIO_PVCCD_HV_CPU0   
PR369            Q_RES_0402LF-1K,1%,1/16W,EMPTYA 1        PVCCD_HV_CPU0_ISENSE_P  
                                  2        GND                     
PR370            Q_RES_0402LF-1K,1%,1/16W,CHIP,A 1        P3V3_AUX                
                                  2        PVCCD_HV_CPU0_PIN_ALT   
PR371            Q_RES_0402LF-0,5%,1/16W,CHIP,CA 1        SH_PVCCD_HV_CPU0        
                                  2        SH_PVCCD_HV_CPU0_R      
PR372            Q_RES_0402LF-1K,1%,1/16W,CHIP,A 1        P3V3_AUX                
                                  2        PVCCD_HV_CPU0_FAULT     
PR373            Q_RES_0402LF-1K,1%,1/16W,EMPTYA 1        PVCCD_HV_CPU0_ISENSE_N  
                                  2        GND                     
PR375            Q_RES_0402LF-1,1%,1/16W,CHIP,CA 1        PVCCD_HV_CPU0_VCC       
                                  2        P3V3_AUX                
PR378            Q_RES_0402LF-1K,1%,1/16W,CHIP,A 1        P3V3_AUX                
                                  2        IRQ_PVCCD_CPU0_VRHOT_LVC3_N
PR380            Q_RES_0402LF-2.2,1%,1/16W,CHIPA 1        PVCCD_HV_CPU0_PVCC      
                                  2        PVCCD_HV_CPU0_VDD1      
PR389            Q_RES_0402LF-1,1%,1/16W,CHIP,CA 1        P5V_AUX                 
                                  2        P3V3_AUX_VCC            
PR395            Q_RES_0402LF-0,5%,1/16W,CHIP,CA 1        P3V3_AUX                
                                  2        PVCC1_AUX               
PR396            Q_RES_0402LF-0,5%,1/16W,EMPTY,A 1        P5V_AUX                 
                                  2        PVCC1_AUX               
PR400            Q_RES_0402LF-10K,1%,1/16W,EMPTB 1        PVCCIN_CPU0_ATSEN       
                                  2        GND                     
PR402            Q_RES_0402LF-0,5%,1/16W,CHIP,CA 1        P5V                     
                                  2        PVCCIN_CPU0_PVCC        
PR403            Q_RES_0402LF-0,5%,1/16W,EMPTY,A 1        P3V3                    
                                  2        PVCCIN_CPU0_PVCC        
PR409            Q_RES_0402LF-0,5%,1/16W,EMPTY,A 1        PVCCD_HV_CPU0_ISYS_R    
PR410            Q_RES_0402LF-0,5%,1/16W,EMPTY,A 1        PVCCD_HV_CPU1_ISYS_R    
PR411            Q_RES_0402LF-0,5%,1/16W,CHIP,CA 1        FM_PCH_P1V8_AUX_EN      
                                  2        FM_PCH_P1V8_AUX_EN_R    
PR412            Q_RES_0402LF-0,5%,1/16W,EMPTY,A 2        FM_PCH_P1V8_AUX_EN_R    
PR435            Q_RES_0402LF-10K,1%,1/16W,EMPTB 1        PVCCINFAON_CPU0_ATSEN   
                                  2        GND                     
PR436            Q_RES_0402LF-10K,1%,1/16W,EMPTB 1        PVCCFA_EHV_CPU0_BTSEN   
                                  2        GND                     
PR437            Q_RES_0402LF-0,5%,1/16W,CHIP,CA 1        P5V                     
                                  2        PVCCINFAON_CPU0_PVCC    
PR441            Q_RES_0402LF-0,5%,1/16W,EMPTY,A 1        P3V3                    
                                  2        PVCCINFAON_CPU0_PVCC    
PR442            Q_RES_0402LF-0,5%,1/16W,CHIP,CA 1        P5V                     
                                  2        PVCCFA_EHV_CPU0_PVCC    
PR443            Q_RES_0402LF-0,5%,1/16W,EMPTY,A 1        P3V3                    
                                  2        PVCCFA_EHV_CPU0_PVCC    
PR444            Q_RES_0402LF-0,5%,1/16W,CHIP,CA 1        P5V                     
                                  2        PVCCFA_EHV_FIVRA_CPU0_PVCC1
PR447            Q_RES_0402LF-0,5%,1/16W,CHIP,CA 1        P5V                     
                                  2        PVCCFA_EHV_FIVRA_CPU0_PVCC2
PR450            Q_RES_0402LF-0,5%,1/16W,EMPTY,A 1        PVCCIN_CPU0_ISYS_R      
PR451            Q_RES_0402LF-0,5%,1/16W,CHIP,CA 1        PVCCIN_CPU0_ISYS_R      
                                  2        GND                     
PR452            Q_RES_0402LF-0,5%,1/16W,EMPTY,A 1        PVCCIN_CPU1_ISYS_R      
PR453            Q_RES_0402LF-0,5%,1/16W,CHIP,CA 1        PVCCIN_CPU1_ISYS_R      
                                  2        GND                     
PR501            Q_RES_0402LF-8.25K,1%,1/16W,CHA 1        PVNN_MAIN_CPU0_FB_RC    
                                  2        PVNN_MAIN_CPU0          
PR502            Q_RES_0402LF-8.25K,1%,1/16W,CHA 1        PVNN_MAIN_CPU1_FB_RC    
                                  2        PVNN_MAIN_CPU1          
PR519            Q_RES_0402LF-100,1%,1/16W,CHIPA 1        VSENSE_PVCCINFAON_CPU0_DN
                                  2        GND                     
PR520            Q_RES_0402LF-100,1%,1/16W,CHIPA 1        VSENSE_PVCCFA_EHV_CPU0_DN
                                  2        GND                     
PR521            Q_RES_0402LF-100,1%,1/16W,CHIPA 1        VSENSE_PVCCINFAON_CPU0_DP
                                  2        PVCCINFAON_CPU0         
PR522            Q_RES_0402LF-100,1%,1/16W,CHIPA 1        VSENSE_PVCCFA_EHV_CPU0_DP
                                  2        PVCCFA_EHV_CPU0         
PR523            Q_RES_0402LF-1K,1%,1/16W,CHIP,A 1        P3V3_AUX                
                                  2        PVCCINFAON_CPU0_VR_FAULT
PR524            Q_RES_0402LF-1K,1%,1/16W,CHIP,A 1        P3V3_AUX                
                                  2        PVCCINFAON_CPU0_PIN_ALERT
PR527            Q_RES_0402LF-100,1%,1/16W,CHIPA 1        VSENSE_PVCCIN_CPU0_DN   
                                  2        GND                     
PR528            Q_RES_0402LF-100,1%,1/16W,CHIPA 1        SVID_DIO0_CPU0_R        
                                  2        PVNN_TERM_CPU0          
PR529            Q_RES_0402LF-49.9     ,1%  ,1/A 1        SVID_CLK0_CPU0_R        
                                  2        PVNN_TERM_CPU0          
PR530            Q_RES_0402LF-49.9     ,1%  ,1/B 1        SVID_ALERT0_CPU0_R_N    
                                  2        PVNN_TERM_CPU0          
PR531            Q_RES_0402LF-100,1%,1/16W,CHIPA 1        VSENSE_PVCCIN_CPU0_DP   
                                  2        PVCCIN_CPU0             
PR558            Q_RES_0402LF-100,1%,1/16W,CHIPA 1        VSENSE_PVCCD_HV_CPU1_DN 
                                  2        GND                     
PR559            Q_RES_0402LF-100,1%,1/16W,CHIPA 1        VSENSE_PVCCD_HV_CPU1_DP 
                                  2        PVCCD_HV_CPU1           
PR560            Q_RES_0402LF-100,1%,1/16W,CHIPA 1        VSENSE_PVCCFA_EHV_FIVRA_CPU1_DN
                                  2        GND                     
PR561            Q_RES_0402LF-100,1%,1/16W,CHIPA 1        VSENSE_PVCCFA_EHV_FIVRA_CPU1_DP
                                  2        PVCCFA_EHV_FIVRA_CPU1   
PR566            Q_RES_0402LF-100,1%,1/16W,CHIPA 1        VSENSE_PVCCINFAON_CPU1_DN
                                  2        GND                     
PR567            Q_RES_0402LF-100,1%,1/16W,CHIPA 1        VSENSE_PVCCFA_EHV_CPU1_DN
                                  2        GND                     
PR568            Q_RES_0402LF-100,1%,1/16W,CHIPA 1        VSENSE_PVCCINFAON_CPU1_DP
                                  2        PVCCINFAON_CPU1         
PR569            Q_RES_0402LF-100,1%,1/16W,CHIPA 1        VSENSE_PVCCFA_EHV_CPU1_DP
                                  2        PVCCFA_EHV_CPU1         
PR570            Q_RES_0402LF-1K,1%,1/16W,CHIP,A 1        P3V3_AUX                
                                  2        PVCCINFAON_CPU1_VR_FAULT
PR571            Q_RES_0402LF-1K,1%,1/16W,CHIP,A 1        P3V3_AUX                
                                  2        PVCCINFAON_CPU1_PIN_ALERT
PR574            Q_RES_0402LF-100,1%,1/16W,CHIPA 1        VSENSE_PVCCIN_CPU1_DN   
                                  2        GND                     
PR575            Q_RES_0402LF-100,1%,1/16W,CHIPA 1        SVID_DIO0_CPU1_R        
                                  2        PVNN_TERM_CPU1          
PR576            Q_RES_0402LF-49.9     ,1%  ,1/A 1        SVID_CLK0_CPU1_R        
                                  2        PVNN_TERM_CPU1          
PR577            Q_RES_0402LF-49.9     ,1%  ,1/B 1        SVID_ALERT0_CPU1_R_N    
                                  2        PVNN_TERM_CPU1          
PR578            Q_RES_0402LF-100,1%,1/16W,CHIPA 1        VSENSE_PVCCIN_CPU1_DP   
                                  2        PVCCIN_CPU1             
PR586            Q_RES_0402LF-100,1%,1/16W,CHIPA 1        VSENSE_PVCCFA_EHV_FIVRA_CPU0_DN
                                  2        GND                     
PR587            Q_RES_0402LF-100,1%,1/16W,CHIPA 1        VSENSE_PVCCFA_EHV_FIVRA_CPU0_DP
                                  2        PVCCFA_EHV_FIVRA_CPU0   
PR591            Q_RES_0402LF-100,1%,1/16W,CHIPA 1        VSENSE_PVCCD_HV_CPU0_DN 
                                  2        GND                     
PR592            Q_RES_0402LF-100,1%,1/16W,CHIPA 1        VSENSE_PVCCD_HV_CPU0_DP 
                                  2        PVCCD_HV_CPU0           
PR632            Q_RES_0402LF-0,5%,1/16W,EMPTY,A 1        P3V3                    
                                  2        PVCCFA_EHV_FIVRA_CPU0_PVCC1
PR633            Q_RES_0402LF-0,5%,1/16W,EMPTY,A 1        P3V3                    
                                  2        PVCCFA_EHV_FIVRA_CPU0_PVCC2
PR634            Q_RES_0402LF-10K,1%,1/16W,EMPTB 1        PVCCD_HV_CPU0_ATSEN     
                                  2        GND                     
PR635            Q_RES_0402LF-0,5%,1/16W,CHIP,CA 1        P5V                     
                                  2        PVCCD_HV_CPU0_PVCC      
PR636            Q_RES_0402LF-0,5%,1/16W,EMPTY,A 1        P3V3                    
                                  2        PVCCD_HV_CPU0_PVCC      
PR637            Q_RES_0402LF-10K,1%,1/16W,EMPTB 1        PVCCIN_CPU1_ATSEN       
                                  2        GND                     
PR639            Q_RES_0402LF-0,5%,1/16W,CHIP,CA 1        P5V                     
                                  2        PVCCIN_CPU1_PVCC        
PR640            Q_RES_0402LF-0,5%,1/16W,EMPTY,A 1        P3V3                    
                                  2        PVCCIN_CPU1_PVCC        
PR665            Q_RES_0402LF-10K,1%,1/16W,EMPTB 1        PVCCINFAON_CPU1_ATSEN   
                                  2        GND                     
PR667            Q_RES_0402LF-10K,1%,1/16W,EMPTB 1        PVCCFA_EHV_CPU1_BTSEN   
                                  2        GND                     
PR668            Q_RES_0402LF-0,5%,1/16W,CHIP,CA 1        P5V                     
                                  2        PVCCINFAON_CPU1_PVCC    
PR677            Q_RES_0402LF-0,5%,1/16W,EMPTY,A 1        P3V3                    
                                  2        PVCCINFAON_CPU1_PVCC    
PR678            Q_RES_0402LF-0,5%,1/16W,CHIP,CA 1        P5V                     
                                  2        PVCCFA_EHV_CPU1_PVCC    
PR699            Q_RES_0402LF-0,5%,1/16W,EMPTY,A 1        P3V3                    
                                  2        PVCCFA_EHV_CPU1_PVCC    
PR701            Q_RES_0402LF-0,5%,1/16W,CHIP,CA 1        P5V                     
                                  2        PVCCFA_EHV_FIVRA_CPU1_PVCC1
PR702            Q_RES_0402LF-0,5%,1/16W,CHIP,CA 1        P5V                     
                                  2        PVCCFA_EHV_FIVRA_CPU1_PVCC2
PR703            Q_RES_0402LF-0,5%,1/16W,EMPTY,A 1        P3V3                    
                                  2        PVCCFA_EHV_FIVRA_CPU1_PVCC1
PR704            Q_RES_0402LF-0,5%,1/16W,EMPTY,A 1        P3V3                    
                                  2        PVCCFA_EHV_FIVRA_CPU1_PVCC2
PR705            Q_RES_0402LF-10K,1%,1/16W,EMPTB 1        PVCCD_HV_CPU1_ATSEN     
                                  2        GND                     
PR706            Q_RES_0402LF-0,5%,1/16W,CHIP,CA 1        P5V                     
                                  2        PVCCD_HV_CPU1_PVCC      
PR707            Q_RES_0402LF-0,5%,1/16W,EMPTY,A 1        P3V3                    
                                  2        PVCCD_HV_CPU1_PVCC      
PR830            Q_RES_0402LF-31.6K,1%,1/16W,CHA 1        P3V3_AUX_FB             
                                  2        GND                     
PR831            Q_RES_0402LF-100K,1%,1/16W,CHIA 1        P3V3_AUX_FB             
                                  2        P3V3_AUX                
PR832            Q_RES_0402LF-7.5K,1%,1/16W,CHIA 1        P3V3_AUX_MODE           
                                  2        GND                     
PR833            Q_RES_0402LF-1.5K,1%,1/16W,EMPA 1        P3V3_AUX_SS             
                                  2        GND                     
PR834            Q_RES_0402LF-21.5K,1%,1/16W,CHA 1        P3V3_AUX_ILIM           
                                  2        GND                     
PR835            Q_RES_0402LF-0,5%,1/16W,CHIP,CA 1        SW_P3V3_AUX_BOOT        
                                  2        SW_P3V3_AUX_BOOT_R      
PR836            Q_RES_0402LF-1K,1%,1/16W,CHIP,A 1        P3V3_AUX_VOS            
                                  2        P3V3_AUX                
PR1297           Q_RES_0402LF-8.87K,1%,1/16W,EMA 1        PVCCFA_EHV_FIVRA_CPU0_LSET4
                                  2        GND                     
PR1298           Q_RES_0402LF-8.87K,1%,1/16W,EMA 1        PVCCFA_EHV_FIVRA_CPU0_LSET3
                                  2        GND                     
PR1299           Q_RES_0402LF-2.2,1%,1/16W,EMPTA 1        PVCCFA_EHV_FIVRA_CPU0_PVCC1
                                  2        PVCCFA_EHV_FIVRA_CPU0_VDD3
PR1300           Q_RES_0402LF-2.2,1%,1/16W,EMPTA 1        PVCCFA_EHV_FIVRA_CPU0_PVCC2
                                  2        PVCCFA_EHV_FIVRA_CPU0_VDD4
PR1301           Q_RES_0402LF-60.4K,1%,1/16W,CHA 1        PVNN_MAIN_CPU0_MODE     
                                  2        GND                     
PR1302           Q_RES_0402LF-10K,1%,1/16W,CHIPA 1        P3V3_AUX                
                                  2        PWRGD_P1V8_PCH_AUX_R    
PR1303           Q_RES_0402LF-9.09K,1%,1/16W,CHA 1        PVNN_MAIN_CPU0_CS       
                                  2        GND                     
PR1304           Q_RES_0402LF-8.87K,1%,1/16W,EMA 1        PVCCFA_EHV_FIVRA_CPU1_LSET4
                                  2        GND                     
PR1305           Q_RES_0402LF-8.87K,1%,1/16W,EMA 1        PVCCFA_EHV_FIVRA_CPU1_LSET3
                                  2        GND                     
PR1306           Q_RES_0402LF-2.2,1%,1/16W,CHIPA 1        PVCCFA_EHV_FIVRA_CPU1_PVCC1
                                  2        PVCCFA_EHV_FIVRA_CPU1_VDD3
PR1307           Q_RES_0402LF-2.2,1%,1/16W,CHIPA 1        PVCCFA_EHV_FIVRA_CPU1_PVCC2
                                  2        PVCCFA_EHV_FIVRA_CPU1_VDD4
PR1309           Q_RES_0402LF-10K,1%,1/16W,EMPTA 1        P3V3_AUX                
                                  2        PWRGD_PVPP_HBM_CPU0_R   
PR1310           Q_RES_0402LF-18.2K,0.1%,1/16W,A 1        PVPP_HBM_CPU0_FB        
                                  2        SH_PVPP_HBM_CPU0_N      
PR1311           Q_RES_0402LF-0,5%,1/16W,CHIP,CA 1        PVCCD_HV_CPU0_ISYS_R    
                                  2        GND                     
PR1313           Q_RES_0402LF-10K,1%,1/16W,CHIPA 1        P3V3_AUX                
                                  2        PWRGD_PVPP_HBM_CPU1_R   
PR1314           Q_RES_0402LF-18.2K,0.1%,1/16W,B 1        PVPP_HBM_CPU1_FB        
                                  2        SH_PVPP_HBM_CPU1_N      
PR1315           Q_RES_0402LF-0,5%,1/16W,CHIP,CA 1        PVCCD_HV_CPU1_ISYS_R    
                                  2        GND                     
PR1317           Q_RES_0402LF-10K,1%,1/16W,CHIPA 1        P3V3_AUX                
                                  2        PWRGD_PVNN_MAIN_CPU0_R  
PR1320           Q_RES_0402LF-10K,1%,1/16W,CHIPA 1        P3V3_AUX                
                                  2        PWRGD_PVNN_MAIN_CPU1_R  
PR1322           Q_RES_0402LF-0,5%,1/16W,CHIP,CA 1        PVCCFA_EHV_FIVRA_CPU0_VOS1
                                  2        PVCCFA_EHV_FIVRA_CPU0   
PR1323           Q_RES_0402LF-0,5%,1/16W,CHIP,CA 1        PVCCFA_EHV_FIVRA_CPU0_VOS2
                                  2        PVCCFA_EHV_FIVRA_CPU0   
PR1324           Q_RES_0402LF-0,5%,1/16W,EMPTY,A 1        PVCCFA_EHV_FIVRA_CPU0_VOS3
                                  2        PVCCFA_EHV_FIVRA_CPU0   
PR1325           Q_RES_0402LF-0,5%,1/16W,EMPTY,A 1        PVCCFA_EHV_FIVRA_CPU0_VOS4
                                  2        PVCCFA_EHV_FIVRA_CPU0   
PR1326           Q_RES_0402LF-0,5%,1/16W,CHIP,CA 1        P3V3_AUX                
                                  2        P1V05_PCH_AUX_VCC       
PR1327           Q_RES_0402LF-6.81K,1%,1/16W,CHA 1        P1V05_PCH_AUX_CS        
                                  2        GND                     
PR1328           Q_RES_0402LF-7.32K,1%,1/16W,CHA 1        P1V05_PCH_AUX_FB        
                                  2        SH_P1V05_PCH_AUX_P      
PR1329           Q_RES_0402LF-5.1,5%,1/16W,CHIPA 1        PVCC1_AUX               
                                  2        P1V8_PCH_AUX_VCC        
PR1330           Q_RES_0402LF-150K,1%,1/16W,CHIA 1        P1V8_PCH_AUX_MODE       
                                  2        GND                     
PR1331           Q_RES_0402LF-0,5%,1/16W,CHIP,CA 1        PVCCFA_EHV_FIVRA_CPU1_VOS1
                                  2        PVCCFA_EHV_FIVRA_CPU1   
PR1332           Q_RES_0402LF-0,5%,1/16W,CHIP,CA 1        PVCCFA_EHV_FIVRA_CPU1_VOS2
                                  2        PVCCFA_EHV_FIVRA_CPU1   
PR1333           Q_RES_0402LF-0,5%,1/16W,CHIP,CA 1        PVCCFA_EHV_FIVRA_CPU1_VOS3
                                  2        PVCCFA_EHV_FIVRA_CPU1   
PR1334           Q_RES_0402LF-0,5%,1/16W,CHIP,CA 1        PVCCFA_EHV_FIVRA_CPU1_VOS4
                                  2        PVCCFA_EHV_FIVRA_CPU1   
PR1335           Q_RES_0402LF-0,5%,1/16W,EMPTY,A 1        P3V3_AUX                
                                  2        PVPP_HBM_CPU0_VCC       
PR1336           Q_RES_0402LF-8.87K,1%,1/16W,EMA 1        PVPP_HBM_CPU0_CS        
                                  2        GND                     
PR1337           Q_RES_0402LF-36K,1%,1/16W,EMPTA 1        PVPP_HBM_CPU0_FB        
                                  2        SH_PVPP_HBM_CPU0_P      
PR1338           Q_RES_0402LF-0,5%,1/16W,CHIP,CA 1        P3V3_AUX                
                                  2        PVPP_HBM_CPU1_VCC       
PR1339           Q_RES_0402LF-9.31K,1%,1/16W,CHA 1        PVPP_HBM_CPU1_CS        
                                  2        GND                     
PR1340           Q_RES_0402LF-36K,1%,1/16W,CHIPA 1        PVPP_HBM_CPU1_FB        
                                  2        SH_PVPP_HBM_CPU1_P      
PR1380           Q_RES_0402LF-49.9     ,1%  ,1/A 1        P12V_S3_AUX_CPU0_NVDIMM_ISENS_1
                                  2        PVCCD_HV_CPU0_ISENSE_P  
PR1388           Q_RES_0402LF-0,5%,1/16W,EMPTY,A 2        FM_P1V05_PCH_AUX_R_EN   
PR1389           Q_RES_0402LF-0,5%,1/16W,CHIP,CA 1        FM_P1V05_PCH_AUX_EN     
                                  2        FM_P1V05_PCH_AUX_R_EN   
PR1390           Q_RES_0402LF-49.9     ,1%  ,1/A 1        P12V_S3_AUX_CPU0_NVDIMM_ISENSE_
                                  2        PVCCD_HV_CPU0_ISENSE_N  
PR1400           Q_RES_0402LF-49.9     ,1%  ,1/A 1        P12V_S3_AUX_CPU1_NVDIMM_ISENS_1
                                  2        PVCCD_HV_CPU1_ISENSE_P  
PR1410           Q_RES_0402LF-49.9     ,1%  ,1/A 1        P12V_S3_AUX_CPU1_NVDIMM_ISENSE_
                                  2        PVCCD_HV_CPU1_ISENSE_N  
PR1647           Q_RES_0402LF-10K,1%,1/16W,EMPTA 1        P3V3_AUX                
                                  2        FM_P1V05_PCH_AUX_R_EN   
PR1650           Q_RES_0402LF-0,5%,1/16W,CHIP,CA 1        PWRGD_P1V05_PCH_AUX_R   
                                  2        PWRGD_P1V05_PCH_AUX     
PR1651           Q_RES_0402LF-0,5%,1/16W,CHIP,CA 1        PWRGD_P1V8_PCH_AUX_R    
                                  2        PWRGD_P1V8_PCH_AUX      
PR1707           Q_RES_0402LF-8.87K,1%,1/16W,EMA 1        PVCCINFAON_CPU0_LSET2   
                                  2        GND                     
PR1708           Q_RES_0402LF-8.87K,1%,1/16W,EMA 1        PVCCINFAON_CPU0_LSET1   
                                  2        GND                     
PR1709           Q_RES_0402LF-8.87K,1%,1/16W,EMA 1        PVCCFA_EHV_CPU0_LSET1   
                                  2        GND                     
PR1718           Q_RES_0402LF-49.9     ,1%  ,1/A 1        PVNN_TERM_CPU1          
                                  2        SVID_CLK1_CPU1_R        
PR1726           Q_RES_0402LF-8.87K,1%,1/16W,EMA 1        PVCCINFAON_CPU1_LSET1   
                                  2        GND                     
PR1727           Q_RES_0402LF-8.87K,1%,1/16W,EMA 1        PVCCINFAON_CPU1_LSET2   
                                  2        GND                     
PR1728           Q_RES_0402LF-8.87K,1%,1/16W,EMA 1        PVCCFA_EHV_CPU1_LSET1   
                                  2        GND                     
PR1746           Q_RES_0402LF-8.87K,1%,1/16W,EMA 1        PVCCD_HV_CPU1_LSET1     
                                  2        GND                     
PR1747           Q_RES_0402LF-100,1%,1/16W,CHIPA 1        PVNN_TERM_CPU1          
                                  2        SVID_DIO1_CPU1_R        
PR1766           Q_RES_0402LF-3.3,1%,1/16W,CHIPA 1        SW_PVCCIN_CPU1_BOOT2    
                                  2        SW_PVCCIN_CPU1_BOOT2_R  
PR1767           Q_RES_0402LF-3.3,1%,1/16W,CHIPA 1        SW_PVCCIN_CPU1_BOOT1    
                                  2        SW_PVCCIN_CPU1_BOOT1_R  
PR1768           Q_RES_0402LF-3.3,1%,1/16W,CHIPA 1        SW_PVCCIN_CPU0_BOOT4    
                                  2        SW_PVCCIN_CPU0_BOOT4_R  
PR1769           Q_RES_0402LF-3.3,1%,1/16W,CHIPA 1        SW_PVCCIN_CPU0_BOOT3    
                                  2        SW_PVCCIN_CPU0_BOOT3_R  
PR1770           Q_RES_0402LF-3.3,1%,1/16W,CHIPA 1        SW_PVCCIN_CPU0_BOOT6    
                                  2        SW_PVCCIN_CPU0_BOOT6_R  
PR1771           Q_RES_0402LF-3.3,1%,1/16W,CHIPA 1        SW_PVCCIN_CPU0_BOOT5    
                                  2        SW_PVCCIN_CPU0_BOOT5_R  
PR1772           Q_RES_0402LF-3.3,1%,1/16W,CHIPA 1        SW_PVCCIN_CPU0_BOOT8    
                                  2        SW_PVCCIN_CPU0_BOOT8_R  
PR1773           Q_RES_0402LF-3.3,1%,1/16W,CHIPA 1        SW_PVCCIN_CPU0_BOOT7    
                                  2        SW_PVCCIN_CPU0_BOOT7_R  
PR1774           Q_RES_0402LF-4.7,1%,1/16W,CHIPA 1        SW_PVCCINFAON_CPU0_BOOT1
                                  2        SW_PVCCINFAON_CPU0_BOOT1_R
PR1775           Q_RES_0402LF-4.7,1%,1/16W,CHIPA 1        SW_PVCCINFAON_CPU0_BOOT2
                                  2        SW_PVCCINFAON_CPU0_BOOT2_R
PR1776           Q_RES_0402LF-0,5%,1/16W,CHIP,CA 1        PVCCINFAON_CPU0_PH1_NC1 
                                  2        PVCCINFAON_CPU0_VDD1    
PR1777           Q_RES_0402LF-0,5%,1/16W,CHIP,CA 1        PVCCINFAON_CPU0_PH2_NC1 
                                  2        PVCCINFAON_CPU0_VDD2    
PR1778           Q_RES_0402LF-4.7,1%,1/16W,CHIPA 1        SW_PVCCFA_EHV_CPU0_BOOT1
                                  2        SW_PVCCFA_EHV_CPU0_BOOT1_R
PR1779           Q_RES_0402LF-0,5%,1/16W,CHIP,CA 1        PVCCFA_EHV_CPU0_NC1     
                                  2        PVCCFA_EHV_CPU0_VDD1    
PR1780           Q_RES_0402LF-3.3,1%,1/16W,CHIPA 1        SW_PVCCFA_EHV_FIVRA_CPU0_BOOT1
                                  2        SW_PVCCFA_EHV_FIVRA_CPU0_BOOT1_
PR1781           Q_RES_0402LF-3.3,1%,1/16W,CHIPA 1        SW_PVCCFA_EHV_FIVRA_CPU0_BOOT2
                                  2        SW_PVCCFA_EHV_FIVRA_CPU0_BOOT2_
PR1782           Q_RES_0402LF-3.3,1%,1/16W,EMPTA 1        SW_PVCCFA_EHV_FIVRA_CPU0_BOOT3
                                  2        SW_PVCCFA_EHV_FIVRA_CPU0_BOOT3_
PR1783           Q_RES_0402LF-3.3,1%,1/16W,EMPTA 1        SW_PVCCFA_EHV_FIVRA_CPU0_BOOT4
                                  2        SW_PVCCFA_EHV_FIVRA_CPU0_BOOT4_
PR1784           Q_RES_0402LF-4.7,1%,1/16W,CHIPA 1        SW_PVCCD_HV_CPU0_BOOT1  
                                  2        SW_PVCCD_HV_CPU0_BOOT1_R
PR1785           Q_RES_0402LF-0,5%,1/16W,CHIP,CA 1        PVCCD_HV_CPU0_NC1       
                                  2        PVCCD_HV_CPU0_VDD1      
PR1786           Q_RES_0402LF-3.3,1%,1/16W,CHIPA 1        SW_PVCCIN_CPU0_BOOT2    
                                  2        SW_PVCCIN_CPU0_BOOT2_R  
PR1787           Q_RES_0402LF-3.3,1%,1/16W,CHIPA 1        SW_PVCCIN_CPU0_BOOT1    
                                  2        SW_PVCCIN_CPU0_BOOT1_R  
PR1788           Q_RES_0402LF-3.3,1%,1/16W,CHIPA 1        SW_PVCCIN_CPU1_BOOT4    
                                  2        SW_PVCCIN_CPU1_BOOT4_R  
PR1789           Q_RES_0402LF-3.3,1%,1/16W,CHIPA 1        SW_PVCCIN_CPU1_BOOT3    
                                  2        SW_PVCCIN_CPU1_BOOT3_R  
PR1790           Q_RES_0402LF-3.3,1%,1/16W,CHIPA 1        SW_PVCCIN_CPU1_BOOT6    
                                  2        SW_PVCCIN_CPU1_BOOT6_R  
PR1791           Q_RES_0402LF-3.3,1%,1/16W,CHIPA 1        SW_PVCCIN_CPU1_BOOT5    
                                  2        SW_PVCCIN_CPU1_BOOT5_R  
PR1792           Q_RES_0402LF-3.3,1%,1/16W,CHIPA 1        SW_PVCCIN_CPU1_BOOT8    
                                  2        SW_PVCCIN_CPU1_BOOT8_R  
PR1793           Q_RES_0402LF-3.3,1%,1/16W,CHIPA 1        SW_PVCCIN_CPU1_BOOT7    
                                  2        SW_PVCCIN_CPU1_BOOT7_R  
PR1794           Q_RES_0402LF-4.7,1%,1/16W,CHIPA 1        SW_PVCCINFAON_CPU1_BOOT1
                                  2        SW_PVCCINFAON_CPU1_BOOT1_R
PR1795           Q_RES_0402LF-4.7,1%,1/16W,CHIPA 1        SW_PVCCINFAON_CPU1_BOOT2
                                  2        SW_PVCCINFAON_CPU1_BOOT2_R
PR1796           Q_RES_0402LF-0,5%,1/16W,CHIP,CA 1        PVCCINFAON_CPU1_PH1_NC1 
                                  2        PVCCINFAON_CPU1_VDD1    
PR1797           Q_RES_0402LF-0,5%,1/16W,CHIP,CA 1        PVCCINFAON_CPU1_PH2_NC1 
                                  2        PVCCINFAON_CPU1_VDD2    
PR1798           Q_RES_0402LF-4.7,1%,1/16W,CHIPA 1        SW_PVCCFA_EHV_CPU1_BOOT1
                                  2        SW_PVCCFA_EHV_CPU1_BOOT1_R
PR1799           Q_RES_0402LF-0,5%,1/16W,CHIP,CA 1        PVCCFA_EHV_CPU1_NC1     
                                  2        PVCCFA_EHV_CPU1_VDD1    
PR1800           Q_RES_0402LF-3.3,1%,1/16W,CHIPA 1        SW_PVCCFA_EHV_FIVRA_CPU1_BOOT1
                                  2        SW_PVCCFA_EHV_FIVRA_CPU1_BOOT1_
PR1801           Q_RES_0402LF-3.3,1%,1/16W,CHIPA 1        SW_PVCCFA_EHV_FIVRA_CPU1_BOOT2
                                  2        SW_PVCCFA_EHV_FIVRA_CPU1_BOOT2_
PR1802           Q_RES_0402LF-3.3,1%,1/16W,CHIPA 1        SW_PVCCFA_EHV_FIVRA_CPU1_BOOT3
                                  2        SW_PVCCFA_EHV_FIVRA_CPU1_BOOT3_
PR1803           Q_RES_0402LF-3.3,1%,1/16W,CHIPA 1        SW_PVCCFA_EHV_FIVRA_CPU1_BOOT4
                                  2        SW_PVCCFA_EHV_FIVRA_CPU1_BOOT4_
PR1804           Q_RES_0402LF-4.7,1%,1/16W,CHIPA 1        SW_PVCCD_HV_CPU1_BOOT1  
                                  2        SW_PVCCD_HV_CPU1_BOOT1_R
PR1805           Q_RES_0402LF-0,5%,1/16W,CHIP,CA 1        PVCCD_HV_CPU1_NC1       
                                  2        PVCCD_HV_CPU1_VDD1      
PR1945           Q_RES_0402LF-510K,5%,1/16W,CHIA 1        P12V_AUX                
                                  2        P5V_AUX_EN              
PR1948           Q_RES_0402LF-75K,1%,1/16W,CHIPA 1        P5V_AUX_EN              
                                  2        GND                     
PR2220           Q_RES_0402LF-60.4K,1%,1/16W,CHA 1        PVNN_MAIN_CPU1_MODE     
                                  2        GND                     
PR2222           Q_RES_0402LF-9.09K,1%,1/16W,CHA 1        PVNN_MAIN_CPU1_CS       
                                  2        GND                     
PR2390           Q_RES_0402LF-0,5%,1/16W,CHIP,CA 1        PWRGD_P1V05_PCH_AUX_R   
                                  2        PWRGD_PVNN_PCH_AUX      
PR2718           Q_RES_0402LF-8.87K,1%,1/16W,EMA 1        PVCCD_HV_CPU0_LSET1     
                                  2        GND                     
PU5              ISL69260IRAZT-ISL69260IRAZ-T,SA 1        PVCCFA_EHV_CPU0_BPWM1   
                                  7        PVCCINFAON_CPU0_APWM2   
                                  8        PVCCINFAON_CPU0_APWM1   
                                  9        SMB_DIO_PVCCINFAON_CPU0 
                                  10       SMB_CLK_PVCCINFAON_CPU0 
                                  12       PWRGD_PVCCINFAON_CPU0_R 
                                  13       PVCCINFAON_CPU0_EN_R    
                                  14       IRQ_CPU0_VRHOT_N        
                                  15       PVCCINFAON_CPU0_PIN_ALERT
                                  16       PWRGD_PVCCFA_EHV_CPU0_R 
                                  17       SVID_CLK_PVCCINFAON_CPU0_R
                                  18       SVID_DIO_PVCCINFAON_CPU0_R
                                  19       SVID_ALERT_PVCCINFAON_CPU0_R
                                  20       PVCCFA_EHV_CPU0_EN_R    
                                  21       SH_PVCCINFAON_CPU0_R    
                                  22       VSENSE_PVCCINFAON_CPU0_DN
                                  23       PVCCINFAON_CPU0_ACSP1   
                                  24       PVCCINFAON_CPU0_ACSP2   
                                  30       PVCCFA_EHV_CPU0_BCSP1   
                                  31       VSENSE_PVCCFA_EHV_CPU0_DN
                                  32       SH_PVCCFA_EHV_CPU0_R    
                                  33       PVCCINFAON_CPU0_VR_FAULT
                                  34       PVCCINFAON_CPU0_ADDR    
                                  35       PVCCINFAON_CPU0_ATSEN   
                                  36       PVCCFA_EHV_CPU0_BTSEN   
                                  37       PVCCINFAON_CPU0_CSPIN   
                                  38       PVCCINFAON_CPU0_VIN_CSNIN
                                  39       PVCCINFAON_CPU0_VCC     
                                  40       PVCCINFAON_CPU0_VREF    
                                  TH       GND                     
PU6_P0_8         ISL99390FRZTR5935-ISL99390FRZ-A 1        PVCCIN_CPU0_VOS8        
                                  10_19    SW_PVCCIN_CPU0_SW8      
                                  2        GND                     
                                  25_29    SW_P12V_PVCCIN_CPU0_FLT 
                                  3        PVCCIN_CPU0_VDD8        
                                  4        PVCCIN_CPU0_PVCC        
                                  5        GND                     
                                  30       SW_P12V_PVCCIN_CPU0_FLT 
                                  32       SW_PVCCIN_CPU0_BOOTR8   
                                  33       SW_PVCCIN_CPU0_BOOT8    
                                  34       PVCCIN_CPU0_PWM8        
                                  35       PVCCIN_CPU0_VDD8        
                                  36       PVCCIN_CPU0_ATSEN       
                                  37       PVCCIN_CPU0_LSET8       
                                  38       PVCCIN_CPU0_IMON8       
                                  39       PVCCIN_CPU0_VREF        
                                  40       GND                     
                                  7_9-20_24 GND                     
PU7_P0_7         ISL99390FRZTR5935-ISL99390FRZ-A 1        PVCCIN_CPU0_VOS7        
                                  10_19    SW_PVCCIN_CPU0_SW7      
                                  2        GND                     
                                  25_29    SW_P12V_PVCCIN_CPU0_FLT 
                                  3        PVCCIN_CPU0_VDD7        
                                  4        PVCCIN_CPU0_PVCC        
                                  5        GND                     
                                  30       SW_P12V_PVCCIN_CPU0_FLT 
                                  32       SW_PVCCIN_CPU0_BOOTR7   
                                  33       SW_PVCCIN_CPU0_BOOT7    
                                  34       PVCCIN_CPU0_PWM7        
                                  35       PVCCIN_CPU0_VDD7        
                                  36       PVCCIN_CPU0_ATSEN       
                                  37       PVCCIN_CPU0_LSET7       
                                  38       PVCCIN_CPU0_IMON7       
                                  39       PVCCIN_CPU0_VREF        
                                  40       GND                     
                                  7_9-20_24 GND                     
PU8_P0_6         ISL99390FRZTR5935-ISL99390FRZ-A 1        PVCCIN_CPU0_VOS6        
                                  10_19    SW_PVCCIN_CPU0_SW6      
                                  2        GND                     
                                  25_29    SW_P12V_PVCCIN_CPU0_FLT 
                                  3        PVCCIN_CPU0_VDD6        
                                  4        PVCCIN_CPU0_PVCC        
                                  5        GND                     
                                  30       SW_P12V_PVCCIN_CPU0_FLT 
                                  32       SW_PVCCIN_CPU0_BOOTR6   
                                  33       SW_PVCCIN_CPU0_BOOT6    
                                  34       PVCCIN_CPU0_PWM6        
                                  35       PVCCIN_CPU0_VDD6        
                                  36       PVCCIN_CPU0_ATSEN       
                                  37       PVCCIN_CPU0_LSET6       
                                  38       PVCCIN_CPU0_IMON6       
                                  39       PVCCIN_CPU0_VREF        
                                  40       GND                     
                                  7_9-20_24 GND                     
PU9              NCP3284MNTXG-NCP3284MNTXG,SMLFA 1        P3V3_AUX_ILIM           
                                  11_18    SW_P3V3_AUX_SW          
                                  2        PWRGD_P3V3_AUX          
                                  20_24    SW_P3V3_AUX_FLT         
                                  3        P5V_AUX                 
                                  4        P3V3_AUX_VCC            
                                  5        P5V_AUX                 
                                  25       SW_P3V3_AUX_BOOTR       
                                  26       SW_P3V3_AUX_BOOT        
                                  27       PWRGD_P5V_AUX           
                                  28       P3V3_AUX_VOS            
                                  29       P3V3_AUX_SS             
                                  30       P3V3_AUX_FB             
                                  31       GND                     
                                  32       GND                     
                                  36       P3V3_AUX_MODE           
                                  7_10-19  GND                     
PU9_P0_5         ISL99390FRZTR5935-ISL99390FRZ-A 1        PVCCIN_CPU0_VOS5        
                                  10_19    SW_PVCCIN_CPU0_SW5      
                                  2        GND                     
                                  25_29    SW_P12V_PVCCIN_CPU0_FLT 
                                  3        PVCCIN_CPU0_VDD5        
                                  4        PVCCIN_CPU0_PVCC        
                                  5        GND                     
                                  30       SW_P12V_PVCCIN_CPU0_FLT 
                                  32       SW_PVCCIN_CPU0_BOOTR5   
                                  33       SW_PVCCIN_CPU0_BOOT5    
                                  34       PVCCIN_CPU0_PWM5        
                                  35       PVCCIN_CPU0_VDD5        
                                  36       PVCCIN_CPU0_ATSEN       
                                  37       PVCCIN_CPU0_LSET5       
                                  38       PVCCIN_CPU0_IMON5       
                                  39       PVCCIN_CPU0_VREF        
                                  40       GND                     
                                  7_9-20_24 GND                     
PU10_P0_4        ISL99390FRZTR5935-ISL99390FRZ-A 1        PVCCIN_CPU0_VOS4        
                                  10_19    SW_PVCCIN_CPU0_SW4      
                                  2        GND                     
                                  25_29    SW_P12V_PVCCIN_CPU0_FLT 
                                  3        PVCCIN_CPU0_VDD4        
                                  4        PVCCIN_CPU0_PVCC        
                                  5        GND                     
                                  30       SW_P12V_PVCCIN_CPU0_FLT 
                                  32       SW_PVCCIN_CPU0_BOOTR4   
                                  33       SW_PVCCIN_CPU0_BOOT4    
                                  34       PVCCIN_CPU0_PWM4        
                                  35       PVCCIN_CPU0_VDD4        
                                  36       PVCCIN_CPU0_ATSEN       
                                  37       PVCCIN_CPU0_LSET4       
                                  38       PVCCIN_CPU0_IMON4       
                                  39       PVCCIN_CPU0_VREF        
                                  40       GND                     
                                  7_9-20_24 GND                     
PU11_P0_3        ISL99390FRZTR5935-ISL99390FRZ-A 1        PVCCIN_CPU0_VOS3        
                                  10_19    SW_PVCCIN_CPU0_SW3      
                                  2        GND                     
                                  25_29    SW_P12V_PVCCIN_CPU0_FLT 
                                  3        PVCCIN_CPU0_VDD3        
                                  4        PVCCIN_CPU0_PVCC        
                                  5        GND                     
                                  30       SW_P12V_PVCCIN_CPU0_FLT 
                                  32       SW_PVCCIN_CPU0_BOOTR3   
                                  33       SW_PVCCIN_CPU0_BOOT3    
                                  34       PVCCIN_CPU0_PWM3        
                                  35       PVCCIN_CPU0_VDD3        
                                  36       PVCCIN_CPU0_ATSEN       
                                  37       PVCCIN_CPU0_LSET3       
                                  38       PVCCIN_CPU0_IMON3       
                                  39       PVCCIN_CPU0_VREF        
                                  40       GND                     
                                  7_9-20_24 GND                     
PU12_P0_2        ISL99390FRZTR5935-ISL99390FRZ-A 1        PVCCIN_CPU0_VOS2        
                                  10_19    SW_PVCCIN_CPU0_SW2      
                                  2        GND                     
                                  25_29    SW_P12V_PVCCIN_CPU0_FLT 
                                  3        PVCCIN_CPU0_VDD2        
                                  4        PVCCIN_CPU0_PVCC        
                                  5        GND                     
                                  30       SW_P12V_PVCCIN_CPU0_FLT 
                                  32       SW_PVCCIN_CPU0_BOOTR2   
                                  33       SW_PVCCIN_CPU0_BOOT2    
                                  34       PVCCIN_CPU0_PWM2        
                                  35       PVCCIN_CPU0_VDD2        
                                  36       PVCCIN_CPU0_ATSEN       
                                  37       PVCCIN_CPU0_LSET2       
                                  38       PVCCIN_CPU0_IMON2       
                                  39       PVCCIN_CPU0_VREF        
                                  40       GND                     
                                  7_9-20_24 GND                     
PU13_P0_1        ISL99390FRZTR5935-ISL99390FRZ-A 1        PVCCIN_CPU0_VOS1        
                                  10_19    SW_PVCCIN_CPU0_SW1      
                                  2        GND                     
                                  25_29    SW_P12V_PVCCIN_CPU0_FLT 
                                  3        PVCCIN_CPU0_VDD1        
                                  4        PVCCIN_CPU0_PVCC        
                                  5        GND                     
                                  30       SW_P12V_PVCCIN_CPU0_FLT 
                                  32       SW_PVCCIN_CPU0_BOOTR1   
                                  33       SW_PVCCIN_CPU0_BOOT1    
                                  34       PVCCIN_CPU0_PWM1        
                                  35       PVCCIN_CPU0_VDD1        
                                  36       PVCCIN_CPU0_ATSEN       
                                  37       PVCCIN_CPU0_LSET1       
                                  38       PVCCIN_CPU0_IMON1       
                                  39       PVCCIN_CPU0_VREF        
                                  40       GND                     
                                  7_9-20_24 GND                     
PU14             RAA229126GNPHA0-RAA229126GNP#HA 1        PVCCFA_EHV_FIVRA_CPU0_PWM1
                                  2        PVCCFA_EHV_FIVRA_CPU0_PWM2
                                  5        PVCCIN_CPU0_PWM8        
                                  6        PVCCIN_CPU0_PWM7        
                                  7        PVCCIN_CPU0_PWM6        
                                  8        PVCCIN_CPU0_PWM5        
                                  9        PVCCIN_CPU0_PWM4        
                                  10       PVCCIN_CPU0_PWM3        
                                  11       PVCCIN_CPU0_PWM2        
                                  12       PVCCIN_CPU0_PWM1        
                                  13       SMB_DIO_PVCCIN_CPU0     
                                  14       SMB_CLK_PVCCIN_CPU0     
                                  16       PWRGD_PVCCIN_CPU0_R     
                                  17       PVCCIN_CPU0_EN_R        
                                  18       IRQ_CPU0_VRHOT_N        
                                  19       PVCCIN_CPU0_PIN_ALERT   
                                  20       PWRGD_PVCCFA_EHV_FIVRA_CPU0_R
                                  21       SVID_CLK_PVCCIN_CPU0_R  
                                  22       SVID_DIO_PVCCIN_CPU0_R  
                                  23       SVID_ALERT_PVCCIN_CPU0_R
                                  24       PVCCFA_EHV_FIVRA_CPU0_EN_R
                                  25       SH_PVCCIN_CPU0_R        
                                  26       VSENSE_PVCCIN_CPU0_DN   
                                  27       PVCCIN_CPU0_IMON1       
                                  28       PVCCIN_CPU0_IMON2       
                                  29       PVCCIN_CPU0_IMON3       
                                  30       PVCCIN_CPU0_IMON4       
                                  31       PVCCIN_CPU0_IMON5       
                                  32       PVCCIN_CPU0_IMON6       
                                  33       PVCCIN_CPU0_IMON7       
                                  34       PVCCIN_CPU0_IMON8       
                                  37       PVCCFA_EHV_FIVRA_CPU0_IMON2
                                  38       PVCCFA_EHV_FIVRA_CPU0_IMON1
                                  39       VSENSE_PVCCFA_EHV_FIVRA_CPU0_DN
                                  40       SH_PVCCFA_EHV_FIVRA_CPU0_R
                                  41       PVCCIN_CPU0_VR_FAULT    
                                  42       PVCCIN_CPU0_ADDR        
                                  43       PVCCIN_CPU0_ATSEN       
                                  44       PVCCIN_CPU0_ISYS_R      
                                  45       PVCCIN_CPU0_CSPIN       
                                  46       PVCCIN_CPU0_VIN_CSNIN   
                                  47       PVCCIN_CPU0_VCC         
                                  48       PVCCIN_CPU0_VREF        
                                  TH       GND                     
PU17             RAA2213404GNPHB0-RAA2213404GNPA 1        PVCCD_HV_CPU1_ATSEN     
                                  16_18-28 SW_P12V_PVCCINFAON_CPU1_FLT
                                  2        GND                     
                                  3        PVCCD_HV_CPU1_NC1       
                                  4        PVCCD_HV_CPU1_VDD1      
                                  5        PVCCD_HV_CPU1_LSET1     
                                  19       SW_PVCCD_HV_CPU1_BOOTR1 
                                  20       SW_PVCCD_HV_CPU1_BOOT1  
                                  21       PVCCD_HV_CPU1_APWM1     
                                  22       PVCCD_HV_CPU1_VDD1      
                                  23       GND                     
                                  24       PVCCD_HV_CPU1_VREF      
                                  25       PVCCD_HV_CPU1_ACSP1     
                                  26       GND                     
                                  6_7-13_15-29 GND                     
                                  8_12     SW_PVCCD_HV_CPU1_SW1    
PU18             ISL69260IRAZT-ISL69260IRAZ-T,SA 8        PVCCD_HV_CPU1_APWM1     
                                  9        SMB_DIO_PVCCD_HV_CPU1   
                                  10       SMB_CLK_PVCCD_HV_CPU1   
                                  12       PWRGD_PVCCD_HV_CPU1_R   
                                  13       PVCCD_HV_CPU1_EN_R      
                                  14       IRQ_PVCCD_CPU1_VRHOT_LVC3_N
                                  15       PVCCD_HV_CPU1_PIN_ALT   
                                  17       SVID_CLK_PVCCD_HV_CPU1_R
                                  18       SVID_DIO_PVCCD_HV_CPU1_R
                                  19       SVID_ALERT_PVCCD_HV_CPU1_R
                                  20       GND                     
                                  21       SH_PVCCD_HV_CPU1_R      
                                  22       VSENSE_PVCCD_HV_CPU1_DN 
                                  23       PVCCD_HV_CPU1_ACSP1     
                                  31       GND                     
                                  32       GND                     
                                  33       PVCCD_HV_CPU1_FAULT     
                                  34       PVCCD_HV_CPU1_ADDR      
                                  35       PVCCD_HV_CPU1_ATSEN     
                                  36       PVCCD_HV_CPU1_ISYS_R    
                                  37       PVCCD_HV_CPU1_ISENSE_P  
                                  38       PVCCD_HV_CPU1_ISENSE_N  
                                  39       PVCCD_HV_CPU1_VCC       
                                  40       PVCCD_HV_CPU1_VREF      
                                  TH       GND                     
PU22             ISL69260IRAZT-ISL69260IRAZ-T,SA 1        PVCCFA_EHV_CPU1_BPWM1   
                                  7        PVCCINFAON_CPU1_APWM2   
                                  8        PVCCINFAON_CPU1_APWM1   
                                  9        SMB_DIO_PVCCINFAON_CPU1 
                                  10       SMB_CLK_PVCCINFAON_CPU1 
                                  12       PWRGD_PVCCINFAON_CPU1_R 
                                  13       PVCCINFAON_CPU1_EN_R    
                                  14       IRQ_CPU1_VRHOT_N        
                                  15       PVCCINFAON_CPU1_PIN_ALERT
                                  16       PWRGD_PVCCFA_EHV_CPU1_R 
                                  17       SVID_CLK_PVCCINFAON_CPU1_R
                                  18       SVID_DIO_PVCCINFAON_CPU1_R
                                  19       SVID_ALERT_PVCCINFAON_CPU1_R
                                  20       PVCCFA_EHV_CPU1_EN_R    
                                  21       SH_PVCCINFAON_CPU1_R    
                                  22       VSENSE_PVCCINFAON_CPU1_DN
                                  23       PVCCINFAON_CPU1_ACSP1   
                                  24       PVCCINFAON_CPU1_ACSP2   
                                  30       PVCCFA_EHV_CPU1_BCSP1   
                                  31       VSENSE_PVCCFA_EHV_CPU1_DN
                                  32       SH_PVCCFA_EHV_CPU1_R    
                                  33       PVCCINFAON_CPU1_VR_FAULT
                                  34       PVCCINFAON_CPU1_ADDR    
                                  35       PVCCINFAON_CPU1_ATSEN   
                                  36       PVCCFA_EHV_CPU1_BTSEN   
                                  37       PVCCINFAON_CPU1_CSPIN   
                                  38       PVCCINFAON_CPU1_VIN_CSNIN
                                  39       PVCCINFAON_CPU1_VCC     
                                  40       PVCCINFAON_CPU1_VREF    
                                  TH       GND                     
PU23_P1_8        ISL99390FRZTR5935-ISL99390FRZ-A 1        PVCCIN_CPU1_VOS8        
                                  10_19    SW_PVCCIN_CPU1_SW8      
                                  2        GND                     
                                  25_29    SW_P12V_PVCCIN_CPU1_FLT 
                                  3        PVCCIN_CPU1_VDD8        
                                  4        PVCCIN_CPU1_PVCC        
                                  5        GND                     
                                  30       SW_P12V_PVCCIN_CPU1_FLT 
                                  32       SW_PVCCIN_CPU1_BOOTR8   
                                  33       SW_PVCCIN_CPU1_BOOT8    
                                  34       PVCCIN_CPU1_PWM8        
                                  35       PVCCIN_CPU1_VDD8        
                                  36       PVCCIN_CPU1_ATSEN       
                                  37       PVCCIN_CPU1_LSET8       
                                  38       PVCCIN_CPU1_IMON8       
                                  39       PVCCIN_CPU1_VREF        
                                  40       GND                     
                                  7_9-20_24 GND                     
PU24_P1_7        ISL99390FRZTR5935-ISL99390FRZ-A 1        PVCCIN_CPU1_VOS7        
                                  10_19    SW_PVCCIN_CPU1_SW7      
                                  2        GND                     
                                  25_29    SW_P12V_PVCCIN_CPU1_FLT 
                                  3        PVCCIN_CPU1_VDD7        
                                  4        PVCCIN_CPU1_PVCC        
                                  5        GND                     
                                  30       SW_P12V_PVCCIN_CPU1_FLT 
                                  32       SW_PVCCIN_CPU1_BOOTR7   
                                  33       SW_PVCCIN_CPU1_BOOT7    
                                  34       PVCCIN_CPU1_PWM7        
                                  35       PVCCIN_CPU1_VDD7        
                                  36       PVCCIN_CPU1_ATSEN       
                                  37       PVCCIN_CPU1_LSET7       
                                  38       PVCCIN_CPU1_IMON7       
                                  39       PVCCIN_CPU1_VREF        
                                  40       GND                     
                                  7_9-20_24 GND                     
PU25_P1_6        ISL99390FRZTR5935-ISL99390FRZ-A 1        PVCCIN_CPU1_VOS6        
                                  10_19    SW_PVCCIN_CPU1_SW6      
                                  2        GND                     
                                  25_29    SW_P12V_PVCCIN_CPU1_FLT 
                                  3        PVCCIN_CPU1_VDD6        
                                  4        PVCCIN_CPU1_PVCC        
                                  5        GND                     
                                  30       SW_P12V_PVCCIN_CPU1_FLT 
                                  32       SW_PVCCIN_CPU1_BOOTR6   
                                  33       SW_PVCCIN_CPU1_BOOT6    
                                  34       PVCCIN_CPU1_PWM6        
                                  35       PVCCIN_CPU1_VDD6        
                                  36       PVCCIN_CPU1_ATSEN       
                                  37       PVCCIN_CPU1_LSET6       
                                  38       PVCCIN_CPU1_IMON6       
                                  39       PVCCIN_CPU1_VREF        
                                  40       GND                     
                                  7_9-20_24 GND                     
PU26_P1_5        ISL99390FRZTR5935-ISL99390FRZ-A 1        PVCCIN_CPU1_VOS5        
                                  10_19    SW_PVCCIN_CPU1_SW5      
                                  2        GND                     
                                  25_29    SW_P12V_PVCCIN_CPU1_FLT 
                                  3        PVCCIN_CPU1_VDD5        
                                  4        PVCCIN_CPU1_PVCC        
                                  5        GND                     
                                  30       SW_P12V_PVCCIN_CPU1_FLT 
                                  32       SW_PVCCIN_CPU1_BOOTR5   
                                  33       SW_PVCCIN_CPU1_BOOT5    
                                  34       PVCCIN_CPU1_PWM5        
                                  35       PVCCIN_CPU1_VDD5        
                                  36       PVCCIN_CPU1_ATSEN       
                                  37       PVCCIN_CPU1_LSET5       
                                  38       PVCCIN_CPU1_IMON5       
                                  39       PVCCIN_CPU1_VREF        
                                  40       GND                     
                                  7_9-20_24 GND                     
PU27_P1_4        ISL99390FRZTR5935-ISL99390FRZ-A 1        PVCCIN_CPU1_VOS4        
                                  10_19    SW_PVCCIN_CPU1_SW4      
                                  2        GND                     
                                  25_29    SW_P12V_PVCCIN_CPU1_FLT 
                                  3        PVCCIN_CPU1_VDD4        
                                  4        PVCCIN_CPU1_PVCC        
                                  5        GND                     
                                  30       SW_P12V_PVCCIN_CPU1_FLT 
                                  32       SW_PVCCIN_CPU1_BOOTR4   
                                  33       SW_PVCCIN_CPU1_BOOT4    
                                  34       PVCCIN_CPU1_PWM4        
                                  35       PVCCIN_CPU1_VDD4        
                                  36       PVCCIN_CPU1_ATSEN       
                                  37       PVCCIN_CPU1_LSET4       
                                  38       PVCCIN_CPU1_IMON4       
                                  39       PVCCIN_CPU1_VREF        
                                  40       GND                     
                                  7_9-20_24 GND                     
PU28_P1_3        ISL99390FRZTR5935-ISL99390FRZ-A 1        PVCCIN_CPU1_VOS3        
                                  10_19    SW_PVCCIN_CPU1_SW3      
                                  2        GND                     
                                  25_29    SW_P12V_PVCCIN_CPU1_FLT 
                                  3        PVCCIN_CPU1_VDD3        
                                  4        PVCCIN_CPU1_PVCC        
                                  5        GND                     
                                  30       SW_P12V_PVCCIN_CPU1_FLT 
                                  32       SW_PVCCIN_CPU1_BOOTR3   
                                  33       SW_PVCCIN_CPU1_BOOT3    
                                  34       PVCCIN_CPU1_PWM3        
                                  35       PVCCIN_CPU1_VDD3        
                                  36       PVCCIN_CPU1_ATSEN       
                                  37       PVCCIN_CPU1_LSET3       
                                  38       PVCCIN_CPU1_IMON3       
                                  39       PVCCIN_CPU1_VREF        
                                  40       GND                     
                                  7_9-20_24 GND                     
PU29             RAA229126GNPHA0-RAA229126GNP#HA 1        PVCCFA_EHV_FIVRA_CPU1_PWM1
                                  2        PVCCFA_EHV_FIVRA_CPU1_PWM2
                                  3        PVCCFA_EHV_FIVRA_CPU1_PWM3
                                  4        PVCCFA_EHV_FIVRA_CPU1_PWM4
                                  5        PVCCIN_CPU1_PWM8        
                                  6        PVCCIN_CPU1_PWM7        
                                  7        PVCCIN_CPU1_PWM6        
                                  8        PVCCIN_CPU1_PWM5        
                                  9        PVCCIN_CPU1_PWM4        
                                  10       PVCCIN_CPU1_PWM3        
                                  11       PVCCIN_CPU1_PWM2        
                                  12       PVCCIN_CPU1_PWM1        
                                  13       SMB_DIO_PVCCIN_CPU1     
                                  14       SMB_CLK_PVCCIN_CPU1     
                                  16       PWRGD_PVCCIN_CPU1_R     
                                  17       PVCCIN_CPU1_EN_R        
                                  18       IRQ_CPU1_VRHOT_N        
                                  19       PVCCIN_CPU1_PIN_ALERT   
                                  20       PWRGD_PVCCFA_EHV_FIVRA_CPU1_R
                                  21       SVID_CLK_PVCCIN_CPU1_R  
                                  22       SVID_DIO_PVCCIN_CPU1_R  
                                  23       SVID_ALERT_PVCCIN_CPU1_R
                                  24       PVCCFA_EHV_FIVRA_CPU1_EN_R
                                  25       SH_PVCCIN_CPU1_R        
                                  26       VSENSE_PVCCIN_CPU1_DN   
                                  27       PVCCIN_CPU1_IMON1       
                                  28       PVCCIN_CPU1_IMON2       
                                  29       PVCCIN_CPU1_IMON3       
                                  30       PVCCIN_CPU1_IMON4       
                                  31       PVCCIN_CPU1_IMON5       
                                  32       PVCCIN_CPU1_IMON6       
                                  33       PVCCIN_CPU1_IMON7       
                                  34       PVCCIN_CPU1_IMON8       
                                  35       PVCCFA_EHV_FIVRA_CPU1_IMON4
                                  36       PVCCFA_EHV_FIVRA_CPU1_IMON3
                                  37       PVCCFA_EHV_FIVRA_CPU1_IMON2
                                  38       PVCCFA_EHV_FIVRA_CPU1_IMON1
                                  39       VSENSE_PVCCFA_EHV_FIVRA_CPU1_DN
                                  40       SH_PVCCFA_EHV_FIVRA_CPU1_R
                                  41       PVCCIN_CPU1_VR_FAULT    
                                  42       PVCCIN_CPU1_ADDR        
                                  43       PVCCIN_CPU1_ATSEN       
                                  44       PVCCIN_CPU1_ISYS_R      
                                  45       PVCCIN_CPU1_CSPIN       
                                  46       PVCCIN_CPU1_VIN_CSNIN   
                                  47       PVCCIN_CPU1_VCC         
                                  48       PVCCIN_CPU1_VREF        
                                  TH       GND                     
PU30_P1_2        ISL99390FRZTR5935-ISL99390FRZ-A 1        PVCCIN_CPU1_VOS2        
                                  10_19    SW_PVCCIN_CPU1_SW2      
                                  2        GND                     
                                  25_29    SW_P12V_PVCCIN_CPU1_FLT 
                                  3        PVCCIN_CPU1_VDD2        
                                  4        PVCCIN_CPU1_PVCC        
                                  5        GND                     
                                  30       SW_P12V_PVCCIN_CPU1_FLT 
                                  32       SW_PVCCIN_CPU1_BOOTR2   
                                  33       SW_PVCCIN_CPU1_BOOT2    
                                  34       PVCCIN_CPU1_PWM2        
                                  35       PVCCIN_CPU1_VDD2        
                                  36       PVCCIN_CPU1_ATSEN       
                                  37       PVCCIN_CPU1_LSET2       
                                  38       PVCCIN_CPU1_IMON2       
                                  39       PVCCIN_CPU1_VREF        
                                  40       GND                     
                                  7_9-20_24 GND                     
PU31_P1_1        ISL99390FRZTR5935-ISL99390FRZ-A 1        PVCCIN_CPU1_VOS1        
                                  10_19    SW_PVCCIN_CPU1_SW1      
                                  2        GND                     
                                  25_29    SW_P12V_PVCCIN_CPU1_FLT 
                                  3        PVCCIN_CPU1_VDD1        
                                  4        PVCCIN_CPU1_PVCC        
                                  5        GND                     
                                  30       SW_P12V_PVCCIN_CPU1_FLT 
                                  32       SW_PVCCIN_CPU1_BOOTR1   
                                  33       SW_PVCCIN_CPU1_BOOT1    
                                  34       PVCCIN_CPU1_PWM1        
                                  35       PVCCIN_CPU1_VDD1        
                                  36       PVCCIN_CPU1_ATSEN       
                                  37       PVCCIN_CPU1_LSET1       
                                  38       PVCCIN_CPU1_IMON1       
                                  39       PVCCIN_CPU1_VREF        
                                  40       GND                     
                                  7_9-20_24 GND                     
PU35             ISL69260IRAZT-ISL69260IRAZ-T,SA 8        PVCCD_HV_CPU0_APWM1     
                                  9        SMB_DIO_PVCCD_HV_CPU0   
                                  10       SMB_CLK_PVCCD_HV_CPU0   
                                  12       PWRGD_PVCCD_HV_CPU0_R   
                                  13       PVCCD_HV_CPU0_EN_R      
                                  14       IRQ_PVCCD_CPU0_VRHOT_LVC3_N
                                  15       PVCCD_HV_CPU0_PIN_ALT   
                                  17       SVID_CLK_PVCCD_HV_CPU0_R
                                  18       SVID_DIO_PVCCD_HV_CPU0_R
                                  19       SVID_ALERT_PVCCD_HV_CPU0_R
                                  20       GND                     
                                  21       SH_PVCCD_HV_CPU0_R      
                                  22       VSENSE_PVCCD_HV_CPU0_DN 
                                  23       PVCCD_HV_CPU0_ACSP1     
                                  31       GND                     
                                  32       GND                     
                                  33       PVCCD_HV_CPU0_FAULT     
                                  34       PVCCD_HV_CPU0_ADDR      
                                  35       PVCCD_HV_CPU0_ATSEN     
                                  36       PVCCD_HV_CPU0_ISYS_R    
                                  37       PVCCD_HV_CPU0_ISENSE_P  
                                  38       PVCCD_HV_CPU0_ISENSE_N  
                                  39       PVCCD_HV_CPU0_VCC       
                                  40       PVCCD_HV_CPU0_VREF      
                                  TH       GND                     
PU36             RAA2213404GNPHB0-RAA2213404GNPA 1        PVCCD_HV_CPU0_ATSEN     
                                  16_18-28 SW_P12V_PVCCINFAON_CPU0_FLT
                                  2        GND                     
                                  3        PVCCD_HV_CPU0_NC1       
                                  4        PVCCD_HV_CPU0_VDD1      
                                  5        PVCCD_HV_CPU0_LSET1     
                                  19       SW_PVCCD_HV_CPU0_BOOTR1 
                                  20       SW_PVCCD_HV_CPU0_BOOT1  
                                  21       PVCCD_HV_CPU0_APWM1     
                                  22       PVCCD_HV_CPU0_VDD1      
                                  23       GND                     
                                  24       PVCCD_HV_CPU0_VREF      
                                  25       PVCCD_HV_CPU0_ACSP1     
                                  26       GND                     
                                  6_7-13_15-29 GND                     
                                  8_12     SW_PVCCD_HV_CPU0_SW1    
PU42             RAA2213404GNPHB0-RAA2213404GNPA 1        PVCCFA_EHV_CPU0_BTSEN   
                                  16_18-28 SW_P12V_PVCCINFAON_CPU0_FLT
                                  2        GND                     
                                  3        PVCCFA_EHV_CPU0_NC1     
                                  4        PVCCFA_EHV_CPU0_VDD1    
                                  5        PVCCFA_EHV_CPU0_LSET1   
                                  19       SW_PVCCFA_EHV_CPU0_BOOTR1
                                  20       SW_PVCCFA_EHV_CPU0_BOOT1
                                  21       PVCCFA_EHV_CPU0_BPWM1   
                                  22       PVCCFA_EHV_CPU0_VDD1    
                                  23       GND                     
                                  24       PVCCINFAON_CPU0_VREF    
                                  25       PVCCFA_EHV_CPU0_BCSP1   
                                  26       GND                     
                                  6_7-13_15-29 GND                     
                                  8_12     SW_PVCCFA_EHV_CPU0_SW1  
PU43_P0_1        RAA2213404GNPHB0-RAA2213404GNPA 1        PVCCINFAON_CPU0_ATSEN   
                                  16_18-28 SW_P12V_PVCCINFAON_CPU0_FLT
                                  2        GND                     
                                  3        PVCCINFAON_CPU0_PH1_NC1 
                                  4        PVCCINFAON_CPU0_VDD1    
                                  5        PVCCINFAON_CPU0_LSET1   
                                  19       SW_PVCCINFAON_CPU0_BOOTR1
                                  20       SW_PVCCINFAON_CPU0_BOOT1
                                  21       PVCCINFAON_CPU0_APWM1   
                                  22       PVCCINFAON_CPU0_VDD1    
                                  23       GND                     
                                  24       PVCCINFAON_CPU0_VREF    
                                  25       PVCCINFAON_CPU0_ACSP1   
                                  26       GND                     
                                  6_7-13_15-29 GND                     
                                  8_12     SW_PVCCINFAON_CPU0_SW1  
PU44_P0_2        RAA2213404GNPHB0-RAA2213404GNPA 1        PVCCINFAON_CPU0_ATSEN   
                                  16_18-28 SW_P12V_PVCCINFAON_CPU0_FLT
                                  2        GND                     
                                  3        PVCCINFAON_CPU0_PH2_NC1 
                                  4        PVCCINFAON_CPU0_VDD2    
                                  5        PVCCINFAON_CPU0_LSET2   
                                  19       SW_PVCCINFAON_CPU0_BOOTR2
                                  20       SW_PVCCINFAON_CPU0_BOOT2
                                  21       PVCCINFAON_CPU0_APWM2   
                                  22       PVCCINFAON_CPU0_VDD2    
                                  23       GND                     
                                  24       PVCCINFAON_CPU0_VREF    
                                  25       PVCCINFAON_CPU0_ACSP2   
                                  26       GND                     
                                  6_7-13_15-29 GND                     
                                  8_12     SW_PVCCINFAON_CPU0_SW2  
PU49             RAA2213404GNPHB0-RAA2213404GNPA 1        PVCCFA_EHV_CPU1_BTSEN   
                                  16_18-28 SW_P12V_PVCCINFAON_CPU1_FLT
                                  2        GND                     
                                  3        PVCCFA_EHV_CPU1_NC1     
                                  4        PVCCFA_EHV_CPU1_VDD1    
                                  5        PVCCFA_EHV_CPU1_LSET1   
                                  19       SW_PVCCFA_EHV_CPU1_BOOTR1
                                  20       SW_PVCCFA_EHV_CPU1_BOOT1
                                  21       PVCCFA_EHV_CPU1_BPWM1   
                                  22       PVCCFA_EHV_CPU1_VDD1    
                                  23       GND                     
                                  24       PVCCINFAON_CPU1_VREF    
                                  25       PVCCFA_EHV_CPU1_BCSP1   
                                  26       GND                     
                                  6_7-13_15-29 GND                     
                                  8_12     SW_PVCCFA_EHV_CPU1_SW1  
PU50_P1_1        RAA2213404GNPHB0-RAA2213404GNPA 1        PVCCINFAON_CPU1_ATSEN   
                                  16_18-28 SW_P12V_PVCCINFAON_CPU1_FLT
                                  2        GND                     
                                  3        PVCCINFAON_CPU1_PH1_NC1 
                                  4        PVCCINFAON_CPU1_VDD1    
                                  5        PVCCINFAON_CPU1_LSET1   
                                  19       SW_PVCCINFAON_CPU1_BOOTR1
                                  20       SW_PVCCINFAON_CPU1_BOOT1
                                  21       PVCCINFAON_CPU1_APWM1   
                                  22       PVCCINFAON_CPU1_VDD1    
                                  23       GND                     
                                  24       PVCCINFAON_CPU1_VREF    
                                  25       PVCCINFAON_CPU1_ACSP1   
                                  26       GND                     
                                  6_7-13_15-29 GND                     
                                  8_12     SW_PVCCINFAON_CPU1_SW1  
PU51_P1_2        RAA2213404GNPHB0-RAA2213404GNPA 1        PVCCINFAON_CPU1_ATSEN   
                                  16_18-28 SW_P12V_PVCCINFAON_CPU1_FLT
                                  2        GND                     
                                  3        PVCCINFAON_CPU1_PH2_NC1 
                                  4        PVCCINFAON_CPU1_VDD2    
                                  5        PVCCINFAON_CPU1_LSET2   
                                  19       SW_PVCCINFAON_CPU1_BOOTR2
                                  20       SW_PVCCINFAON_CPU1_BOOT2
                                  21       PVCCINFAON_CPU1_APWM2   
                                  22       PVCCINFAON_CPU1_VDD2    
                                  23       GND                     
                                  24       PVCCINFAON_CPU1_VREF    
                                  25       PVCCINFAON_CPU1_ACSP2   
                                  26       GND                     
                                  6_7-13_15-29 GND                     
                                  8_12     SW_PVCCINFAON_CPU1_SW2  
PU69_P0_1        ISL99390FRZTR5935-ISL99390FRZ-A 1        PVCCFA_EHV_FIVRA_CPU0_VOS1
                                  10_19    SW_PVCCFA_EHV_FIVRA_CPU0_SW1
                                  2        GND                     
                                  25_29    SW_P12V_PVCCFA_EHV_FIVRA_CPU0_R
                                  3        PVCCFA_EHV_FIVRA_CPU0_VDD1
                                  4        PVCCFA_EHV_FIVRA_CPU0_PVCC1
                                  5        GND                     
                                  30       SW_P12V_PVCCFA_EHV_FIVRA_CPU0_R
                                  32       SW_PVCCFA_EHV_FIVRA_CPU0_BOOTR1
                                  33       SW_PVCCFA_EHV_FIVRA_CPU0_BOOT1
                                  34       PVCCFA_EHV_FIVRA_CPU0_PWM1
                                  35       PVCCFA_EHV_FIVRA_CPU0_VDD1
                                  36       PVCCIN_CPU0_ATSEN       
                                  37       PVCCFA_EHV_FIVRA_CPU0_LSET1
                                  38       PVCCFA_EHV_FIVRA_CPU0_IMON1
                                  39       PVCCIN_CPU0_VREF        
                                  40       GND                     
                                  7_9-20_24 GND                     
PU70_P0_2        ISL99390FRZTR5935-ISL99390FRZ-A 1        PVCCFA_EHV_FIVRA_CPU0_VOS2
                                  10_19    SW_PVCCFA_EHV_FIVRA_CPU0_SW2
                                  2        GND                     
                                  25_29    SW_P12V_PVCCFA_EHV_FIVRA_CPU0_L
                                  3        PVCCFA_EHV_FIVRA_CPU0_VDD2
                                  4        PVCCFA_EHV_FIVRA_CPU0_PVCC2
                                  5        GND                     
                                  30       SW_P12V_PVCCFA_EHV_FIVRA_CPU0_L
                                  32       SW_PVCCFA_EHV_FIVRA_CPU0_BOOTR2
                                  33       SW_PVCCFA_EHV_FIVRA_CPU0_BOOT2
                                  34       PVCCFA_EHV_FIVRA_CPU0_PWM2
                                  35       PVCCFA_EHV_FIVRA_CPU0_VDD2
                                  36       PVCCIN_CPU0_ATSEN       
                                  37       PVCCFA_EHV_FIVRA_CPU0_LSET2
                                  38       PVCCFA_EHV_FIVRA_CPU0_IMON2
                                  39       PVCCIN_CPU0_VREF        
                                  40       GND                     
                                  7_9-20_24 GND                     
PU71_P0_3        ISL99390FRZTR5935-ISL99390FRZ-B 1        PVCCFA_EHV_FIVRA_CPU0_VOS3
                                  10_19    SW_PVCCFA_EHV_FIVRA_CPU0_SW3
                                  2        GND                     
                                  25_29    SW_P12V_PVCCFA_EHV_FIVRA_CPU0_R
                                  3        PVCCFA_EHV_FIVRA_CPU0_VDD3
                                  4        PVCCFA_EHV_FIVRA_CPU0_PVCC1
                                  5        GND                     
                                  30       SW_P12V_PVCCFA_EHV_FIVRA_CPU0_R
                                  32       SW_PVCCFA_EHV_FIVRA_CPU0_BOOTR3
                                  33       SW_PVCCFA_EHV_FIVRA_CPU0_BOOT3
                                  35       PVCCFA_EHV_FIVRA_CPU0_VDD3
                                  36       PVCCIN_CPU0_ATSEN       
                                  37       PVCCFA_EHV_FIVRA_CPU0_LSET3
                                  39       PVCCIN_CPU0_VREF        
                                  40       GND                     
                                  7_9-20_24 GND                     
PU72_P0_4        ISL99390FRZTR5935-ISL99390FRZ-B 1        PVCCFA_EHV_FIVRA_CPU0_VOS4
                                  10_19    SW_PVCCFA_EHV_FIVRA_CPU0_SW4
                                  2        GND                     
                                  25_29    SW_P12V_PVCCFA_EHV_FIVRA_CPU0_L
                                  3        PVCCFA_EHV_FIVRA_CPU0_VDD4
                                  4        PVCCFA_EHV_FIVRA_CPU0_PVCC2
                                  5        GND                     
                                  30       SW_P12V_PVCCFA_EHV_FIVRA_CPU0_L
                                  32       SW_PVCCFA_EHV_FIVRA_CPU0_BOOTR4
                                  33       SW_PVCCFA_EHV_FIVRA_CPU0_BOOT4
                                  35       PVCCFA_EHV_FIVRA_CPU0_VDD4
                                  36       PVCCIN_CPU0_ATSEN       
                                  37       PVCCFA_EHV_FIVRA_CPU0_LSET4
                                  39       PVCCIN_CPU0_VREF        
                                  40       GND                     
                                  7_9-20_24 GND                     
PU73             MPQ8633BGLEC838Z-MPQ8633BGLE-CA 1        SW_P1V05_PCH_AUX_BST    
                                  11_18    GND                     
                                  2        GND                     
                                  3        P1V05_PCH_AUX_CS        
                                  4        P1V05_PCH_AUX_VCC       
                                  5        P1V05_PCH_AUX_REF       
                                  6        SH_P1V05_PCH_AUX_N      
                                  7        P1V05_PCH_AUX_FB        
                                  8        FM_P1V05_PCH_AUX_R_EN   
                                  9        PWRGD_P1V05_PCH_AUX_R   
                                  10       SW_P12V_AUX_P1V05_PCH_AUX_FLT
                                  19       P1V05_PCH_AUX_VCC       
                                  20       SW_P1V05_PCH_AUX_SW     
                                  21       SW_P12V_AUX_P1V05_PCH_AUX_FLT
PU74             NB695GDZ-NB695GD-Z,SMLF,IC,AL0A 1        SW_P1V8_PCH_AUX_FLT     
                                  2        GND                     
                                  3        P1V8_PCH_AUX_VCC        
                                  4        GND                     
                                  5        FM_PCH_P1V8_AUX_EN_R    
                                  6        P1V8_PCH_AUX_VCC        
                                  7        P1V8_PCH_AUX_MODE       
                                  8        SW_P1V8_PCH_AUX_SW      
                                  9        SW_P1V8_PCH_AUX_BST     
                                  10       P1V8_PCH_AUX_VCC        
                                  11       GND                     
                                  12       P1V8_PCH_AUX            
                                  13       PWRGD_P1V8_PCH_AUX_R    
PU75_P1_1        ISL99390FRZTR5935-ISL99390FRZ-A 1        PVCCFA_EHV_FIVRA_CPU1_VOS1
                                  10_19    SW_PVCCFA_EHV_FIVRA_CPU1_SW1
                                  2        GND                     
                                  25_29    SW_P12V_PVCCFA_EHV_FIVRA_CPU1_R
                                  3        PVCCFA_EHV_FIVRA_CPU1_VDD1
                                  4        PVCCFA_EHV_FIVRA_CPU1_PVCC1
                                  5        GND                     
                                  30       SW_P12V_PVCCFA_EHV_FIVRA_CPU1_R
                                  32       SW_PVCCFA_EHV_FIVRA_CPU1_BOOTR1
                                  33       SW_PVCCFA_EHV_FIVRA_CPU1_BOOT1
                                  34       PVCCFA_EHV_FIVRA_CPU1_PWM1
                                  35       PVCCFA_EHV_FIVRA_CPU1_VDD1
                                  36       PVCCIN_CPU1_ATSEN       
                                  37       PVCCFA_EHV_FIVRA_CPU1_LSET1
                                  38       PVCCFA_EHV_FIVRA_CPU1_IMON1
                                  39       PVCCIN_CPU1_VREF        
                                  40       GND                     
                                  7_9-20_24 GND                     
PU76_P1_2        ISL99390FRZTR5935-ISL99390FRZ-A 1        PVCCFA_EHV_FIVRA_CPU1_VOS2
                                  10_19    SW_PVCCFA_EHV_FIVRA_CPU1_SW2
                                  2        GND                     
                                  25_29    SW_P12V_PVCCFA_EHV_FIVRA_CPU1_L
                                  3        PVCCFA_EHV_FIVRA_CPU1_VDD2
                                  4        PVCCFA_EHV_FIVRA_CPU1_PVCC2
                                  5        GND                     
                                  30       SW_P12V_PVCCFA_EHV_FIVRA_CPU1_L
                                  32       SW_PVCCFA_EHV_FIVRA_CPU1_BOOTR2
                                  33       SW_PVCCFA_EHV_FIVRA_CPU1_BOOT2
                                  34       PVCCFA_EHV_FIVRA_CPU1_PWM2
                                  35       PVCCFA_EHV_FIVRA_CPU1_VDD2
                                  36       PVCCIN_CPU1_ATSEN       
                                  37       PVCCFA_EHV_FIVRA_CPU1_LSET2
                                  38       PVCCFA_EHV_FIVRA_CPU1_IMON2
                                  39       PVCCIN_CPU1_VREF        
                                  40       GND                     
                                  7_9-20_24 GND                     
PU77_P1_3        ISL99390FRZTR5935-ISL99390FRZ-A 1        PVCCFA_EHV_FIVRA_CPU1_VOS3
                                  10_19    SW_PVCCFA_EHV_FIVRA_CPU1_SW3
                                  2        GND                     
                                  25_29    SW_P12V_PVCCFA_EHV_FIVRA_CPU1_R
                                  3        PVCCFA_EHV_FIVRA_CPU1_VDD3
                                  4        PVCCFA_EHV_FIVRA_CPU1_PVCC1
                                  5        GND                     
                                  30       SW_P12V_PVCCFA_EHV_FIVRA_CPU1_R
                                  32       SW_PVCCFA_EHV_FIVRA_CPU1_BOOTR3
                                  33       SW_PVCCFA_EHV_FIVRA_CPU1_BOOT3
                                  34       PVCCFA_EHV_FIVRA_CPU1_PWM3
                                  35       PVCCFA_EHV_FIVRA_CPU1_VDD3
                                  36       PVCCIN_CPU1_ATSEN       
                                  37       PVCCFA_EHV_FIVRA_CPU1_LSET3
                                  38       PVCCFA_EHV_FIVRA_CPU1_IMON3
                                  39       PVCCIN_CPU1_VREF        
                                  40       GND                     
                                  7_9-20_24 GND                     
PU78_P1_4        ISL99390FRZTR5935-ISL99390FRZ-A 1        PVCCFA_EHV_FIVRA_CPU1_VOS4
                                  10_19    SW_PVCCFA_EHV_FIVRA_CPU1_SW4
                                  2        GND                     
                                  25_29    SW_P12V_PVCCFA_EHV_FIVRA_CPU1_L
                                  3        PVCCFA_EHV_FIVRA_CPU1_VDD4
                                  4        PVCCFA_EHV_FIVRA_CPU1_PVCC2
                                  5        GND                     
                                  30       SW_P12V_PVCCFA_EHV_FIVRA_CPU1_L
                                  32       SW_PVCCFA_EHV_FIVRA_CPU1_BOOTR4
                                  33       SW_PVCCFA_EHV_FIVRA_CPU1_BOOT4
                                  34       PVCCFA_EHV_FIVRA_CPU1_PWM4
                                  35       PVCCFA_EHV_FIVRA_CPU1_VDD4
                                  36       PVCCIN_CPU1_ATSEN       
                                  37       PVCCFA_EHV_FIVRA_CPU1_LSET4
                                  38       PVCCFA_EHV_FIVRA_CPU1_IMON4
                                  39       PVCCIN_CPU1_VREF        
                                  40       GND                     
                                  7_9-20_24 GND                     
PU79             MPQ8633AGLEC807Z-MPQ8633AGLE-CA 1        SW_PVPP_HBM_CPU0_BST    
                                  11_18    GND                     
                                  2        GND                     
                                  3        PVPP_HBM_CPU0_CS        
                                  4        PVPP_HBM_CPU0_VCC       
                                  5        PVPP_HBM_CPU0_REF       
                                  6        SH_PVPP_HBM_CPU0_N      
                                  7        PVPP_HBM_CPU0_FB        
                                  8        FM_PVPP_HBM_CPU0_EN     
                                  9        PWRGD_PVPP_HBM_CPU0_R   
                                  10       SW_P12V_PVCCIN_CPU0_FLT 
                                  19       PVPP_HBM_CPU0_VCC       
                                  20       SW_PVPP_HBM_CPU0_SW     
                                  21       SW_P12V_PVCCIN_CPU0_FLT 
PU80             MPQ8633AGLEC807Z-MPQ8633AGLE-CB 1        SW_PVPP_HBM_CPU1_BST    
                                  11_18    GND                     
                                  2        GND                     
                                  3        PVPP_HBM_CPU1_CS        
                                  4        PVPP_HBM_CPU1_VCC       
                                  5        PVPP_HBM_CPU1_REF       
                                  6        SH_PVPP_HBM_CPU1_N      
                                  7        PVPP_HBM_CPU1_FB        
                                  8        FM_PVPP_HBM_CPU1_EN     
                                  9        PWRGD_PVPP_HBM_CPU1_R   
                                  10       SW_P12V_PVCCIN_CPU1_FLT 
                                  19       PVPP_HBM_CPU1_VCC       
                                  20       SW_PVPP_HBM_CPU1_SW     
                                  21       SW_P12V_PVCCIN_CPU1_FLT 
PU81             MPQ8626GDZ-MPQ8626GD-Z,SMLF,ICA 1        GND                     
                                  2        SW_PVNN_MAIN_CPU0_SW    
                                  3        SW_P12V_PVCCINFAON_CPU0_FLT
                                  4        PVNN_MAIN_CPU0_CS       
                                  5        FM_PVNN_MAIN_CPU0_EN    
                                  6        PVNN_MAIN_CPU0_FB_RC    
                                  7        GND                     
                                  8        PVNN_MAIN_CPU0_REF      
                                  9        PWRGD_PVNN_MAIN_CPU0_R  
                                  10       SW_PVNN_MAIN_CPU0_BST   
                                  11       SW_PVNN_MAIN_CPU0_SW    
                                  12       PVNN_MAIN_CPU0_MODE     
                                  13       PVNN_MAIN_CPU0_VCC      
                                  14       GND                     
PU82             MPQ8626GDZ-MPQ8626GD-Z,SMLF,ICA 1        GND                     
                                  2        SW_PVNN_MAIN_CPU1_SW    
                                  3        SW_P12V_PVCCINFAON_CPU1_FLT
                                  4        PVNN_MAIN_CPU1_CS       
                                  5        FM_PVNN_MAIN_CPU1_EN    
                                  6        PVNN_MAIN_CPU1_FB_RC    
                                  7        GND                     
                                  8        PVNN_MAIN_CPU1_REF      
                                  9        PWRGD_PVNN_MAIN_CPU1_R  
                                  10       SW_PVNN_MAIN_CPU1_BST   
                                  11       SW_PVNN_MAIN_CPU1_SW    
                                  12       PVNN_MAIN_CPU1_MODE     
                                  13       PVNN_MAIN_CPU1_VCC      
                                  14       GND                     
PU181            MPQ8633BGLEC838Z-MPQ8633BGLE-CA 1        SW_P5V_AUX_BST          
                                  11_18    GND                     
                                  2        GND                     
                                  3        P5V_AUX_CS              
                                  4        P5V_AUX_VCC             
                                  5        P5V_AUX_REF             
                                  6        GND                     
                                  7        P5V_AUX_FB              
                                  8        P5V_AUX_EN              
                                  9        PWRGD_P5V_AUX           
                                  10       SW_P5V_AUX_FLT          
                                  19       P5V_AUX_VCC             
                                  20       SW_P5V_AUX_SW           
                                  21       SW_P5V_AUX_FLT          
Q15              MOSFET_NCH_DUAL-2N7002KDW,SMLFA 1        GND                     
                                  2        FM_SMB_PEHPCPU0_PCIE_ALERT_R_N
                                  3        FM_PEHPCPU0_ALERT_N     
                                  4        GND                     
                                  5        FM_SMB_CPU0_ALERT_R1    
                                  6        FM_SMB_CPU0_ALERT_R1    
Q16              MOSFET_NCH_DUAL-2N7002KDW,SMLFA 1        GND                     
                                  2        FM_SMB_PEHPCPU1_PCIE_ALERT_R_N
                                  3        FM_PEHPCPU1_ALERT_N     
                                  4        GND                     
                                  5        FM_SMB_CPU1_ALERT_R1    
                                  6        FM_SMB_CPU1_ALERT_R1    
Q33              MOSFET_PCH_GDS_ESD_PROTECTED-PA D        P3V3_AUX                
                                  G        CPU_RMCA_CATERR_LVT3_N  
                                  S        LED_CPU_RMCA_CATERR_R   
Q34              MOSFET_N_GSD-NX7002AK,SMLF,IC,A D        RST_RTCRST_N            
                                  G        RST_PFR_OVR_RTC         
                                  S        GND                     
Q35              MOSFET_N_GSD-NX7002AK,SMLF,IC,A D        RST_SRTCRST_N           
                                  G        RST_PFR_OVR_SRTC        
                                  S        GND                     
Q37              MOSFET_NCH_DUAL-2N7002KDW,SMLFA 1        GND                     
                                  2        VR_P5V_EN               
                                  3        VR_P5V_EN_D_R1          
                                  4        GND                     
                                  5        VR_P5V_EN_N             
                                  6        VR_P5V_EN_N             
Q39              MOSFET_NCH_DUAL-2N7002KDW,SMLFA 3        P12V_SCM_EN_N           
                                  4        GND                     
                                  5        FM_SCM_PRSNT1_R_N       
Q45              MOSFET_NCH_DUAL-2N7002KDW,SMLFA 1        GND                     
                                  2        HP_LVC3_OCP_V3_1_HSC_PWRGD
                                  3        HP_LVC3_OCP_V3_1_PWRGD  
                                  4        GND                     
                                  5        HP_LVC3_OCP_V3_1_PWRGD_N
                                  6        HP_LVC3_OCP_V3_1_PWRGD_N
R1               Q_RES_0402LF-10,1%,1/16W,CHIP,A 1        H_CPU_PRDY_QS_GTL_N     
                                  2        H_CPU0_PRDY_QS_GTL_R_N  
R2               Q_RES_0402LF-100,1%,1/16W,CHIPA 1        H_CPU_PREQ_QS_GTL_N     
                                  2        H_CPU0_PREQ_QS_GTL_R_N  
R3               Q_RES_0402LF-33.2,1%,1/16W,CHIA 1        PECI_CPU_GTL            
                                  2        PECI_CPU0_GTL_R         
R4               Q_RES_0402LF-200,1%,1/16W,CHIPA 1        JTAG_MUX_CPU0_GTL_TDI   
                                  2        JTAG_DBP_CPU0_GTL_R_TDI 
R5               Q_RES_0402LF-100,1%,1/16W,CHIPA 1        JTAG_DBP_CPU_GTL_TCK    
                                  2        JTAG_DBP_CPU0_GTL_R_TCK 
R6               Q_RES_0402LF-100,1%,1/16W,CHIPA 1        JTAG_DBP_CPU_QS_GTL_TMS 
                                  2        JTAG_DBP_CPU0_QS_GTL_R_TMS
R7               Q_RES_0402LF-33.2,1%,1/16W,CHIA 1        H_CPU0_PMDOWN_PCH_R     
                                  2        H_CPU0_PMDOWN_PCH       
R8               Q_RES_0402LF-10K,1%,1/16W,CHIPA 1        P3V3_AUX                
                                  2        FM_PS_PWROK_DLY_R_SEL   
R9               Q_RES_0402LF-4.32K,1%,1/16W,CHA 1        PWRGD_S0_PWROK_CPU0_LVC1_R
                                  2        GND                     
R10              Q_RES_0402LF-33.2,1%,1/16W,CHIA 1        H_CPU0_PMSYNC_PCH_R     
                                  2        H_CPU0_PMSYNC_PCH       
R11              Q_RES_0402LF-33.2,1%,1/16W,CHIA 1        H_CPU0_PMDOWN_CPU1      
                                  2        H_CPU0_PMDOWN_CPU1_R    
R12              Q_RES_0402LF-0,5%,1/16W,CHIP,CA 1        SVID_DIO0_CPU0          
                                  2        SVID_DIO0_CPU0_R        
R13              Q_RES_0402LF-0,5%,1/16W,CHIP,CA 1        SVID_CLK0_CPU0          
                                  2        SVID_CLK0_CPU0_R        
R14              Q_RES_0402LF-200,1%,1/16W,CHIPA 1        SVID_ALERT0_CPU0_N      
                                  2        SVID_ALERT0_CPU0_R_N    
R15              Q_RES_0402LF-0,5%,1/16W,CHIP,CA 1        SVID_DIO1_CPU0          
                                  2        SVID_DIO1_CPU0_R        
R16              Q_RES_0402LF-0,5%,1/16W,CHIP,CA 1        SVID_CLK1_CPU0          
                                  2        SVID_CLK1_CPU0_R        
R17              Q_RES_0402LF-200,1%,1/16W,CHIPA 1        SVID_ALERT1_CPU0_N      
                                  2        SVID_ALERT1_CPU0_R_N    
R18              Q_RES_0402LF-499,1%,1/16W,CHIPA 1        PVNN_TERM_CPU0          
                                  2        DBP_CPU_MBP0_GTL_N      
R19              Q_RES_0402LF-499,1%,1/16W,CHIPA 1        PVNN_TERM_CPU0          
                                  2        DBP_CPU_MBP1_GTL_N      
R20              Q_RES_0402LF-0,5%,1/16W,CHIP,CA 1        DBP_CPU_MBP0_GTL_N      
                                  2        FM_PCH_TRIGGER0_N       
R21              Q_RES_0402LF-0,5%,1/16W,CHIP,CA 1        DBP_CPU_MBP1_GTL_N      
                                  2        FM_PCH_TRIGGER1_N       
R22              Q_RES_0402LF-100,1%,1/16W,CHIPA 1        DBP_CPU0_MBP0_GTL_R_N   
                                  2        DBP_CPU_MBP0_GTL_N      
R23              Q_RES_0402LF-100,1%,1/16W,CHIPA 1        DBP_CPU0_MBP1_GTL_R_N   
                                  2        DBP_CPU_MBP1_GTL_N      
R24              Q_RES_0402LF-10,1%,1/16W,CHIP,A 1        DBP_CPU0_HOOK8_MBP2_GTL_QS_R_N
                                  2        DBP_CPU_HOOK8_MBP2_GTL_QS_N
R25              Q_RES_0402LF-10,1%,1/16W,CHIP,A 1        DBP_CPU0_HOOK9_MBP3_GTL_QS_R_N
                                  2        DBP_CPU_HOOK9_MBP3_GTL_QS_N
R26              Q_RES_0402LF-10K,1%,1/16W,CHIPA 1        PD_CHA_CPU0_DIMM1_SAA   
                                  2        GND                     
R27              Q_RES_0402LF-15.4K,1%,1/16W,CHA 1        PD_CHA_CPU0_DIMM2_SAA   
                                  2        GND                     
R28              Q_RES_0402LF-23.2K,1%,1/16W,CHA 1        PD_CHB_CPU0_DIMM1_SAA   
                                  2        GND                     
R29              Q_RES_0402LF-35.7K,1%,1/16W,CHA 1        PD_CHB_CPU0_DIMM2_SAA   
                                  2        GND                     
R30              Q_RES_0402LF-54.9K,1%,1/16W,CHA 1        PD_CHC_CPU0_DIMM1_SAA   
                                  2        GND                     
R31              Q_RES_0402LF-84.5K,1%,1/16W,CHA 1        PD_CHC_CPU0_DIMM2_SAA   
                                  2        GND                     
R32              Q_RES_0402LF-127K,1%,1/16W,CHIA 1        PD_CHD_CPU0_DIMM1_SAA   
                                  2        GND                     
R33              Q_RES_0402LF-196K,1%,1/16W,CHIA 1        PD_CHD_CPU0_DIMM2_SAA   
                                  2        GND                     
R34              Q_RES_0402LF-10K,1%,1/16W,CHIPA 1        PD_CHE_CPU0_DIMM1_SAA   
                                  2        GND                     
R35              Q_RES_0402LF-15.4K,1%,1/16W,CHA 1        PD_CHE_CPU0_DIMM2_SAA   
                                  2        GND                     
R36              Q_RES_0402LF-23.2K,1%,1/16W,CHA 1        PD_CHF_CPU0_DIMM1_SAA   
                                  2        GND                     
R37              Q_RES_0402LF-35.7K,1%,1/16W,CHA 1        PD_CHF_CPU0_DIMM2_SAA   
                                  2        GND                     
R38              Q_RES_0402LF-54.9K,1%,1/16W,CHA 1        PD_CHG_CPU0_DIMM1_SAA   
                                  2        GND                     
R39              Q_RES_0402LF-84.5K,1%,1/16W,CHA 1        PD_CHG_CPU0_DIMM2_SAA   
                                  2        GND                     
R40              Q_RES_0402LF-127K,1%,1/16W,CHIA 1        PD_CHH_CPU0_DIMM1_SAA   
                                  2        GND                     
R41              Q_RES_0402LF-196K,1%,1/16W,CHIA 1        PD_CHH_CPU0_DIMM2_SAA   
                                  2        GND                     
R42              Q_RES_0402LF-10K,1%,1/16W,CHIPA 1        PD_CHA_CPU1_DIMM1_SAA   
                                  2        GND                     
R43              Q_RES_0402LF-15.4K,1%,1/16W,CHA 1        PD_CHA_CPU1_DIMM2_SAA   
                                  2        GND                     
R44              Q_RES_0402LF-23.2K,1%,1/16W,CHA 1        PD_CHB_CPU1_DIMM1_SAA   
                                  2        GND                     
R45              Q_RES_0402LF-35.7K,1%,1/16W,CHA 1        PD_CHB_CPU1_DIMM2_SAA   
                                  2        GND                     
R46              Q_RES_0402LF-54.9K,1%,1/16W,CHA 1        PD_CHC_CPU1_DIMM1_SAA   
                                  2        GND                     
R47              Q_RES_0402LF-84.5K,1%,1/16W,CHA 1        PD_CHC_CPU1_DIMM2_SAA   
                                  2        GND                     
R48              Q_RES_0402LF-127K,1%,1/16W,CHIA 1        PD_CHD_CPU1_DIMM1_SAA   
                                  2        GND                     
R49              Q_RES_0402LF-499,1%,1/16W,CHIPA 1        PVNN_TERM_CPU1          
                                  2        DBP_CPU_MBP0_GTL_N      
R50              Q_RES_0402LF-499,1%,1/16W,CHIPA 1        PVNN_TERM_CPU1          
                                  2        DBP_CPU_MBP1_GTL_N      
R51              Q_RES_0402LF-100,1%,1/16W,CHIPA 1        DBP_CPU1_MBP0_GTL_R_N   
                                  2        DBP_CPU_MBP0_GTL_N      
R52              Q_RES_0402LF-100,1%,1/16W,CHIPA 1        DBP_CPU1_MBP1_GTL_R_N   
                                  2        DBP_CPU_MBP1_GTL_N      
R53              Q_RES_0402LF-10,1%,1/16W,CHIP,A 1        DBP_CPU1_HOOK8_MBP2_GTL_QS_R_N
                                  2        DBP_CPU_HOOK8_MBP2_GTL_QS_N
R54              Q_RES_0402LF-10,1%,1/16W,CHIP,A 1        DBP_CPU1_HOOK9_MBP3_GTL_QS_R_N
                                  2        DBP_CPU_HOOK9_MBP3_GTL_QS_N
R55              Q_RES_0402LF-0,5%,1/16W,CHIP,CA 1        SVID_DIO0_CPU1          
                                  2        SVID_DIO0_CPU1_R        
R56              Q_RES_0402LF-0,5%,1/16W,CHIP,CA 1        SVID_CLK0_CPU1          
                                  2        SVID_CLK0_CPU1_R        
R57              Q_RES_0402LF-200,1%,1/16W,CHIPA 1        SVID_ALERT0_CPU1_N      
                                  2        SVID_ALERT0_CPU1_R_N    
R58              Q_RES_0402LF-0,5%,1/16W,CHIP,CA 1        SVID_DIO1_CPU1          
                                  2        SVID_DIO1_CPU1_R        
R59              Q_RES_0402LF-0,5%,1/16W,CHIP,CA 1        SVID_CLK1_CPU1          
                                  2        SVID_CLK1_CPU1_R        
R60              Q_RES_0402LF-200,1%,1/16W,CHIPA 1        SVID_ALERT1_CPU1_N      
                                  2        SVID_ALERT1_CPU1_R_N    
R61              Q_RES_0402LF-10,1%,1/16W,CHIP,A 1        H_CPU_PRDY_QS_GTL_N     
                                  2        H_CPU1_PRDY_QS_GTL_R_N  
R62              Q_RES_0402LF-100,1%,1/16W,CHIPA 1        H_CPU_PREQ_QS_GTL_N     
                                  2        H_CPU1_PREQ_QS_GTL_R_N  
R63              Q_RES_0402LF-33.2,1%,1/16W,CHIA 1        PECI_CPU_GTL            
                                  2        PECI_CPU1_GTL_R         
R64              Q_RES_0402LF-200,1%,1/16W,CHIPA 1        JTAG_MUX_CPU1_GTL_TDI   
                                  2        JTAG_DBP_CPU1_GTL_R_TDI 
R65              Q_RES_0402LF-100,1%,1/16W,CHIPA 1        JTAG_DBP_CPU_GTL_TCK    
                                  2        JTAG_DBP_CPU1_GTL_R_TCK 
R66              Q_RES_0402LF-100,1%,1/16W,CHIPA 1        JTAG_DBP_CPU_QS_GTL_TMS 
                                  2        JTAG_DBP_CPU1_QS_GTL_R_TMS
R67              Q_RES_0402LF-33.2,1%,1/16W,CHIA 1        PWRGD_PLT_AUX_CPU0_LVT3_R
                                  2        PWRGD_PLT_AUX_CPU0_LVT3 
R68              Q_RES_0402LF-33.2,1%,1/16W,CHIA 1        PWRGD_PLT_AUX_CPU1_LVT3_R
                                  2        PWRGD_PLT_AUX_CPU1_LVT3 
R69              Q_RES_0402LF-10K,1%,1/16W,CHIPA 1        PWRGD_PLT_AUX_CPU0_LVT3 
                                  2        GND                     
R70              Q_RES_0402LF-10K,1%,1/16W,CHIPA 1        PWRGD_PLT_AUX_CPU1_LVT3 
                                  2        GND                     
R71              Q_RES_0402LF-10K,1%,1/16W,CHIPA 1        P3V3_AUX                
                                  2        FM_ME_BT_DONE           
R72              Q_RES_0402LF-196K,1%,1/16W,CHIA 1        PD_CHH_CPU1_DIMM2_SAA   
                                  2        GND                     
R73              Q_RES_0402LF-127K,1%,1/16W,CHIA 1        PD_CHH_CPU1_DIMM1_SAA   
                                  2        GND                     
R74              Q_RES_0402LF-84.5K,1%,1/16W,CHA 1        PD_CHG_CPU1_DIMM2_SAA   
                                  2        GND                     
R75              Q_RES_0402LF-54.9K,1%,1/16W,CHA 1        PD_CHG_CPU1_DIMM1_SAA   
                                  2        GND                     
R76              Q_RES_0402LF-35.7K,1%,1/16W,CHA 1        PD_CHF_CPU1_DIMM2_SAA   
                                  2        GND                     
R77              Q_RES_0402LF-23.2K,1%,1/16W,CHA 1        PD_CHF_CPU1_DIMM1_SAA   
                                  2        GND                     
R78              Q_RES_0402LF-15.4K,1%,1/16W,CHA 1        PD_CHE_CPU1_DIMM2_SAA   
                                  2        GND                     
R79              Q_RES_0402LF-10K,1%,1/16W,CHIPA 1        PD_CHE_CPU1_DIMM1_SAA   
                                  2        GND                     
R80              Q_RES_0402LF-196K,1%,1/16W,CHIA 1        PD_CHD_CPU1_DIMM2_SAA   
                                  2        GND                     
R85              Q_RES_0402LF-10K,5%,1/16W,EMPTA 1        P3V3_AUX                
                                  2        FM_SYS_THROTTLE_R_N     
R86              Q_RES_0402LF-10K,5%,1/16W,EMPTA 1        P3V3_AUX                
                                  2        FM_SYS_THROTTLE_R_N     
R87              Q_RES_0402LF-1K,5%,1/16W,EMPTYA 1        P3V3_AUX                
                                  2        FM_SPD_REMOTE_EN        
R90              Q_RES_0402LF-240,1%,1/16W,EMPTA 1        PVNN_TERM_CPU1          
                                  2        PU_CPU1_UPI0_AC_COUPLING
R91              Q_RES_0402LF-240,1%,1/16W,EMPTA 1        PVNN_TERM_CPU1          
                                  2        PU_CPU1_UPI1_AC_COUPLING
R92              Q_RES_0402LF-240,1%,1/16W,EMPTA 1        PVNN_TERM_CPU1          
                                  2        PU_CPU1_UPI2_AC_COUPLING
R93              Q_RES_0402LF-240,1%,1/16W,EMPTA 1        PVNN_TERM_CPU1          
                                  2        PU_CPU1_UPI3_AC_COUPLING
R94              Q_RES_0402LF-240,1%,1/16W,EMPTA 1        PVNN_TERM_CPU0          
                                  2        PU_CPU0_UPI0_AC_COUPLING
R95              Q_RES_0402LF-240,1%,1/16W,EMPTA 1        PVNN_TERM_CPU0          
                                  2        PU_CPU0_UPI1_AC_COUPLING
R96              Q_RES_0402LF-240,1%,1/16W,EMPTA 1        PVNN_TERM_CPU0          
                                  2        PU_CPU0_UPI2_AC_COUPLING
R97              Q_RES_0402LF-240,1%,1/16W,EMPTA 1        PVNN_TERM_CPU0          
                                  2        PU_CPU0_UPI3_AC_COUPLING
R100             Q_RES_0402LF-33,5%,1/16W,CHIP,A 1        H_CPU0_MON_FAIL_LVC1_R_N
                                  2        H_CPU0_MON_FAIL_PLD_LVC1_N
R104             Q_RES_0402LF-33,5%,1/16W,CHIP,A 1        H_CPU1_MON_FAIL_LVC1_R_N
                                  2        H_CPU1_MON_FAIL_PLD_LVC1_N
R106             Q_RES_0402LF-2K,1%,1/16W,CHIP,A 1        GND                     
                                  2        FM_PLD_CLKS_DEV_EN      
R107             Q_RES_0402LF-0,5%,1/16W,CHIP,CA 1        SMB_HOST_3V3AUX_SCL_R   
                                  2        SMB_HOST_DB2000_3V3AUX_SCL
R108             Q_RES_0402LF-33.2,1%,1/16W,CHIA 1        SMB_HOST_3V3AUX_SDA_R   
                                  2        SMB_HOST_DB2000_3V3AUX_SDA
R109             Q_RES_0402LF-33.2,1%,1/16W,CHIA 1        FM_PLD_CLK_25M_R_EN     
                                  2        FM_PLD_CLK_25M_EN       
R110             Q_RES_0402LF-33.2,1%,1/16W,CHIA 1        FM_PLD_CLKS_DEV_R_EN    
                                  2        FM_PLD_CLKS_DEV_EN      
R111             Q_RES_0402LF-10K,1%,1/16W,CHIPA 1        P3V3_AUX                
                                  2        FM_PLD_CLKS_OE_R_N      
R112             Q_RES_0402LF-10K,1%,1/16W,EMPTA 1        P3V3                    
                                  2        HP_LVC3_OCP_V3_1_PRSNT2_N
R113             Q_RES_0402LF-33.2,1%,1/16W,CHIA 1        FM_PLD_CLKS_OE_R_N      
                                  2        FM_DB2000_OE_N          
R120             Q_RES_0603LF-10M,1%,1/10W,CHIPA 1        XTAL_PCH_RTC2_R         
                                  2        XTAL_PCH_RTC1           
R122             Q_RES_0402LF-0,5%,1/16W,CHIP,CA 1        PWRGD_DRAMPWRGD_CPU1_AB_R_LVC1
                                  2        PWRGD_DRAMPWRGD_CPU1_AB_LVC1_R
R124             Q_RES_0402LF-0,5%,1/16W,CHIP,CA 1        PWRGD_DRAMPWRGD_CPU1_CD_R_LVC1
                                  2        PWRGD_DRAMPWRGD_CPU1_CD_LVC1_R
R126             Q_RES_0402LF-0,5%,1/16W,CHIP,CA 1        PWRGD_DRAMPWRGD_CPU1_EF_R_LVC1
                                  2        PWRGD_DRAMPWRGD_CPU1_EF_LVC1_R
R128             Q_RES_0402LF-0,5%,1/16W,CHIP,CA 1        PWRGD_DRAMPWRGD_CPU1_GH_R_LVC1
                                  2        PWRGD_DRAMPWRGD_CPU1_GH_LVC1_R
R130             Q_RES_0402LF-0,5%,1/16W,CHIP,CA 1        PWRGD_CPU1_LVC1_R       
                                  2        PWRGD_CPU1_BUF_R        
R132             Q_RES_0402LF-0,5%,1/16W,CHIP,CA 1        RST_CPU1_LVC1_R_N       
                                  2        RST_CPU1_BUF_R_N        
R135             Q_RES_0402LF-100,1%,1/16W,EMPTA 1        PWRGD_DRAMPWRGD_CPU1_AB_LVC1_R
                                  2        PVCCD_HV_CPU1           
R137             Q_RES_0402LF-100,1%,1/16W,EMPTA 1        PWRGD_DRAMPWRGD_CPU1_CD_LVC1_R
                                  2        PVCCD_HV_CPU1           
R139             Q_RES_0402LF-10K,1%,1/16W,CHIPA 1        FM_BMC_PWRBTN_N         
                                  2        P3V3_AUX                
R142             Q_RES_0402LF-0,5%,1/16W,CHIP,CA 1        PVNN_TERM_CPU0          
                                  2        PVCCIO_PECI_BMC         
R143             Q_RES_0402LF-0,5%,1/16W,EMPTY,A 1        PECI_PCH                
                                  2        PECI_CPU_GTL            
R144             Q_RES_0402LF-10,1%,1/16W,CHIP,A 1        PECI_BMC                
                                  2        PECI_CPU_GTL            
R146             Q_RES_0402LF-4.75K,1%,1/16W,EMA 1        PVNN_TERM_CPU0          
                                  2        PECI_CPU_GTL            
R148             Q_RES_0402LF-10K,1%,1/16W,CHIPA 1        PECI_CPU_GTL            
                                  2        GND                     
R151             Q_RES_0402LF-100,1%,1/16W,EMPTA 1        PWRGD_DRAMPWRGD_CPU1_EF_LVC1_R
                                  2        PVCCD_HV_CPU1           
R153             Q_RES_0402LF-100,1%,1/16W,EMPTA 1        PWRGD_DRAMPWRGD_CPU1_GH_LVC1_R
                                  2        PVCCD_HV_CPU1           
R155             Q_RES_0402LF-100,1%,1/16W,EMPTA 1        PWRGD_CPU1_BUF_R        
                                  2        PVNN_TERM_CPU1          
R156             Q_RES_0402LF-33,5%,1/16W,CHIP,A 1        PWRGD_CPU1_BUF_R        
                                  2        PWRGD_CPU1_LVC1         
R157             Q_RES_0402LF-100,1%,1/16W,EMPTA 1        RST_CPU1_BUF_R_N        
                                  2        PVNN_TERM_CPU1          
R158             Q_RES_0402LF-33,5%,1/16W,CHIP,A 1        RST_CPU1_BUF_R_N        
                                  2        RST_CPU1_LVC1_N         
R160             Q_RES_0402LF-0,5%,1/16W,CHIP,CA 1        PWRGD_DRAMPWRGD_CPU0_AB_R_LVC1
                                  2        PWRGD_DRAMPWRGD_CPU0_AB_LVC1_R
R162             Q_RES_0402LF-0,5%,1/16W,CHIP,CA 1        PWRGD_DRAMPWRGD_CPU0_CD_R_LVC1
                                  2        PWRGD_DRAMPWRGD_CPU0_CD_LVC1_R
R164             Q_RES_0402LF-0,5%,1/16W,CHIP,CA 1        PWRGD_DRAMPWRGD_CPU0_EF_R_LVC1
                                  2        PWRGD_DRAMPWRGD_CPU0_EF_LVC1_R
R166             Q_RES_0402LF-0,5%,1/16W,CHIP,CA 1        PWRGD_DRAMPWRGD_CPU0_GH_R_LVC1
                                  2        PWRGD_DRAMPWRGD_CPU0_GH_LVC1_R
R168             Q_RES_0402LF-0,5%,1/16W,CHIP,CA 1        PWRGD_CPU0_LVC1_R       
                                  2        PWRGD_CPU0_BUF_R        
R171             Q_RES_0402LF-0,5%,1/16W,CHIP,CA 1        RST_CPU0_LVC1_R_N       
                                  2        RST_CPU0_BUF_R_N        
R175             Q_RES_0402LF-100,1%,1/16W,EMPTA 1        PWRGD_DRAMPWRGD_CPU0_AB_LVC1_R
                                  2        PVCCD_HV_CPU0           
R177             Q_RES_0402LF-100,1%,1/16W,EMPTA 1        PWRGD_DRAMPWRGD_CPU0_CD_LVC1_R
                                  2        PVCCD_HV_CPU0           
R179             Q_RES_0402LF-100,1%,1/16W,EMPTA 1        PWRGD_DRAMPWRGD_CPU0_EF_LVC1_R
                                  2        PVCCD_HV_CPU0           
R181             Q_RES_0402LF-100,1%,1/16W,EMPTA 1        PWRGD_DRAMPWRGD_CPU0_GH_LVC1_R
                                  2        PVCCD_HV_CPU0           
R183             Q_RES_0402LF-100,1%,1/16W,EMPTA 1        PWRGD_CPU0_BUF_R        
                                  2        PVNN_TERM_CPU0          
R184             Q_RES_0402LF-33,5%,1/16W,CHIP,A 1        PWRGD_CPU0_BUF_R        
                                  2        PWRGD_CPU0_LVC1         
R185             Q_RES_0402LF-100,1%,1/16W,EMPTA 1        RST_CPU0_BUF_R_N        
                                  2        PVNN_TERM_CPU0          
R186             Q_RES_0402LF-33,5%,1/16W,CHIP,A 1        RST_CPU0_BUF_R_N        
                                  2        RST_CPU0_LVC1_N         
R188             Q_RES_0402LF-0,5%,1/16W,CHIP,CA 1        H_CPU_NMI_LVC1_R_N      
                                  2        H_CPU_NMI_LVC1_N        
R195             Q_RES_0402LF-49.9     ,1%  ,1/A 1        H_CPU_NMI_LVC1_N        
                                  2        H_CPU0_NMI_LVC1_N       
R196             Q_RES_0402LF-49.9     ,1%  ,1/A 1        H_CPU_NMI_LVC1_N        
                                  2        H_CPU1_NMI_LVC1_N       
R197             Q_RES_0402LF-10K,1%,1/16W,EMPTA 1        PVNN_TERM_CPU0          
                                  2        H_CPU0_NMI_LVC1_N       
R198             Q_RES_0402LF-10K,1%,1/16W,EMPTA 1        PVNN_TERM_CPU1          
                                  2        H_CPU1_NMI_LVC1_N       
R199             Q_RES_0402LF-100,1%,1/16W,EMPTA 1        PVNN_TERM_CPU0          
                                  2        H_CPU0_MEMHOT_OUT_LVC1_R_N
R200             Q_RES_0402LF-100,1%,1/16W,EMPTA 1        PVNN_TERM_CPU0          
                                  2        H_CPU0_MEMTRIP_LVC1_R_N 
R201             Q_RES_0402LF-100,1%,1/16W,EMPTA 1        PVNN_TERM_CPU1          
                                  2        H_CPU1_MEMHOT_OUT_LVC1_R_N
R202             Q_RES_0402LF-100,1%,1/16W,EMPTA 1        PVNN_TERM_CPU1          
                                  2        H_CPU1_MEMTRIP_LVC1_R_N 
R203             Q_RES_0402LF-33,5%,1/16W,CHIP,A 1        H_CPU0_MEMHOT_OUT_LVC1_R_N
                                  2        H_CPU0_MEMHOT_OUT_LVC1_N
R204             Q_RES_0402LF-33,5%,1/16W,CHIP,A 1        H_CPU1_MEMHOT_OUT_LVC1_R_N
                                  2        H_CPU1_MEMHOT_OUT_LVC1_N
R205             Q_RES_0402LF-33,5%,1/16W,CHIP,A 1        H_CPU0_MEMTRIP_LVC1_R_N 
                                  2        H_CPU0_MEMTRIP_LVC1_N   
R206             Q_RES_0402LF-33,5%,1/16W,CHIP,A 1        H_CPU1_MEMTRIP_LVC1_R_N 
                                  2        H_CPU1_MEMTRIP_LVC1_N   
R208             Q_RES_0402LF-0,5%,1/16W,CHIP,CA 1        H_CPU0_MEMHOT_IN_LVC1_R_N
                                  2        H_CPU0_MEMHOT_IN_LVC1_N 
R210             Q_RES_0402LF-0,5%,1/16W,CHIP,CA 1        H_CPU1_MEMHOT_IN_LVC1_R_N
                                  2        H_CPU1_MEMHOT_IN_LVC1_N 
R219             Q_RES_0402LF-100,1%,1/16W,EMPTA 1        PVNN_TERM_CPU0          
                                  2        H_CPU0_MEMHOT_IN_LVC1_N 
R220             Q_RES_0402LF-100,1%,1/16W,EMPTA 1        PVNN_TERM_CPU1          
                                  2        H_CPU1_MEMHOT_IN_LVC1_N 
R237             Q_RES_0402LF-0,5%,1/16W,CHIP,CA 1        H_CPU0_THERMTRIP_LVC1_R_N
                                  2        H_CPU0_THERMTRIP_LVC1_N 
R238             Q_RES_0402LF-0,5%,1/16W,CHIP,CA 1        H_CPU1_THERMTRIP_LVC1_R_N
                                  2        H_CPU1_THERMTRIP_LVC1_N 
R239             Q_RES_0402LF-0,5%,1/16W,CHIP,CA 1        H_CPU0_PROCHOT_LVC1_R_N 
                                  2        H_CPU0_PROCHOT_LVC1_N   
R240             Q_RES_0402LF-0,5%,1/16W,CHIP,CA 1        H_CPU1_PROCHOT_LVC1_R_N 
                                  2        H_CPU1_PROCHOT_LVC1_N   
R241             Q_RES_0402LF-1K,1%,1/16W,EMPTYA 1        P3V3                    
                                  2        H_CPU0_THERMTRIP_LVC1_N 
R242             Q_RES_0402LF-1K,1%,1/16W,EMPTYA 1        P3V3                    
                                  2        H_CPU1_THERMTRIP_LVC1_N 
R243             Q_RES_0402LF-100,1%,1/16W,EMPTA 1        PVNN_TERM_CPU0          
                                  2        H_CPU0_PROCHOT_LVC1_N   
R244             Q_RES_0402LF-100,1%,1/16W,EMPTA 1        PVNN_TERM_CPU1          
                                  2        H_CPU1_PROCHOT_LVC1_N   
R249             Q_RES_0402LF-240,1%,1/16W,EMPTA 1        PVNN_TERM_CPU0          
                                  2        FM_S3M_CPU0_LVC1_GPIO_0 
R250             Q_RES_0402LF-240,1%,1/16W,EMPTA 1        PVNN_TERM_CPU0          
                                  2        FM_S3M_CPU0_LVC1_GPIO_1 
R251             Q_RES_0402LF-240,1%,1/16W,EMPTA 1        PVNN_TERM_CPU0          
                                  2        FM_S3M_CPU0_LVC1_GPIO_4 
R252             Q_RES_0402LF-240,1%,1/16W,CHIPA 1        PVNN_TERM_CPU0          
                                  2        PUD_PCH_BOOT_MODE_CPU0  
R253             Q_RES_0402LF-240,1%,1/16W,CHIPA 1        PVNN_TERM_CPU0          
                                  2        FM_S3M_CPU0_LVC1_GPIO_2 
R254             Q_RES_0402LF-240,1%,1/16W,CHIPA 1        PVNN_TERM_CPU0          
                                  2        FM_S3M_CPU0_LVC1_GPIO_3 
R255             Q_RES_0402LF-240,1%,1/16W,EMPTA 1        PVNN_TERM_CPU1          
                                  2        FM_S3M_CPU1_LVC1_GPIO_0 
R256             Q_RES_0402LF-240,1%,1/16W,EMPTA 1        PVNN_TERM_CPU1          
                                  2        FM_S3M_CPU1_LVC1_GPIO_1 
R257             Q_RES_0402LF-240,1%,1/16W,EMPTA 1        PVNN_TERM_CPU1          
                                  2        FM_S3M_CPU1_LVC1_GPIO_4 
R258             Q_RES_0402LF-240,1%,1/16W,CHIPA 1        PVNN_TERM_CPU1          
                                  2        PUD_PCH_BOOT_MODE_CPU1  
R259             Q_RES_0402LF-240,1%,1/16W,CHIPA 1        PVNN_TERM_CPU1          
                                  2        FM_S3M_CPU1_LVC1_GPIO_2 
R260             Q_RES_0402LF-240,1%,1/16W,CHIPA 1        PVNN_TERM_CPU1          
                                  2        FM_S3M_CPU1_LVC1_GPIO_3 
R261             Q_RES_0402LF-240,1%,1/16W,EMPTA 1        PVNN_TERM_CPU1          
                                  2        PU_CPU1_TXT_AGENT       
R262             Q_RES_0402LF-240,1%,1/16W,EMPTA 1        PVNN_TERM_CPU1          
                                  2        PU_CPU1_SAFE_MODE_BOOT  
R263             Q_RES_0402LF-240,1%,1/16W,EMPTA 1        PVNN_TERM_CPU1          
                                  2        PU_CPU1_FRMAGENT        
R264             Q_RES_0402LF-240,1%,1/16W,EMPTA 1        PVNN_TERM_CPU1          
                                  2        H_CPU1_BMCINIT_LVC1     
R265             Q_RES_0402LF-240,1%,1/16W,CHIPA 1        PVNN_TERM_CPU1          
                                  2        PU_CPU1_SOCKET_ID0      
R266             Q_RES_0402LF-240,1%,1/16W,EMPTA 1        PVNN_TERM_CPU1          
                                  2        PU_CPU1_SOCKET_ID1      
R267             Q_RES_0402LF-240,1%,1/16W,EMPTA 1        PVNN_TERM_CPU1          
                                  2        PU_CPU1_SOCKET_ID2      
R268             Q_RES_0402LF-240,1%,1/16W,EMPTA 1        PVNN_TERM_CPU1          
                                  2        PU_CPU1_LEGACY_SKT      
R269             Q_RES_0402LF-33.2,1%,1/16W,CHIA 1        FM_ADR_MODE1            
                                  2        FM_ADR_MODE1_R          
R270             Q_RES_0402LF-10K,1%,1/16W,CHIPA 1        P3V3_AUX                
                                  2        FM_CPU1_PKGID0          
R271             Q_RES_0402LF-10K,1%,1/16W,CHIPA 1        P3V3_AUX                
                                  2        FM_CPU1_PKGID1          
R272             Q_RES_0402LF-10K,1%,1/16W,CHIPA 1        P3V3_AUX                
                                  2        FM_CPU1_PKGID2          
R273             Q_RES_0402LF-10K,1%,1/16W,CHIPA 1        P3V3_AUX                
                                  2        FM_CPU1_PROC_ID0        
R274             Q_RES_0402LF-10K,1%,1/16W,CHIPA 1        P3V3_AUX                
                                  2        FM_CPU1_PROC_ID1        
R275             Q_RES_0402LF-240,1%,1/16W,CHIPA 1        PVNN_TERM_CPU0          
                                  2        PU_CPU0_TXT_AGENT       
R276             Q_RES_0402LF-240,1%,1/16W,EMPTA 1        PVNN_TERM_CPU0          
                                  2        PU_CPU0_SAFE_MODE_BOOT  
R277             Q_RES_0402LF-240,1%,1/16W,CHIPA 1        PVNN_TERM_CPU0          
                                  2        PU_CPU0_FRMAGENT        
R278             Q_RES_0402LF-240,1%,1/16W,EMPTA 1        PVNN_TERM_CPU0          
                                  2        H_CPU0_BMCINIT_LVC1     
R279             Q_RES_0402LF-240,1%,1/16W,EMPTA 1        PVNN_TERM_CPU0          
                                  2        PU_CPU0_SOCKET_ID0      
R280             Q_RES_0402LF-240,1%,1/16W,EMPTA 1        PVNN_TERM_CPU0          
                                  2        PU_CPU0_SOCKET_ID1      
R281             Q_RES_0402LF-240,1%,1/16W,EMPTA 1        PVNN_TERM_CPU0          
                                  2        PU_CPU0_SOCKET_ID2      
R282             Q_RES_0402LF-240,1%,1/16W,CHIPA 1        PVNN_TERM_CPU0          
                                  2        PU_CPU0_LEGACY_SKT      
R283             Q_RES_0402LF-10K,1%,1/16W,CHIPA 1        P3V3_AUX                
                                  2        FM_CPU0_PKGID0          
R284             Q_RES_0402LF-10K,1%,1/16W,CHIPA 1        P3V3_AUX                
                                  2        FM_CPU0_PKGID1          
R285             Q_RES_0402LF-10K,1%,1/16W,CHIPA 1        P3V3_AUX                
                                  2        FM_CPU0_PKGID2          
R286             Q_RES_0402LF-10K,1%,1/16W,CHIPA 1        P3V3_AUX                
                                  2        FM_CPU0_PROC_ID0        
R287             Q_RES_0402LF-10K,1%,1/16W,CHIPA 1        P3V3_AUX                
                                  2        FM_CPU0_PROC_ID1        
R288             Q_RES_0402LF-240,1%,1/16W,CHIPA 1        GND                     
                                  2        PD_CPU1_TXT_PLTEN       
R289             Q_RES_0402LF-240,1%,1/16W,CHIPA 1        GND                     
                                  2        PD_CPU1_BIST_ENABLE     
R290             Q_RES_0402LF-240,1%,1/16W,CHIPA 1        GND                     
                                  2        PD_CPU1_DMIMODE_OVERRIDE
R291             Q_RES_0402LF-240,1%,1/16W,EMPTA 1        GND                     
                                  2        PD_CPU1_ENH_MCECC_DIS   
R292             Q_RES_0402LF-240,1%,1/16W,CHIPA 1        GND                     
                                  2        PD_CPU0_TXT_PLTEN       
R293             Q_RES_0402LF-240,1%,1/16W,CHIPA 1        GND                     
                                  2        PD_CPU0_BIST_ENABLE     
R294             Q_RES_0402LF-240,1%,1/16W,EMPTA 1        GND                     
                                  2        PD_CPU0_DMIMODE_OVERRIDE
R295             Q_RES_0402LF-240,1%,1/16W,EMPTA 1        GND                     
                                  2        PD_CPU0_ENH_MCECC_DIS   
R296             Q_RES_0402LF-301,1%,1/16W,CHIPA 1        PVNN_TERM_CPU0          
                                  2        H_CPU_CATERR_LVC1_R_N   
R297             Q_RES_0402LF-0,5%,1/16W,CHIP,CA 1        H_CPU0_CATERR_LVC1_R_N  
                                  2        H_CPU_CATERR_LVC1_R_N   
R298             Q_RES_0402LF-301,1%,1/16W,CHIPA 1        PVNN_TERM_CPU1          
                                  2        H_CPU_CATERR_LVC1_R_N   
R299             Q_RES_0402LF-0,5%,1/16W,CHIP,CA 1        H_CPU1_CATERR_LVC1_R_N  
                                  2        H_CPU_CATERR_LVC1_R_N   
R301             Q_RES_0402LF-301,1%,1/16W,CHIPA 1        PVNN_TERM_CPU0          
                                  2        H_CPU_RMCA_LVC1_R_N     
R302             Q_RES_0402LF-33.2,1%,1/16W,CHIA 1        H_CPU0_RMCA_LVC1_R_N    
                                  2        H_CPU_RMCA_LVC1_R_N     
R303             Q_RES_0402LF-301,1%,1/16W,CHIPA 1        PVNN_TERM_CPU1          
                                  2        H_CPU_RMCA_LVC1_R_N     
R304             Q_RES_0402LF-33.2,1%,1/16W,CHIA 1        H_CPU1_RMCA_LVC1_R_N    
                                  2        H_CPU_RMCA_LVC1_R_N     
R315             Q_RES_0402LF-33,5%,1/16W,CHIP,A 1        PWRGD_CPUPWRGD_GTL      
                                  2        PWRGD_CPUPWRGD_LVC1_R   
R316             Q_RES_0402LF-4.32K,1%,1/16W,CHA 1        PWRGD_S0_PWROK_CPU1_LVC1_R
                                  2        GND                     
R318             Q_RES_0402LF-10K,1%,1/16W,CHIPA 1        FM_SPD_REMOTE_EN        
                                  2        GND                     
R319             Q_RES_0402LF-10K,1%,1/16W,CHIPA 1        P3V3_AUX                
                                  2        PU_S3M_CPU0_CPLD_STATUS 
R320             Q_RES_0402LF-10K,1%,1/16W,CHIPA 1        P3V3_AUX                
                                  2        PU_S3M_CPU0_CPLD_CONFD  
R321             Q_RES_0402LF-10K,1%,1/16W,CHIPA 1        P3V3_AUX                
                                  2        FM_S3M_CPU0_CPLD_CONFIG_N
R322             Q_RES_0402LF-33.2,1%,1/16W,CHIA 1        H_CPU0_PMSYNC_CPU1_R    
                                  2        H_CPU0_PMSYNC_CPU1      
R323             Q_RES_1206LF-0,,1/2W,EMPTY,CS0A 1        PVCCINFAON_CPU0         
                                  2        PVNN_TERM_CPU0          
R324             Q_RES_1206LF-0,,1/2W,CHIP,CS00A 1        PVNN_MAIN_CPU0          
                                  2        PVNN_TERM_CPU0          
R325             Q_RES_0402LF-10K,1%,1/16W,CHIPA 1        P3V3_AUX                
                                  2        PU_S3M_CPU1_CPLD_STATUS 
R326             Q_RES_0402LF-10K,1%,1/16W,CHIPA 1        P3V3_AUX                
                                  2        PU_S3M_CPU1_CPLD_CONFD  
R327             Q_RES_0402LF-10K,1%,1/16W,CHIPA 1        P3V3_AUX                
                                  2        FM_S3M_CPU1_CPLD_CONFIG_N
R328             Q_RES_0402LF-100,1%,1/16W,CHIPA 1        SVID_DIO0_CPU0_R        
                                  2        PVNN_TERM_CPU0          
R329             Q_RES_1206LF-0,,1/2W,EMPTY,CS0A 1        PVCCINFAON_CPU1         
                                  2        PVNN_TERM_CPU1          
R330             Q_RES_1206LF-0,,1/2W,CHIP,CS00A 1        PVNN_MAIN_CPU1          
                                  2        PVNN_TERM_CPU1          
R331             Q_RES_0402LF-1K,1%,1/16W,EMPTYA 1        P3V3_AUX                
                                  2        PD_PIROM_CPU0_ADDR2     
R332             Q_RES_0402LF-10K,1%,1/16W,CHIPA 1        PD_PIROM_CPU0_ADDR2     
                                  2        GND                     
R333             Q_RES_0402LF-1K,1%,1/16W,EMPTYA 1        P3V3_AUX                
                                  2        PD_PIROM_CPU0_ADDR1     
R334             Q_RES_0402LF-10K,1%,1/16W,CHIPA 1        PD_PIROM_CPU0_ADDR1     
                                  2        GND                     
R335             Q_RES_0402LF-1K,1%,1/16W,EMPTYA 1        P3V3_AUX                
                                  2        PD_PIROM_CPU0_ADDR0     
R336             Q_RES_0402LF-0,5%,1/16W,CHIP,CA 1        H_CPU0_ERR0_LVC1_R_N    
                                  2        H_CPU_ERR0_LVC1_R_N     
R337             Q_RES_0402LF-0,5%,1/16W,CHIP,CA 1        H_CPU1_ERR0_LVC1_R_N    
                                  2        H_CPU_ERR0_LVC1_R_N     
R338             Q_RES_0402LF-33,5%,1/16W,CHIP,A 1        H_CPU_ERR0_LVC1_R_N     
                                  2        H_CPU_ERR0_LVC1_N       
R339             Q_RES_0402LF-33,5%,1/16W,CHIP,A 1        H_CPU_ERR0_LVC1_R_N     
                                  2        H_CPU_ERR0_PCH_R_N      
R340             Q_RES_0402LF-0,5%,1/16W,CHIP,CA 1        H_CPU0_ERR1_LVC1_R_N    
                                  2        H_CPU_ERR1_LVC1_R_N     
R341             Q_RES_0402LF-0,5%,1/16W,CHIP,CA 1        H_CPU1_ERR1_LVC1_R_N    
                                  2        H_CPU_ERR1_LVC1_R_N     
R342             Q_RES_0402LF-33,5%,1/16W,CHIP,A 1        H_CPU_ERR1_LVC1_R_N     
                                  2        H_CPU_ERR1_LVC1_N       
R343             Q_RES_0402LF-33,5%,1/16W,CHIP,A 1        H_CPU_ERR1_LVC1_R_N     
                                  2        H_CPU_ERR1_PCH_R_N      
R344             Q_RES_0402LF-0,5%,1/16W,CHIP,CA 1        H_CPU0_ERR2_LVC1_R_N    
                                  2        H_CPU_ERR2_LVC1_R_N     
R345             Q_RES_0402LF-0,5%,1/16W,CHIP,CA 1        H_CPU1_ERR2_LVC1_R_N    
                                  2        H_CPU_ERR2_LVC1_R_N     
R346             Q_RES_0402LF-33,5%,1/16W,CHIP,A 1        H_CPU_ERR2_LVC1_R_N     
                                  2        H_CPU_ERR2_LVC1_N       
R347             Q_RES_0402LF-33,5%,1/16W,CHIP,A 1        H_CPU_ERR2_LVC1_R_N     
                                  2        H_CPU_ERR2_PCH_R_N      
R365             Q_RES_0402LF-0,5%,1/16W,CHIP,CA 1        FM_CPU_RMCA_CATERR_LVT3_R_N
                                  2        CPU_RMCA_CATERR_LVT3_N  
R366             Q_RES_0402LF-332,1%,1/16W,CHIPA 1        LED_CPU_RMCA_CATERR     
                                  2        LED_CPU_RMCA_CATERR_R   
R367             Q_RES_0402LF-1K,5%,1/16W,CHIP,A 1        P3V3_AUX                
                                  2        PU_NO_REBOOT_STRAP      
R369             Q_RES_0402LF-1K,5%,1/16W,CHIP,A 1        P3V3_AUX                
                                  2        FM_ADR_ACK              
R371             Q_RES_0402LF-1K,5%,1/16W,EMPTYA 1        P3V3_AUX                
                                  2        FM_PCH_BOOT_BIOS_STRAP  
R372             Q_RES_0402LF-10K,1%,1/16W,CHIPA 1        FM_PCH_BOOT_BIOS_STRAP  
                                  2        GND                     
R374             Q_RES_0402LF-1K,5%,1/16W,EMPTYA 1        P3V3_AUX                
                                  2        FM_SPI_3V3_1V8_VOLTAGE  
R375             Q_RES_0402LF-10K,1%,1/16W,CHIPA 1        FM_SPI_3V3_1V8_VOLTAGE  
                                  2        GND                     
R378             Q_RES_0402LF-1K,5%,1/16W,EMPTYA 1        P3V3_AUX                
                                  2        FM_ADR_MODE1            
R379             Q_RES_0402LF-1K,5%,1/16W,CHIP,A 1        FM_ADR_MODE1            
                                  2        GND                     
R380             Q_RES_0402LF-1K,5%,1/16W,EMPTYA 1        P3V3_AUX                
                                  2        FM_FLASH_SECURITY_STRAP 
R381             Q_RES_0402LF-10K,1%,1/16W,CHIPA 1        FM_FLASH_SECURITY_STRAP 
                                  2        GND                     
R382             Q_RES_0402LF-1K,5%,1/16W,EMPTYA 1        P1V05_PCH_AUX           
                                  2        FM_XTAL_INPUT_FREQUENCY_0_MGPIO
R388             Q_RES_0402LF-10K,1%,1/16W,CHIPA 1        P3V3_AUX                
                                  2        RISER2_TYPE_ID          
R391             Q_RES_0402LF-10K,1%,1/16W,CHIPA 1        P3V3_AUX                
                                  2        RISER3_TYPE_ID          
R392             Q_RES_0402LF-10K,5%,1/16W,CHIPA 1        P3V3_AUX                
                                  2        PCIE_RISER3_PRSNT2_N    
R394             Q_RES_0402LF-4.7K,5%,1/16W,CHIA 1        FM_PCIE_EDSFF2A_PRSNT_1_N
                                  2        P3V3_AUX                
R395             Q_RES_0402LF-10K,1%,1/16W,CHIPA 1        PU_EDSFF2A_PERST1_CLKREQ_N
                                  2        P3V3_AUX                
R396             Q_RES_0402LF-10K,1%,1/16W,CHIPA 1        PD_EDSFF2A_PWRDIS       
                                  2        GND                     
R398             Q_RES_0402LF-4.7K,5%,1/16W,CHIA 1        FM_PCIE_EDSFF2B_PRSNT_1_N
                                  2        P3V3_AUX                
R399             Q_RES_0402LF-10K,1%,1/16W,CHIPA 1        PU_EDSFF2B_PERST1_CLKREQ_N
                                  2        P3V3_AUX                
R400             Q_RES_0402LF-10K,1%,1/16W,CHIPA 1        PD_EDSFF2B_PWRDIS       
                                  2        GND                     
R401             Q_RES_0402LF-10K,1%,1/16W,EMPTA 1        P1V8_PCH_AUX            
                                  2        IRQ_TPM_SPI_N           
R402             Q_RES_0402LF-4.7K,5%,1/16W,CHIA 1        FM_PCIE_EDSFF3_PRSNT_1_N
                                  2        P3V3_AUX                
R404             Q_RES_0402LF-10K,1%,1/16W,CHIPA 2        GND                     
R409             Q_RES_0402LF-4.7K,1%,1/16W,EMPA 1        P3V3_OCP_SFF            
                                  2        OCP_SFF_ID0             
R410             Q_RES_0402LF-4.7K,1%,1/16W,CHIA 1        OCP_SFF_ID0             
                                  2        GND                     
R413             Q_RES_0402LF-100K,1%,1/16W,CHIA 1        GND                     
                                  2        FM_OCP_SFF_PWR_GOOD     
R414             Q_RES_0402LF-4.7K,1%,1/16W,EMPA 1        P3V3_OCP_SFF            
                                  2        OCP_SFF_ID1             
R415             Q_RES_0402LF-4.7K,1%,1/16W,CHIA 1        OCP_SFF_ID1             
                                  2        GND                     
R416             Q_RES_0402LF-0,5%,1/16W,CHIP,CA 1        OCP_SFF_ISO_BIF0_EN     
                                  2        OCP_SFF_BIF0_R_N        
R417             Q_RES_0402LF-0,5%,1/16W,CHIP,CA 1        OCP_SFF_ISO_BIF1_EN     
                                  2        OCP_SFF_BIF1_R_N        
R418             Q_RES_0402LF-0,5%,1/16W,CHIP,CA 1        OCP_SFF_ISO_BIF2_EN     
                                  2        OCP_SFF_BIF2_R_N        
R419             Q_RES_0402LF-33.2,1%,1/16W,CHIA 1        RST_OCP_V3_1_BUF_N      
                                  2        RST_PERST0_OCP_SFF_N    
R420             Q_RES_0402LF-1K,1%,1/16W,EMPTYA 1        SGPIO_OCP_SFF_LD_N      
                                  2        P3V3_OCP_SFF            
R421             Q_RES_0402LF-4.7K,5%,1/16W,CHIA 1        SGPIO_OCP_SFF_DATAIN_N  
                                  2        P3V3_OCP_SFF            
R422             Q_RES_0402LF-1K,1%,1/16W,EMPTYA 1        SGPIO_OCP_SFF_DATAOUT_N 
                                  2        GND                     
R423             Q_RES_0402LF-0,5%,1/16W,EMPTY,A 1        SGPIO_OCP_SFF_CLK_N     
                                  2        GND                     
R424             Q_RES_0402LF-33.2,1%,1/16W,CHIA 1        SMB_OCP_SFF_3V3AUX_R_SCL
                                  2        SMB_OCP_SFF_3V3AUX_SCL  
R425             Q_RES_0402LF-33.2,1%,1/16W,CHIA 1        SMB_OCP_SFF_3V3AUX_R_SDA
                                  2        SMB_OCP_SFF_3V3AUX_SDA  
R429             Q_RES_0402LF-0,5%,1/16W,CHIP,CA 1        HP_LVC3_OCP_V3_1_HSC_PWRGD
                                  2        OCP_SFF_MAIN_PWR_EN     
R435             Q_RES_0402LF-33.2,1%,1/16W,CHIA 1        RST_OCP_V3_1_BUF_N      
                                  2        RST_PERST1_OCP_SFF_N    
R442             Q_RES_0603LF-1,1%,1/10W,CHIP,CA 1        P3V3_AUX_CLK_GEN_VDDXTAL_CK440
                                  2        P3V3_AUX_CLK_GEN_VDDA25M_CK440
R444             Q_RES_0402LF-0,5%,1/16W,CHIP,CA 1        OCP_SFF_USB2_3_DN       
                                  2        USB2_3_DN               
R445             Q_RES_0402LF-0,5%,1/16W,CHIP,CA 1        OCP_SFF_USB2_3_DP       
                                  2        USB2_3_DP               
R447             Q_RES_0603LF-1,1%,1/10W,CHIP,CA 1        P3V3_AUX_CLK_GEN_VDDMXCK_CK440
                                  2        P3V3_AUX_CLK_GEN_VDDPT_CK440
R448             Q_RES_0402LF-0,5%,1/16W,EMPTY,A 1        SMB_S3M_CPU0_3V3AUX_SCL 
                                  2        SMB_S3M_CPU1_3V3AUX_SCL 
R453             Q_RES_0402LF-10K,1%,1/16W,CHIPA 1        P3V3_AUX                
                                  2        PU_LAN_WAKE_N           
R454             Q_RES_0402LF-10K,1%,1/16W,EMPTA 1        P3V3_OCP_SFF            
                                  2        PU_RST_SMB_OCP_SFF_N    
R456             Q_RES_0402LF-10K,1%,1/16W,CHIPA 1        P3V3_AUX                
                                  2        PU_PCH_PMCALERT_N       
R459             Q_RES_0402LF-33.2,1%,1/16W,CHIA 1        SMB_SENSOR_3V3AUX_SDA   
                                  2        SMB_TMP75_1_3V3AUX_SDA_R
R460             Q_RES_0402LF-33.2,1%,1/16W,CHIA 1        SMB_SENSOR_3V3AUX_SCL   
                                  2        SMB_TMP75_1_3V3AUX_SCL_R
R461             Q_RES_0402LF-100K,5%,1/16W,CHIA 1        P5V                     
                                  2        PU_USB_INT_P5V_EN_N     
R462             Q_RES_0402LF-20K,1%,1/16W,CHIPA 1        PD_USB_INT_ILIM         
                                  2        GND                     
R463             Q_RES_0402LF-10K,1%,1/16W,CHIPA 1        P3V3_AUX                
                                  2        USB_OC2_INT_N           
R464             Q_RES_0402LF-0,5%,1/16W,CHIP,CA 1        USB3_9_TX_DN_C          
                                  2        USB3_9_TX_DN_FB         
R465             Q_RES_0402LF-0,5%,1/16W,CHIP,CA 1        USB3_9_TX_DP_C          
                                  2        USB3_9_TX_DP_FB         
R466             Q_RES_0402LF-0,5%,1/16W,CHIP,CA 1        USB3_9_RX_DN            
                                  2        USB3_9_RX_DN_FB         
R468             Q_RES_0402LF-0,5%,1/16W,CHIP,CA 1        USB3_9_RX_DP            
                                  2        USB3_9_RX_DP_FB         
R469             Q_RES_0402LF-0,5%,1/16W,CHIP,CA 1        USB2_1_DP               
                                  2        USB2_1_F_DP             
R470             Q_RES_0402LF-0,5%,1/16W,CHIP,CA 1        USB2_1_DN               
                                  2        USB2_1_F_DN             
R471             Q_RES_0402LF-0,5%,1/16W,CHIP,CA 1        USB_OC2_INT_N           
                                  2        USB_OC2_INT_R_N         
R473             Q_RES_0402LF-0,5%,1/16W,CHIP,CA 1        IRQ_PSU_ALERT_N         
                                  2        FM_OV_ADR_TRIGGER_N     
R474             Q_RES_0402LF-33,5%,1/16W,CHIP,A 1        FM_PCHHOT_N             
                                  2        FM_PCHHOT_R_N           
R475             Q_RES_0402LF-33.2,1%,1/16W,CHIA 1        SMB_SENSOR_3V3AUX_SCL   
                                  2        SMB_FRU_3V3AUX_SCL_R    
R477             Q_RES_0402LF-60.4,1%,1/16W,CHIA 1        PD_PCH_XCLK_BIASREF     
                                  2        GND                     
R478             Q_RES_0402LF-4.7K,1%,1/16W,CHIA 1        P3V3_AUX                
                                  2        PCIE_M2_SSD0_PRSNT_N    
R480             Q_RES_0402LF-0,5%,1/16W,CHIP,CA 1        JTAG_DBP_TMS            
                                  2        JTAG_DBP_FB_TMS         
R481             Q_RES_0402LF-0,5%,1/16W,CHIP,CA 1        JTAG_DBP_TDI            
                                  2        JTAG_DBP_FB_TDI         
R482             Q_RES_0402LF-0,5%,1/16W,CHIP,CA 1        JTAG_DBP_PREQ_N         
                                  2        JTAG_DBP_PREQ_R_N       
R483             Q_RES_0402LF-0,5%,1/16W,CHIP,CA 1        JTAG_BMC_DBP_TDO_R      
                                  2        JTAG_BMC_DBP_TDO        
R484             Q_RES_0402LF-4.7K,1%,1/16W,EMPA 1        P3V3                    
                                  2        PU_DAS_DSS_N            
R485             Q_RES_0402LF-0,5%,1/16W,CHIP,CA 1        RST_PCIE_PCH_DEV_PERST_N
                                  2        RST_PCIE_PCH_DEV_0_N    
R486             Q_RES_0402LF-0,5%,1/16W,CHIP,CA 1        M2_SSD0_CLKREQ_EN_N     
                                  2        M2_SSD0_CLKREQ_EN_N_BUF 
R487             Q_RES_0402LF-1K,1%,1/16W,EMPTYA 1        P3V3_AUX                
                                  2        M2_SSD0_CLKREQ_EN_N_BUF 
R491             Q_RES_0402LF-4.7K,1%,1/16W,EMPA 1        M2_SSD0_CLKREQ_EN_N     
                                  2        GND                     
R494             Q_RES_0402LF-4.75K,1%,1/16W,CHA 1        P3V3_AUX                
                                  2        IRQ_LVC3_WAKE_N         
R495             Q_RES_0402LF-100,1%,1/16W,CHIPA 1        PCH_PCIEUP_RCOMPP       
                                  2        PCH_PCIEUP_RCOMPN       
R496             Q_RES_0402LF-113,1%,1/16W,CHIPA 1        PD_PCH_USB2_COMP        
                                  2        GND                     
R497             Q_RES_0402LF-200,1%,1/16W,CHIPA 1        PD_RCOMP_1P8_3P3        
                                  2        GND                     
R498             Q_RES_0402LF-10K,1%,1/16W,CHIPA 1        P3V3_AUX                
                                  2        FM_PCH_PRSNT_N          
R499             Q_RES_0402LF-33.2,1%,1/16W,CHIA 1        SPI_PCH_CLK             
                                  2        SPI_SYS_CLK             
R500             Q_RES_0402LF-33.2,1%,1/16W,CHIA 1        SPI_PCH_CS1_R_N         
                                  2        SPI_PCH_PFR_CS1_N       
R501             Q_RES_0402LF-33.2,1%,1/16W,CHIA 1        SPI_PCH_CS0_R_N         
                                  2        SPI_SYS_CS0_N           
R502             Q_RES_0402LF-20K,5%,1/16W,EMPTA 1        P3V3_AUX                
                                  2        FM_PCH_CONSENT_STRAP_N  
R506             Q_RES_0402LF-0,5%,1/16W,CHIP,CA 1        IRQ_SMI_ACTIVE_BMC_N    
                                  2        IRQ0_A57                
R507             Q_RES_0402LF-0,5%,1/16W,EMPTY,A 1        PVCCA_AUX_PLD           
                                  2        P3V3_AUX_DPLD_ADC_VREF  
R508             Q_RES_0402LF-0,5%,1/16W,EMPTY,A 1        P3V3_AUX_DPLD_ADC_VREF  
                                  2        GND                     
R509             Q_RES_0402LF-0,5%,1/16W,CHIP,CA 1        FP_DPLD_ANAIN1          
                                  2        GND                     
R511             Q_RES_1206LF-0,5%,1/4W,CHIP,CSA 1        PVCCD_HV_CPU0           
                                  2        PVCCIO_PLDIO2           
R512             Q_RES_1206LF-0,5%,1/4W,EMPTY,CA 1        P3V3_AUX                
                                  2        PVCCIO_PLDIO2           
R513             Q_RES_1206LF-0,5%,1/4W,CHIP,CSA 1        PVNN_TERM_CPU0          
                                  2        PVCCIO_PLDIO5           
R514             Q_RES_1206LF-0,5%,1/4W,EMPTY,CA 1        P3V3_AUX                
                                  2        PVCCIO_PLDIO5           
R515             Q_RES_0402LF-10K,1%,1/16W,CHIPA 1        PD_PIROM_CPU0_ADDR0     
                                  2        GND                     
R519             Q_RES_0603LF-1,1%,1/10W,CHIP,CA 1        P3V3_AUX_CLK_GEN_VDD_CK440
                                  2        P3V3_AUX_CLK_GEN_VDDA100M_CK440
R520             Q_RES_0402LF-0,5%,1/16W,CHIP,CA 1        CLK_100M_PE_2_R_DP      
                                  2        CLK_100M_PE_2_DP        
R521             Q_RES_0402LF-0,5%,1/16W,CHIP,CA 1        CLK_100M_PE_2_R_DN      
                                  2        CLK_100M_PE_2_DN        
R522             Q_RES_0402LF-0,5%,1/16W,CHIP,CA 1        CLK_100M_PE_3_R_DP      
                                  2        CLK_100M_PE_3_DP        
R523             Q_RES_0402LF-0,5%,1/16W,CHIP,CA 1        CLK_100M_PE_3_R_DN      
                                  2        CLK_100M_PE_3_DN        
R524             Q_RES_0402LF-0,5%,1/16W,CHIP,CA 1        CLK_100M_PE_4_R_DP      
                                  2        CLK_100M_PE_4_DP        
R525             Q_RES_0402LF-0,5%,1/16W,CHIP,CA 1        CLK_100M_PE_4_R_DN      
                                  2        CLK_100M_PE_4_DN        
R526             Q_RES_0402LF-0,5%,1/16W,CHIP,CA 1        CLK_100M_PE_5_R_DP      
                                  2        CLK_100M_PE_5_DP        
R527             Q_RES_0402LF-0,5%,1/16W,CHIP,CA 1        CLK_100M_PE_5_R_DN      
                                  2        CLK_100M_PE_5_DN        
R528             Q_RES_0402LF-0,5%,1/16W,CHIP,CA 1        CLK_100M_E1S_0_R_DP     
                                  2        CLK_100M_E1S_0_DP       
R529             Q_RES_0402LF-0,5%,1/16W,CHIP,CA 1        CLK_100M_E1S_0_R_DN     
                                  2        CLK_100M_E1S_0_DN       
R530             Q_RES_0402LF-0,5%,1/16W,CHIP,CA 1        CLK_100M_E1S_1_R_DP     
                                  2        CLK_100M_E1S_1_DP       
R531             Q_RES_0402LF-0,5%,1/16W,CHIP,CA 1        CLK_100M_E1S_1_R_DN     
                                  2        CLK_100M_E1S_1_DN       
R532             Q_RES_0402LF-0,5%,1/16W,CHIP,CA 1        CLK_100M_E1S_2_R_DP     
                                  2        CLK_100M_E1S_2_DP       
R533             Q_RES_0402LF-0,5%,1/16W,CHIP,CA 1        CLK_100M_E1S_2_R_DN     
                                  2        CLK_100M_E1S_2_DN       
R534             Q_RES_0402LF-0,5%,1/16W,CHIP,CA 1        CLK_100M_E1S_3_R_DP     
                                  2        CLK_100M_E1S_3_DP       
R535             Q_RES_0402LF-0,5%,1/16W,CHIP,CA 1        CLK_100M_E1S_3_R_DN     
                                  2        CLK_100M_E1S_3_DN       
R536             Q_RES_0402LF-10K,1%,1/16W,EMPTA 1        P3V3_AUX                
                                  2        PCA9546_PCIE0_ADDR2     
R537             Q_RES_0402LF-1K,1%,1/16W,CHIP,A 1        PCA9546_PCIE0_ADDR2     
                                  2        GND                     
R538             Q_RES_0402LF-10K,1%,1/16W,EMPTA 1        P3V3_AUX                
                                  2        PCA9546_PCIE0_ADDR1     
R539             Q_RES_0402LF-1K,1%,1/16W,CHIP,A 1        PCA9546_PCIE0_ADDR1     
                                  2        GND                     
R540             Q_RES_0402LF-10K,1%,1/16W,EMPTA 1        P3V3_AUX                
                                  2        PCA9546_PCIE0_ADDR0     
R541             Q_RES_0402LF-0,5%,1/16W,CHIP,CA 1        IRQ_PSYS_CRIT_N         
                                  2        PVCCIN_CPU0_PIN_ALERT   
R548             Q_RES_0402LF-49.9     ,1%  ,1/A 1        SVID_ALERT0_CPU0_R_N    
                                  2        PVNN_TERM_CPU0          
R553             Q_RES_0402LF-0,5%,1/16W,CHIP,CA 1        CLK_100M_CK440_PCH_EXTCLK_R_DP
                                  2        CLK_100M_CK440_PCH_EXTCLK_DP
R554             Q_RES_0402LF-0,5%,1/16W,CHIP,CA 1        CLK_100M_CK440_PCH_EXTCLK_R_DN
                                  2        CLK_100M_CK440_PCH_EXTCLK_DN
R555             Q_RES_0402LF-100,1%,1/16W,CHIPA 1        SVID_DIO1_CPU0_R        
                                  2        PVNN_TERM_CPU0          
R556             Q_RES_0402LF-49.9     ,1%  ,1/A 1        SVID_ALERT1_CPU0_R_N    
                                  2        PVNN_TERM_CPU0          
R557             Q_RES_0402LF-100,1%,1/16W,CHIPA 1        SVID_DIO0_CPU1_R        
                                  2        PVNN_TERM_CPU0          
R558             Q_RES_0402LF-49.9     ,1%  ,1/A 1        SVID_ALERT0_CPU1_R_N    
                                  2        PVNN_TERM_CPU0          
R559             Q_RES_0402LF-100,1%,1/16W,CHIPA 1        SVID_DIO1_CPU1_R        
                                  2        PVNN_TERM_CPU0          
R560             Q_RES_0402LF-49.9     ,1%  ,1/A 1        SVID_ALERT1_CPU1_R_N    
                                  2        PVNN_TERM_CPU0          
R561             Q_RES_0402LF-100,1%,1/16W,EMPTA 1        PVNN_TERM_CPU0          
                                  2        SVID_DIO0_CPU0_R        
R562             Q_RES_0402LF-4.75K,1%,1/16W,EMA 1        P3V3_AUX                
                                  2        CLK_CK440_SMB_ADDR1     
R563             Q_RES_0402LF-0,5%,1/16W,CHIP,CA 1        CLK_100M_OCP_SFF_0_R_DP 
                                  2        CLK_100M_OCP_SFF_0_DP   
R564             Q_RES_0402LF-0,5%,1/16W,CHIP,CA 1        CLK_100M_OCP_SFF_0_R_DN 
                                  2        CLK_100M_OCP_SFF_0_DN   
R565             Q_RES_0402LF-0,5%,1/16W,CHIP,CA 1        CLK_100M_OCP_SFF_1_R_DP 
                                  2        CLK_100M_OCP_SFF_1_DP   
R566             Q_RES_0402LF-0,5%,1/16W,CHIP,CA 1        CLK_100M_OCP_SFF_1_R_DN 
                                  2        CLK_100M_OCP_SFF_1_DN   
R567             Q_RES_0402LF-4.7K,1%,1/16W,EMPA 1        P3V3                    
                                  2        PD_DB2000_SMB_SA1       
R568             Q_RES_0402LF-4.7K,1%,1/16W,CHIA 1        PD_DB2000_SMB_SA1       
                                  2        GND                     
R569             Q_RES_0402LF-4.7K,1%,1/16W,EMPA 1        P3V3                    
                                  2        PD_DB2000_SMB_SA0       
R570             Q_RES_0402LF-4.7K,1%,1/16W,CHIA 1        PD_DB2000_SMB_SA0       
                                  2        GND                     
R571             Q_RES_0603LF-2.2,1%,1/10W,CHIPA 1        P3V3_DB2000_FB_VDD      
                                  2        P3V3_DB2000_VDDR        
R572             Q_RES_0603LF-2.2,1%,1/10W,CHIPA 1        P3V3_DB2000_FB_VDD      
                                  2        P3V3_DB2000_VDDA        
R573             Q_RES_0402LF-4.7K,1%,1/16W,EMPA 1        P3V3                    
                                  2        FM_DB2000_VSBEN         
R574             Q_RES_0402LF-4.7K,1%,1/16W,CHIA 1        FM_DB2000_VSBEN         
                                  2        GND                     
R575             Q_RES_0402LF-49.9     ,1%  ,1/A 1        FM_PLD_CLKS_DEV_EN      
                                  2        FM_DB2000_DEV_EN        
R576             Q_RES_0402LF-49.9     ,1%  ,1/A 1        FM_DB2000_OE_N          
                                  2        FM_DB2000_1_OE_N        
R577             Q_RES_0402LF-33,5%,1/16W,CHIP,A 1        SMB_HOST_3V3AUX_SCL     
                                  2        SMB_HOST_3V3AUX_SCL_R   
R578             Q_RES_0402LF-33,5%,1/16W,CHIP,A 1        SMB_HOST_3V3AUX_SDA     
                                  2        SMB_HOST_3V3AUX_SDA_R   
R579             Q_RES_0402LF-33,5%,1/16W,CHIP,A 1        SMB_HOST_3V3AUX_SCL     
                                  2        SMB_HOST_BMC_3V3AUX_SCL 
R580             Q_RES_0402LF-33,5%,1/16W,CHIP,A 1        SMB_HOST_3V3AUX_SDA     
                                  2        SMB_HOST_BMC_3V3AUX_SDA 
R581             Q_RES_0402LF-33,5%,1/16W,CHIP,A 1        SMB_SML0_3V3AUX_SCL     
                                  2        SMB_SML0_3V3AUX_PCH_SCL 
R582             Q_RES_0402LF-33,5%,1/16W,CHIP,A 1        SMB_SML0_3V3AUX_SDA     
                                  2        SMB_SML0_3V3AUX_PCH_SDA 
R585             Q_RES_0402LF-33,5%,1/16W,CHIP,A 1        SMB_SML1_PMBUS_3V3AUX_PCH_SCL
                                  2        SMB_SML1_PMBUS_3V3AUX_PLD_SCL
R586             Q_RES_0402LF-33,5%,1/16W,CHIP,A 1        SMB_SML1_PMBUS_3V3AUX_PCH_SDA
                                  2        SMB_SML1_PMBUS_3V3AUX_PLD_SDA
R587             Q_RES_0402LF-1K,1%,1/16W,CHIP,A 1        PCA9546_PCIE0_ADDR0     
                                  2        GND                     
R588             Q_RES_0402LF-33.2,1%,1/16W,CHIA 1        SMB_PCIE0_3V3AUX_SDA_R  
                                  2        SMB_PCIE0_3V3AUX_SDA    
R589             Q_RES_0402LF-33.2,1%,1/16W,CHIA 1        SMB_PCIE0_3V3AUX_SCL_R  
                                  2        SMB_PCIE0_3V3AUX_SCL    
R592             Q_RES_0402LF-2.2K ,5%,1/16W,CHA 1        SMB_FAN_3V3AUX_SCL      
                                  2        P3V3_AUX                
R593             Q_RES_0402LF-0,5%,1/16W,CHIP,CA 1        I3C_SPD_DDRABCD_CPU0_BMC_R_SCL
                                  2        I3C_SPD_DDRABCD_CPU0_BMC_SCL
R594             Q_RES_0402LF-0,5%,1/16W,CHIP,CA 1        I3C_SPD_DDRABCD_CPU0_BMC_R_SDA
                                  2        I3C_SPD_DDRABCD_CPU0_BMC_SDA
R595             Q_RES_0402LF-0,5%,1/16W,CHIP,CA 1        I3C_SPD_DDREFGH_CPU0_BMC_R_SCL
                                  2        I3C_SPD_DDREFGH_CPU0_BMC_SCL
R596             Q_RES_0402LF-0,5%,1/16W,CHIP,CA 1        I3C_SPD_DDREFGH_CPU0_BMC_R_SDA
                                  2        I3C_SPD_DDREFGH_CPU0_BMC_SDA
R597             Q_RES_0402LF-0,5%,1/16W,CHIP,CA 1        I3C_SPD_DDRABCD_CPU1_BMC_R_SCL
                                  2        I3C_SPD_DDRABCD_CPU1_BMC_SCL
R598             Q_RES_0402LF-0,5%,1/16W,CHIP,CA 1        I3C_SPD_DDRABCD_CPU1_BMC_R_SDA
                                  2        I3C_SPD_DDRABCD_CPU1_BMC_SDA
R599             Q_RES_0402LF-0,5%,1/16W,CHIP,CA 1        I3C_SPD_DDREFGH_CPU1_BMC_R_SCL
                                  2        I3C_SPD_DDREFGH_CPU1_BMC_SCL
R600             Q_RES_0402LF-0,5%,1/16W,CHIP,CA 1        I3C_SPD_DDREFGH_CPU1_BMC_R_SDA
                                  2        I3C_SPD_DDREFGH_CPU1_BMC_SDA
R601             Q_RES_0402LF-2.2K ,5%,1/16W,CHA 1        SMB_FAN_3V3AUX_SDA      
                                  2        P3V3_AUX                
R606             Q_RES_0402LF-2.2K ,5%,1/16W,CHA 1        SMB_CPU_PIROM_3V3AUX_SCL
                                  2        P3V3_AUX                
R607             Q_RES_0402LF-1K,5%,1/16W,EMPTYA 1        P3V3_AUX                
                                  2        FM_ESPI_FLASH_MODE      
R608             Q_RES_0402LF-10K,1%,1/16W,CHIPA 1        FM_ESPI_FLASH_MODE      
                                  2        GND                     
R609             Q_RES_0402LF-1K,5%,1/16W,EMPTYA 1        P3V3_AUX                
                                  2        FM_ESPI_CS_SWIZZLE      
R610             Q_RES_0402LF-10K,1%,1/16W,CHIPA 1        FM_ESPI_CS_SWIZZLE      
                                  2        GND                     
R611             Q_RES_0402LF-1K,5%,1/16W,CHIP,A 1        P3V3_AUX                
                                  2        FM_PCH_EXTERNALCLKMODE  
R612             Q_RES_0402LF-10K,1%,1/16W,EMPTA 1        FM_PCH_EXTERNALCLKMODE  
                                  2        GND                     
R613             Q_RES_0402LF-10K,1%,1/16W,CHIPA 1        P3V3_AUX                
                                  2        FM_JTAG_ODT_DISABLE     
R614             Q_RES_0402LF-1K,5%,1/16W,EMPTYA 1        FM_JTAG_ODT_DISABLE     
                                  2        GND                     
R615             Q_RES_0402LF-1K,5%,1/16W,CHIP,A 1        P3V3_AUX                
                                  2        FM_PCH_VISA_DEFAULT     
R617             Q_RES_0402LF-1K,5%,1/16W,EMPTYA 1        P3V3_AUX                
                                  2        FM_PCH_IO_EXPANDER      
R618             Q_RES_0402LF-10K,1%,1/16W,CHIPA 1        FM_PCH_IO_EXPANDER      
                                  2        GND                     
R619             Q_RES_0402LF-10K,1%,1/16W,CHIPA 1        P3V3_AUX                
                                  2        FM_LT_KEY_DOWNGRADE_N   
R621             Q_RES_0402LF-1K,5%,1/16W,EMPTYA 1        P3V3_AUX                
                                  2        FM_PCH_SKIP_RTC_CLOCK   
R622             Q_RES_0402LF-1K,5%,1/16W,CHIP,A 1        FM_PCH_SKIP_RTC_CLOCK   
                                  2        GND                     
R623             Q_RES_0402LF-1K,5%,1/16W,EMPTYA 1        P1V8_PCH_AUX            
                                  2        FM_PCH_XTALSEL          
R624             Q_RES_0402LF-10K,1%,1/16W,CHIPA 1        FM_PCH_XTALSEL          
                                  2        GND                     
R625             Q_RES_0402LF-1K,1%,1/16W,EMPTYA 1        P3V3_AUX                
                                  2        PD_PIROM_CPU1_ADDR2     
R626             Q_RES_0402LF-10K,1%,1/16W,CHIPA 1        PD_PIROM_CPU1_ADDR2     
                                  2        GND                     
R627             Q_RES_0402LF-1K,1%,1/16W,EMPTYA 1        P3V3_AUX                
                                  2        PD_PIROM_CPU1_ADDR1     
R628             Q_RES_0402LF-10K,1%,1/16W,CHIPA 1        PD_PIROM_CPU1_ADDR1     
                                  2        GND                     
R629             Q_RES_0402LF-1K,1%,1/16W,CHIP,A 1        P3V3_AUX                
                                  2        PU_PIROM_CPU1_ADDR0     
R630             Q_RES_0402LF-10K,1%,1/16W,EMPTA 1        PU_PIROM_CPU1_ADDR0     
                                  2        GND                     
R631             Q_RES_0402LF-0,5%,1/16W,EMPTY,A 1        IRQ_BMC_PCH_NMI_R       
                                  2        IRQ_BMC_PCH_NMI_R1      
R632             Q_RES_0402LF-0,5%,1/16W,EMPTY,A 2        SMB_HOST_BMC_3V3AUX_SDA 
R633             Q_RES_0402LF-0,5%,1/16W,EMPTY,A 2        SMB_HOST_BMC_3V3AUX_SCL 
R635             Q_RES_0402LF-10K,1%,1/16W,CHIPA 1        PU_OC3_USB_N            
                                  2        P3V3_AUX                
R640             Q_RES_0402LF-4.7K,5%,1/16W,EMPA 1        JTAG_RISER2_TDI         
                                  2        P3V3_AUX                
R641             Q_RES_0402LF-10K,1%,1/16W,EMPTA 1        P3V3_AUX                
                                  2        PCA9546_PCIE1_ADDR2     
R642             Q_RES_0402LF-1K,1%,1/16W,CHIP,A 1        PCA9546_PCIE1_ADDR2     
                                  2        GND                     
R643             Q_RES_0402LF-10K,1%,1/16W,EMPTA 1        P3V3_AUX                
                                  2        PCA9546_PCIE1_ADDR1     
R644             Q_RES_0402LF-1K,1%,1/16W,CHIP,A 1        PCA9546_PCIE1_ADDR1     
                                  2        GND                     
R645             Q_RES_0402LF-10K,1%,1/16W,CHIPA 1        P3V3_AUX                
                                  2        PCA9546_PCIE1_ADDR0     
R646             Q_RES_0402LF-1K,1%,1/16W,EMPTYA 1        PCA9546_PCIE1_ADDR0     
                                  2        GND                     
R647             Q_RES_0402LF-33.2,1%,1/16W,CHIA 1        SMB_PCIE1_3V3AUX_SDA_R  
                                  2        SMB_PCIE1_3V3AUX_SDA    
R648             Q_RES_0402LF-0,5%,1/16W,CHIP,CA 1        SMB_PCIE1_3V3AUX_SCL_R  
                                  2        SMB_PCIE1_3V3AUX_SCL    
R649             Q_RES_0402LF-2.2K ,5%,1/16W,CHA 1        SMB_CPU_PIROM_3V3AUX_SDA
                                  2        P3V3_AUX                
R650             Q_RES_0402LF-1K,1%,1/16W,CHIP,A 1        P3V3_AUX                
                                  2        PU_PIROM_CPU0_SM_WP     
R651             Q_RES_0402LF-2.2K ,5%,1/16W,CHA 1        P3V3_AUX                
                                  2        SMB_RISER2_0_3V3AUX_SCL 
R652             Q_RES_0402LF-2.2K ,5%,1/16W,CHA 1        P3V3_AUX                
                                  2        SMB_RISER2_0_3V3AUX_SDA 
R653             Q_RES_0402LF-2.2K ,5%,1/16W,CHA 1        P3V3_AUX                
                                  2        SMB_RISER2_1_3V3AUX_SCL 
R654             Q_RES_0402LF-2.2K ,5%,1/16W,CHA 1        P3V3_AUX                
                                  2        SMB_RISER2_1_3V3AUX_SDA 
R655             Q_RES_0402LF-2.2K ,5%,1/16W,CHA 1        UNNAMED_222_QRES_I129_A 
                                  2        SMB_RISER3_3V3AUX_SCL   
R656             Q_RES_0402LF-2.2K ,5%,1/16W,CHA 1        UNNAMED_222_QRES_I129_A 
                                  2        SMB_RISER3_3V3AUX_SDA   
R657             Q_RES_0402LF-2.2K ,5%,1/16W,EMA 1        UNNAMED_222_QRES_I129_A 
                                  2        SMB_OCP_SFF_3V3AUX_SCL  
R658             Q_RES_0402LF-2.2K ,5%,1/16W,EMA 1        UNNAMED_222_QRES_I129_A 
                                  2        SMB_OCP_SFF_3V3AUX_SDA  
R659             Q_RES_0402LF-0,5%,1/16W,CHIP,CA 1        SMB_RISER2_0_3V3AUX_SDA 
                                  2        SMB_PCIE0_3V3AUX_SDA_R1 
R660             Q_RES_0402LF-0,5%,1/16W,CHIP,CA 1        SMB_RISER2_0_3V3AUX_SCL 
                                  2        SMB_PCIE0_3V3AUX_SCL_R1 
R661             Q_RES_0402LF-1K,1%,1/16W,CHIP,A 1        PD_I3C_SPD_DDR_CPU1_OE_N
                                  2        GND                     
R662             Q_RES_0402LF-249,1%,1/16W,CHIPA 1        PVNN_TERM_CPU1          
                                  2        I3C_SPD_DDRABCD_CPU1_SCL
R663             Q_RES_0402LF-249,1%,1/16W,CHIPA 1        PVNN_TERM_CPU1          
                                  2        I3C_SPD_DDRABCD_CPU1_SDA
R664             Q_RES_0402LF-249,1%,1/16W,CHIPA 1        PVNN_TERM_CPU1          
                                  2        I3C_SPD_DDREFGH_CPU1_SCL
R665             Q_RES_0402LF-0,5%,1/16W,EMPTY,A 1        I3C_SPD_DDRABCD_CPU1_R_SCL
                                  2        I3C_SPD_DDRABCD_CPU1_LVC1_R_SCL
R666             Q_RES_0402LF-0,5%,1/16W,EMPTY,A 1        I3C_SPD_DDRABCD_CPU1_R_SDA
                                  2        I3C_SPD_DDRABCD_CPU1_LVC1_R_SDA
R667             Q_RES_0402LF-0,5%,1/16W,EMPTY,A 1        I3C_SPD_DDREFGH_CPU1_R_SCL
                                  2        I3C_SPD_DDREFGH_CPU1_LVC1_R_SCL
R668             Q_RES_0402LF-0,5%,1/16W,EMPTY,A 1        I3C_SPD_DDREFGH_CPU1_R_SDA
                                  2        I3C_SPD_DDREFGH_CPU1_LVC1_R_SDA
R669             Q_RES_0402LF-249,1%,1/16W,CHIPA 1        PVNN_TERM_CPU1          
                                  2        I3C_SPD_DDREFGH_CPU1_SDA
R670             Q_RES_0402LF-33.2,1%,1/16W,CHIA 1        I3C_SPD_DDRABCD_CPU1_SCL
                                  2        I3C_SPD_DDRABCD_CPU1_R_SCL
R671             Q_RES_0402LF-33.2,1%,1/16W,CHIA 1        I3C_SPD_DDRABCD_CPU1_SDA
                                  2        I3C_SPD_DDRABCD_CPU1_R_SDA
R672             Q_RES_0402LF-33.2,1%,1/16W,CHIA 1        I3C_SPD_DDREFGH_CPU1_SCL
                                  2        I3C_SPD_DDREFGH_CPU1_R_SCL
R673             Q_RES_0402LF-33.2,1%,1/16W,CHIA 1        I3C_SPD_DDREFGH_CPU1_SDA
                                  2        I3C_SPD_DDREFGH_CPU1_R_SDA
R674             Q_RES_0402LF-0,5%,1/16W,CHIP,CA 1        I3C_SPD_DDRABCD_CPU1_LVC1_R_SCL
                                  2        I3C_SPD_DDRABCD_CPU1_LVC1_SCL
R675             Q_RES_0402LF-0,5%,1/16W,CHIP,CA 1        I3C_SPD_DDRABCD_CPU1_LVC1_R_SDA
                                  2        I3C_SPD_DDRABCD_CPU1_LVC1_SDA
R676             Q_RES_0402LF-0,5%,1/16W,CHIP,CA 1        I3C_SPD_DDREFGH_CPU1_LVC1_R_SCL
                                  2        I3C_SPD_DDREFGH_CPU1_LVC1_SCL
R677             Q_RES_0402LF-0,5%,1/16W,CHIP,CA 1        I3C_SPD_DDREFGH_CPU1_LVC1_R_SDA
                                  2        I3C_SPD_DDREFGH_CPU1_LVC1_SDA
R678             Q_RES_0402LF-1K,1%,1/16W,CHIP,A 1        PD_I3C_SPD_DDR_CPU0_OE_N
                                  2        GND                     
R679             Q_RES_0402LF-249,1%,1/16W,CHIPA 1        PVNN_TERM_CPU0          
                                  2        I3C_SPD_DDRABCD_CPU0_SCL
R680             Q_RES_0402LF-249,1%,1/16W,CHIPA 1        PVNN_TERM_CPU0          
                                  2        I3C_SPD_DDRABCD_CPU0_SDA
R681             Q_RES_0402LF-249,1%,1/16W,CHIPA 1        PVNN_TERM_CPU0          
                                  2        I3C_SPD_DDREFGH_CPU0_SCL
R682             Q_RES_0402LF-0,5%,1/16W,EMPTY,A 1        I3C_SPD_DDRABCD_CPU0_R_SCL
                                  2        I3C_SPD_DDRABCD_CPU0_LVC1_R_SCL
R683             Q_RES_0402LF-0,5%,1/16W,EMPTY,A 1        I3C_SPD_DDRABCD_CPU0_R_SDA
                                  2        I3C_SPD_DDRABCD_CPU0_LVC1_R_SDA
R684             Q_RES_0402LF-0,5%,1/16W,EMPTY,A 1        I3C_SPD_DDREFGH_CPU0_R_SCL
                                  2        I3C_SPD_DDREFGH_CPU0_LVC1_R_SCL
R685             Q_RES_0402LF-0,5%,1/16W,EMPTY,A 1        I3C_SPD_DDREFGH_CPU0_R_SDA
                                  2        I3C_SPD_DDREFGH_CPU0_LVC1_R_SDA
R686             Q_RES_0402LF-249,1%,1/16W,CHIPA 1        PVNN_TERM_CPU0          
                                  2        I3C_SPD_DDREFGH_CPU0_SDA
R687             Q_RES_0402LF-33.2,1%,1/16W,CHIA 1        I3C_SPD_DDRABCD_CPU0_SCL
                                  2        I3C_SPD_DDRABCD_CPU0_R_SCL
R688             Q_RES_0402LF-33.2,1%,1/16W,CHIA 1        I3C_SPD_DDRABCD_CPU0_SDA
                                  2        I3C_SPD_DDRABCD_CPU0_R_SDA
R689             Q_RES_0402LF-33.2,1%,1/16W,CHIA 1        I3C_SPD_DDREFGH_CPU0_SCL
                                  2        I3C_SPD_DDREFGH_CPU0_R_SCL
R690             Q_RES_0402LF-33.2,1%,1/16W,CHIA 1        I3C_SPD_DDREFGH_CPU0_SDA
                                  2        I3C_SPD_DDREFGH_CPU0_R_SDA
R691             Q_RES_0402LF-0,5%,1/16W,CHIP,CA 1        I3C_SPD_DDRABCD_CPU0_LVC1_R_SCL
                                  2        I3C_SPD_DDRABCD_CPU0_LVC1_SCL
R692             Q_RES_0402LF-0,5%,1/16W,CHIP,CA 1        I3C_SPD_DDRABCD_CPU0_LVC1_R_SDA
                                  2        I3C_SPD_DDRABCD_CPU0_LVC1_SDA
R693             Q_RES_0402LF-0,5%,1/16W,CHIP,CA 1        I3C_SPD_DDREFGH_CPU0_LVC1_R_SCL
                                  2        I3C_SPD_DDREFGH_CPU0_LVC1_SCL
R694             Q_RES_0402LF-0,5%,1/16W,CHIP,CA 1        I3C_SPD_DDREFGH_CPU0_LVC1_R_SDA
                                  2        I3C_SPD_DDREFGH_CPU0_LVC1_SDA
R696             Q_RES_0402LF-4.75K,1%,1/16W,CHA 1        P3V3_AUX                
                                  2        RST_PCH_RSTBTN_R_N      
R697             Q_RES_0402LF-33,5%,1/16W,CHIP,A 1        FM_BMC_RSTBTN_OUT_N     
                                  2        RST_PCH_RSTBTN_R_N      
R698             Q_RES_0402LF-49.9     ,1%  ,1/A 1        FM_ADR_TRIGGER_R_N      
                                  2        FM_ADR_TRIGGER_N        
R699             Q_RES_0402LF-33,5%,1/16W,CHIP,A 1        FM_PCH_CRASHLOG_TRIG_R_N
                                  2        FM_PCH_CRASHLOG_TRIG_N  
R700             Q_RES_0402LF-0,5%,1/16W,CHIP,CA 1        FM_ADR_ACK_R            
                                  2        FM_ADR_ACK              
R701             Q_RES_0402LF-10K,1%,1/16W,EMPTA 1        RST_PLD_CPU1_DRAM_CD_N  
                                  2        GND                     
R702             Q_RES_0402LF-10K,1%,1/16W,EMPTA 1        RST_PLD_CPU1_DRAM_GH_N  
                                  2        GND                     
R703             Q_RES_0402LF-10K,1%,1/16W,EMPTA 1        RST_PLD_CPU1_DRAM_AB_N  
                                  2        GND                     
R704             Q_RES_0402LF-10K,1%,1/16W,EMPTA 1        RST_PLD_CPU1_DRAM_EF_N  
                                  2        GND                     
R705             Q_RES_0402LF-10K,1%,1/16W,EMPTA 1        RST_PLD_CPU0_DRAM_GH_N  
                                  2        GND                     
R706             Q_RES_0402LF-10K,1%,1/16W,EMPTA 1        RST_PLD_CPU0_DRAM_AB_N  
                                  2        GND                     
R707             Q_RES_0402LF-10K,1%,1/16W,EMPTA 1        RST_PLD_CPU0_DRAM_CD_N  
                                  2        GND                     
R708             Q_RES_0402LF-10K,1%,1/16W,EMPTA 1        RST_PLD_CPU0_DRAM_EF_N  
                                  2        GND                     
R709             Q_RES_0402LF-33.2,1%,1/16W,CHIA 1        SMB_SENSOR_3V3AUX_SDA   
                                  2        SMB_FRU_3V3AUX_SDA_R    
R710             Q_RES_0402LF-1K,1%,1/16W,CHIP,A 1        PD_MB_FRU_WP            
                                  2        GND                     
R711             Q_RES_0402LF-10K,1%,1/16W,EMPTA 1        P3V3_AUX                
                                  2        TMP75_1_ADDR2           
R712             Q_RES_0402LF-1K,1%,1/16W,CHIP,A 1        TMP75_1_ADDR2           
                                  2        GND                     
R713             Q_RES_0402LF-10K,1%,1/16W,EMPTA 1        P3V3_AUX                
                                  2        MB_FRU_ADDR2            
R714             Q_RES_0402LF-1K,1%,1/16W,CHIP,A 1        MB_FRU_ADDR2            
                                  2        GND                     
R715             Q_RES_0402LF-10K,1%,1/16W,EMPTA 1        P3V3_AUX                
                                  2        TMP75_1_ADDR1           
R716             Q_RES_0402LF-1K,1%,1/16W,CHIP,A 1        TMP75_1_ADDR1           
                                  2        GND                     
R717             Q_RES_0402LF-10K,1%,1/16W,EMPTA 1        P3V3_AUX                
                                  2        MB_FRU_ADDR1            
R718             Q_RES_0402LF-1K,1%,1/16W,CHIP,A 1        MB_FRU_ADDR1            
                                  2        GND                     
R719             Q_RES_0402LF-10K,1%,1/16W,CHIPA 1        P3V3_AUX                
                                  2        TMP75_1_ADDR0           
R720             Q_RES_0402LF-1K,1%,1/16W,EMPTYA 1        TMP75_1_ADDR0           
                                  2        GND                     
R721             Q_RES_0402LF-10K,1%,1/16W,CHIPA 1        P3V3_AUX                
                                  2        MB_FRU_ADDR0            
R722             Q_RES_0402LF-1K,1%,1/16W,EMPTYA 1        MB_FRU_ADDR0            
                                  2        GND                     
R723             Q_RES_0402LF-33,5%,1/16W,CHIP,A 1        SMB_FAN_3V3AUX_SCL_R1   
                                  2        SMB_FAN_3V3AUX_SCL      
R724             Q_RES_0402LF-33,5%,1/16W,CHIP,A 1        SMB_FAN_3V3AUX_SDA_R1   
                                  2        SMB_FAN_3V3AUX_SDA      
R725             Q_RES_0402LF-33.2,1%,1/16W,CHIA 1        SMB_SENSOR_3V3AUX_SDA   
                                  2        SMB_TMP75_2_3V3AUX_SDA_R
R726             Q_RES_0402LF-33.2,1%,1/16W,CHIA 1        SMB_SENSOR_3V3AUX_SCL   
                                  2        SMB_TMP75_2_3V3AUX_SCL_R
R727             Q_RES_0402LF-10K,1%,1/16W,CHIPA 1        PU_OC4_USB_N            
                                  2        P3V3_AUX                
R728             Q_RES_0402LF-10K,1%,1/16W,EMPTA 1        P3V3_AUX                
                                  2        TMP75_2_ADDR2           
R729             Q_RES_0402LF-1K,1%,1/16W,CHIP,A 1        TMP75_2_ADDR2           
                                  2        GND                     
R730             Q_RES_0402LF-10K,1%,1/16W,CHIPA 1        P3V3_AUX                
                                  2        TMP75_2_ADDR1           
R731             Q_RES_0402LF-1K,1%,1/16W,EMPTYA 1        TMP75_2_ADDR1           
                                  2        GND                     
R732             Q_RES_0402LF-10K,1%,1/16W,EMPTA 1        P3V3_AUX                
                                  2        TMP75_2_ADDR0           
R733             Q_RES_0402LF-1K,1%,1/16W,CHIP,A 1        TMP75_2_ADDR0           
                                  2        GND                     
R734             Q_RES_0402LF-4.75K,1%,1/16W,CHA 1        CLK_CK440_SMB_ADDR1     
                                  2        GND                     
R735             Q_RES_0402LF-10K,1%,1/16W,CHIPA 1        P3V3_AUX                
                                  2        FM_DIMM_12V_CPS_SX_N    
R736             Q_RES_0402LF-1K,1%,1/16W,EMPTYA 1        FM_DIMM_12V_CPS_SX_N    
                                  2        GND                     
R737             Q_RES_0402LF-0,5%,1/16W,CHIP,CA 1        FM_CPU1_SKTOCC_LVT3_N   
                                  2        FM_CPU1_SKTOCC_N        
R738             Q_RES_0402LF-0,5%,1/16W,CHIP,CA 1        FM_CPU0_SKTOCC_LVT3_N   
                                  2        FM_CPU0_SKTOCC_N        
R739             Q_RES_0402LF-10K,1%,1/16W,CHIPA 1        P3V3_AUX                
                                  2        FM_CPU1_SKTOCC_N        
R740             Q_RES_0402LF-10K,1%,1/16W,CHIPA 1        P3V3_AUX                
                                  2        FM_CPU0_SKTOCC_N        
R741             Q_RES_0402LF-150,1%,1/16W,CHIPA 1        PVNN_TERM_CPU0          
                                  2        JTAG_MUX_CPU0_GTL_TDI   
R742             Q_RES_0402LF-75,1%,1/16W,CHIP,A 1        PVNN_TERM_CPU1          
                                  2        JTAG_CPU1_MUX_GTL_TDO   
R743             Q_RES_0402LF-150,1%,1/16W,CHIPA 1        PVNN_TERM_CPU1          
                                  2        JTAG_MUX_CPU1_GTL_TDI   
R744             Q_RES_0402LF-75,1%,1/16W,CHIP,A 1        PVNN_TERM_CPU0          
                                  2        JTAG_CPU0_MUX_GTL_TDO   
R745             Q_RES_0402LF-33,5%,1/16W,CHIP,A 1        FM_CPU_EN               
                                  2        FM_CPU_EN_R             
R746             Q_RES_0402LF-0,5%,1/16W,CHIP,CA 1        PD_74CB_A9              
                                  2        GND                     
R747             Q_RES_0402LF-150,1%,1/16W,CHIPA 1        P1V05_PCH_AUX           
                                  2        JTAG_DBP_TDO_PCH        
R748             Q_RES_0402LF-75,1%,1/16W,CHIP,A 1        P1V05_PCH_AUX           
                                  2        JTAG_DBP_TDI_PCH        
R749             Q_RES_0402LF-75,1%,1/16W,CHIP,A 1        P1V05_PCH_AUX           
                                  2        JTAG_DBP_TMS_PCH        
R750             Q_RES_0402LF-150,1%,1/16W,CHIPA 1        P1V05_PCH_AUX           
                                  2        H_DBP_PREQ_N_PCH        
R751             Q_RES_0402LF-150,1%,1/16W,CHIPA 1        P1V05_PCH_AUX           
                                  2        H_DBP_PRDY_N_PCH        
R752             Q_RES_0402LF-10,1%,1/16W,CHIP,A 1        JTAG_DBP_TDO            
                                  2        JTAG_DBP_TDO_PCH        
R753             Q_RES_0402LF-10,1%,1/16W,CHIP,A 1        JTAG_DBP_TDI            
                                  2        JTAG_DBP_TDI_PCH        
R754             Q_RES_0402LF-10,1%,1/16W,CHIP,A 1        JTAG_DBP_TMS            
                                  2        JTAG_DBP_TMS_PCH        
R755             Q_RES_0402LF-10,1%,1/16W,CHIP,A 1        JTAG_DBP_PREQ_N         
                                  2        H_DBP_PREQ_N_PCH        
R756             Q_RES_0402LF-10,1%,1/16W,CHIP,A 1        JTAG_DBP_PRDY_N         
                                  2        H_DBP_PRDY_N_PCH        
R757             Q_RES_0402LF-120,1%,1/16W,CHIPA 1        PVNN_TERM_CPU0          
                                  2        JTAG_DBP_CPU_QS_GTL_TMS 
R758             Q_RES_0402LF-150,1%,1/16W,CHIPA 1        PVNN_TERM_CPU0          
                                  2        H_CPU_PREQ_QS_GTL_N     
R759             Q_RES_0402LF-150,1%,1/16W,CHIPA 1        PVNN_TERM_CPU0          
                                  2        H_CPU_PRDY_QS_GTL_N     
R760             Q_RES_0402LF-499,1%,1/16W,CHIPA 1        PVNN_TERM_CPU0          
                                  2        DBP_CPU_HOOK8_MBP2_GTL_QS_N
R761             Q_RES_0402LF-499,1%,1/16W,CHIPA 1        PVNN_TERM_CPU0          
                                  2        DBP_CPU_HOOK9_MBP3_GTL_QS_N
R762             Q_RES_0402LF-0,5%,1/16W,CHIP,CA 1        JTAG_DBP_CPU_GTL_TCK    
                                  2        JTAG_DBP_CPU_GTL_TCK_R  
R763             Q_RES_0402LF-10,1%,1/16W,CHIP,A 1        JTAG_DBP_TDI            
                                  2        JTAG_DBP_TDI_R          
R764             Q_RES_0402LF-0,5%,1/16W,CHIP,CA 1        JTAG_DBP_PRDY_N         
                                  2        JTAG_DBP_PRDY_R1_N      
R765             Q_RES_0402LF-0,5%,1/16W,CHIP,CA 1        JTAG_DBP_TCK_PCH        
                                  2        JTAG_DBP_TCK_R_TCK      
R766             Q_RES_0402LF-1K,1%,1/16W,EMPTYA 1        P3V3_AUX                
                                  2        JTAG_DBP_POWER_BTN_N    
R767             Q_RES_0402LF-1K,1%,1/16W,CHIP,A 1        P3V3_AUX                
                                  2        JTAG_RST_DBP_RST_CO_N   
R768             Q_RES_0402LF-1K,1%,1/16W,CHIP,A 1        P3V3_AUX                
                                  2        JTAG_DBP_PRESENT_R_N    
R769             Q_RES_0402LF-10K,1%,1/16W,CHIPA 1        PD_TRST_P3              
                                  2        GND                     
R770             Q_RES_0402LF-10K,1%,1/16W,CHIPA 1        PU_OC5_USB_N            
                                  2        P3V3_AUX                
R771             Q_RES_0402LF-1K,1%,1/16W,CHIP,A 1        JTAG_DBP_PCH_DEBUG_CONSENT_N
                                  2        FM_PCH_CONSENT_STRAP_N  
R772             Q_RES_0402LF-1K,1%,1/16W,CHIP,A 1        JTAG_RST_DBP_RSMRST_N   
                                  2        RST_RSMRST_PCH_N        
R773             Q_RES_0402LF-1K,1%,1/16W,CHIP,A 1        JTAG_DBP_BOOT_HALT_N    
                                  2        FM_ADR_MODE0            
R774             Q_RES_0402LF-75,1%,1/16W,CHIP,A 1        JTAG_DBP_CPU_GTL_TCK    
                                  2        GND                     
R775             Q_RES_0402LF-10,1%,1/16W,CHIP,A 1        JTAG_DBP_TMS_R          
                                  2        JTAG_DBP_TMS            
R776             Q_RES_0402LF-100,1%,1/16W,CHIPA 1        JTAG_DBP_TDO_R          
                                  2        JTAG_DBP_TDO            
R777             Q_RES_0402LF-10,1%,1/16W,CHIP,A 1        JTAG_DBP_PREQ_N_R       
                                  2        JTAG_DBP_PREQ_N         
R778             Q_RES_0402LF-1K,1%,1/16W,CHIP,A 1        P3V3_AUX                
                                  2        JTAG_DBP_BOOT_HALT_N    
R779             Q_RES_0402LF-150,5%,1/16W,CHIPA 1        PVNN_TERM_CPU0          
                                  2        FM_CPU_FBRK_DEBUG_N     
R780             Q_RES_0402LF-49.9     ,1%  ,1/A 1        FM_CPU_FBRK_DEBUG_N     
                                  2        FM_CPU_FBRK_DEBUG_R_N   
R781             Q_RES_0402LF-10K,1%,1/16W,EMPTA 1        P3V3_AUX                
                                  2        PCA9548_PCIE2_ADDR2     
R782             Q_RES_0402LF-1K,1%,1/16W,CHIP,A 1        PCA9548_PCIE2_ADDR2     
                                  2        GND                     
R783             Q_RES_0402LF-10K,1%,1/16W,CHIPA 1        P3V3_AUX                
                                  2        PCA9548_PCIE2_ADDR1     
R784             Q_RES_0402LF-1K,1%,1/16W,EMPTYA 1        PCA9548_PCIE2_ADDR1     
                                  2        GND                     
R785             Q_RES_0402LF-10K,1%,1/16W,EMPTA 1        P3V3_AUX                
                                  2        PCA9548_PCIE2_ADDR0     
R786             Q_RES_0402LF-1K,1%,1/16W,CHIP,A 1        PCA9548_PCIE2_ADDR0     
                                  2        GND                     
R787             Q_RES_0402LF-0,5%,1/16W,CHIP,CA 1        SMB_EDSFF1A_3V3AUX_SCL_R1
                                  2        SMB_EDSFF1A_3V3AUX_SCL_R
R788             Q_RES_0402LF-0,5%,1/16W,CHIP,CA 1        SMB_EDSFF1A_3V3AUX_SDA_R1
                                  2        SMB_EDSFF1A_3V3AUX_SDA_R
R789             Q_RES_0402LF-0,5%,1/16W,CHIP,CA 1        SMB_EDSFF2A_3V3AUX_SCL_R1
                                  2        SMB_EDSFF2A_3V3AUX_SCL_R
R790             Q_RES_0402LF-0,5%,1/16W,CHIP,CA 1        SMB_EDSFF2A_3V3AUX_SDA_R1
                                  2        SMB_EDSFF2A_3V3AUX_SDA_R
R791             Q_RES_0402LF-2.2K ,5%,1/16W,CHA 1        P3V3_AUX                
                                  2        SMB_EDSFF1A_3V3AUX_SCL_R
R792             Q_RES_0402LF-2.2K ,5%,1/16W,CHA 1        P3V3_AUX                
                                  2        SMB_EDSFF1A_3V3AUX_SDA_R
R793             Q_RES_0402LF-2.2K ,5%,1/16W,CHA 1        P3V3_AUX                
                                  2        SMB_EDSFF2A_3V3AUX_SCL_R
R794             Q_RES_0402LF-2.2K ,5%,1/16W,CHA 1        P3V3_AUX                
                                  2        SMB_EDSFF2A_3V3AUX_SDA_R
R795             Q_RES_0402LF-2.2K ,5%,1/16W,CHA 1        P3V3_AUX                
                                  2        SMB_EDSFF3_3V3AUX_SCL_R 
R796             Q_RES_0402LF-2.2K ,5%,1/16W,CHA 1        P3V3_AUX                
                                  2        SMB_EDSFF3_3V3AUX_SDA_R 
R797             Q_RES_0402LF-2.2K ,5%,1/16W,CHA 1        P3V3_AUX                
                                  2        SMB_EDSFF4A_3V3AUX_SCL_R
R798             Q_RES_0402LF-2.2K ,5%,1/16W,CHA 1        P3V3_AUX                
                                  2        SMB_EDSFF4A_3V3AUX_SDA_R
R799             Q_RES_0402LF-0,5%,1/16W,CHIP,CA 1        SMB_EDSFF4A_3V3AUX_SCL_R1
                                  2        SMB_EDSFF4A_3V3AUX_SCL_R
R800             Q_RES_0402LF-0,5%,1/16W,CHIP,CA 1        SMB_EDSFF4A_3V3AUX_SDA_R1
                                  2        SMB_EDSFF4A_3V3AUX_SDA_R
R801             Q_RES_0402LF-0,5%,1/16W,CHIP,CA 1        SMB_EDSFF3_3V3AUX_SCL_R1
                                  2        SMB_EDSFF3_3V3AUX_SCL_R 
R802             Q_RES_0402LF-0,5%,1/16W,CHIP,CA 1        SMB_EDSFF3_3V3AUX_SDA_R1
                                  2        SMB_EDSFF3_3V3AUX_SDA_R 
R803             Q_RES_0402LF-33,5%,1/16W,CHIP,A 1        JTAG_PLD_TDI_R          
                                  2        JTAG_BMC_PLD_TDI        
R804             Q_RES_0402LF-33,5%,1/16W,CHIP,A 1        JTAG_PLD_TDO_R          
                                  2        JTAG_BMC_PLD_TDO        
R805             Q_RES_0402LF-33,5%,1/16W,CHIP,A 1        JTAG_PLD_TMS_R          
                                  2        JTAG_BMC_PLD_TMS        
R806             Q_RES_0402LF-33,5%,1/16W,CHIP,A 1        JTAG_PLD_TCK_R          
                                  2        JTAG_BMC_PLD_TCK        
R815             Q_RES_0402LF-0,5%,1/16W,CHIP,CA 1        RST_PLD_CPU1_DRAM_GH_N  
                                  2        RST_M_GH_CPU1_FPGA_N    
R816             Q_RES_0402LF-0,5%,1/16W,CHIP,CA 1        RST_PLD_CPU1_DRAM_AB_N  
                                  2        RST_M_AB_CPU1_FPGA_N    
R817             Q_RES_0402LF-0,5%,1/16W,CHIP,CA 1        RST_PLD_CPU1_DRAM_CD_N  
                                  2        RST_M_CD_CPU1_FPGA_N    
R818             Q_RES_0402LF-0,5%,1/16W,CHIP,CA 1        RST_PLD_CPU1_DRAM_EF_N  
                                  2        RST_M_EF_CPU1_FPGA_N    
R819             Q_RES_0402LF-1K,1%,1/16W,EMPTYA 1        PVCCD_HV_CPU1           
                                  2        RST_M_GH_CPU1_FPGA_N    
R820             Q_RES_0402LF-1K,1%,1/16W,EMPTYA 1        PVCCD_HV_CPU1           
                                  2        RST_M_AB_CPU1_FPGA_N    
R821             Q_RES_0402LF-1K,1%,1/16W,EMPTYA 1        PVCCD_HV_CPU1           
                                  2        RST_M_CD_CPU1_FPGA_N    
R822             Q_RES_0402LF-1K,1%,1/16W,EMPTYA 1        PVCCD_HV_CPU1           
                                  2        RST_M_EF_CPU1_FPGA_N    
R835             Q_RES_0402LF-0,5%,1/16W,CHIP,CA 1        RST_PLD_CPU0_DRAM_GH_N  
                                  2        RST_M_GH_CPU0_FPGA_N    
R836             Q_RES_0402LF-0,5%,1/16W,CHIP,CA 1        RST_PLD_CPU0_DRAM_AB_N  
                                  2        RST_M_AB_CPU0_FPGA_N    
R837             Q_RES_0402LF-0,5%,1/16W,CHIP,CA 1        RST_PLD_CPU0_DRAM_CD_N  
                                  2        RST_M_CD_CPU0_FPGA_N    
R838             Q_RES_0402LF-0,5%,1/16W,CHIP,CA 1        RST_PLD_CPU0_DRAM_EF_N  
                                  2        RST_M_EF_CPU0_FPGA_N    
R839             Q_RES_0402LF-1K,1%,1/16W,EMPTYA 1        PVCCD_HV_CPU0           
                                  2        RST_M_GH_CPU0_FPGA_N    
R840             Q_RES_0402LF-1K,1%,1/16W,EMPTYA 1        PVCCD_HV_CPU0           
                                  2        RST_M_AB_CPU0_FPGA_N    
R841             Q_RES_0402LF-1K,1%,1/16W,EMPTYA 1        PVCCD_HV_CPU0           
                                  2        RST_M_CD_CPU0_FPGA_N    
R842             Q_RES_0402LF-1K,1%,1/16W,EMPTYA 1        PVCCD_HV_CPU0           
                                  2        RST_M_EF_CPU0_FPGA_N    
R851             Q_RES_0402LF-0,5%,1/16W,CHIP,CA 1        RST_CPU0_DRAM_AB_N      
                                  2        RST_CPU0_DRAM_AB_PLD_N  
R852             Q_RES_0402LF-0,5%,1/16W,CHIP,CA 1        RST_CPU0_DRAM_CD_N      
                                  2        RST_CPU0_DRAM_CD_PLD_N  
R853             Q_RES_0402LF-0,5%,1/16W,CHIP,CA 1        RST_CPU0_DRAM_EF_N      
                                  2        RST_CPU0_DRAM_EF_PLD_N  
R854             Q_RES_0402LF-0,5%,1/16W,CHIP,CA 1        RST_CPU0_DRAM_GH_N      
                                  2        RST_CPU0_DRAM_GH_PLD_N  
R859             Q_RES_0402LF-0,5%,1/16W,CHIP,CA 1        RST_CPU1_DRAM_AB_N      
                                  2        RST_CPU1_DRAM_AB_PLD_N  
R860             Q_RES_0402LF-0,5%,1/16W,CHIP,CA 1        RST_CPU1_DRAM_CD_N      
                                  2        RST_CPU1_DRAM_CD_PLD_N  
R861             Q_RES_0402LF-0,5%,1/16W,CHIP,CA 1        RST_CPU1_DRAM_EF_N      
                                  2        RST_CPU1_DRAM_EF_PLD_N  
R862             Q_RES_0402LF-0,5%,1/16W,CHIP,CA 1        RST_CPU1_DRAM_GH_N      
                                  2        RST_CPU1_DRAM_GH_PLD_N  
R877             Q_RES_0402LF-33,5%,1/16W,CHIP,A 1        PWRGD_CHA_CPU0_DIMM1    
                                  2        PWRGD_FAIL_CPU0_AB      
R878             Q_RES_0402LF-33,5%,1/16W,CHIP,A 1        PWRGD_CHA_CPU0_DIMM2    
                                  2        PWRGD_FAIL_CPU0_AB      
R879             Q_RES_0402LF-33,5%,1/16W,CHIP,A 1        PWRGD_CHB_CPU0_DIMM1    
                                  2        PWRGD_FAIL_CPU0_AB      
R880             Q_RES_0402LF-33,5%,1/16W,CHIP,A 1        PWRGD_CHB_CPU0_DIMM2    
                                  2        PWRGD_FAIL_CPU0_AB      
R881             Q_RES_0402LF-33,5%,1/16W,CHIP,A 1        PWRGD_CHC_CPU0_DIMM1    
                                  2        PWRGD_FAIL_CPU0_CD      
R882             Q_RES_0402LF-33,5%,1/16W,CHIP,A 1        PWRGD_CHC_CPU0_DIMM2    
                                  2        PWRGD_FAIL_CPU0_CD      
R883             Q_RES_0402LF-33,5%,1/16W,CHIP,A 1        PWRGD_CHD_CPU0_DIMM1    
                                  2        PWRGD_FAIL_CPU0_CD      
R884             Q_RES_0402LF-33,5%,1/16W,CHIP,A 1        PWRGD_CHD_CPU0_DIMM2    
                                  2        PWRGD_FAIL_CPU0_CD      
R885             Q_RES_0402LF-33,5%,1/16W,CHIP,A 1        PWRGD_CHE_CPU0_DIMM1    
                                  2        PWRGD_FAIL_CPU0_EF      
R886             Q_RES_0402LF-33,5%,1/16W,CHIP,A 1        PWRGD_CHE_CPU0_DIMM2    
                                  2        PWRGD_FAIL_CPU0_EF      
R887             Q_RES_0402LF-33,5%,1/16W,CHIP,A 1        PWRGD_CHF_CPU0_DIMM1    
                                  2        PWRGD_FAIL_CPU0_EF      
R888             Q_RES_0402LF-33,5%,1/16W,CHIP,A 1        PWRGD_CHF_CPU0_DIMM2    
                                  2        PWRGD_FAIL_CPU0_EF      
R889             Q_RES_0402LF-33,5%,1/16W,CHIP,A 1        PWRGD_CHG_CPU0_DIMM1    
                                  2        PWRGD_FAIL_CPU0_GH      
R890             Q_RES_0402LF-33,5%,1/16W,CHIP,A 1        PWRGD_CHG_CPU0_DIMM2    
                                  2        PWRGD_FAIL_CPU0_GH      
R891             Q_RES_0402LF-33,5%,1/16W,CHIP,A 1        PWRGD_CHH_CPU0_DIMM1    
                                  2        PWRGD_FAIL_CPU0_GH      
R892             Q_RES_0402LF-33,5%,1/16W,CHIP,A 1        PWRGD_CHH_CPU0_DIMM2    
                                  2        PWRGD_FAIL_CPU0_GH      
R893             Q_RES_0402LF-33,5%,1/16W,CHIP,A 1        PWRGD_CHA_CPU1_DIMM1    
                                  2        PWRGD_FAIL_CPU1_AB      
R894             Q_RES_0402LF-33,5%,1/16W,CHIP,A 1        PWRGD_CHA_CPU1_DIMM2    
                                  2        PWRGD_FAIL_CPU1_AB      
R895             Q_RES_0402LF-33,5%,1/16W,CHIP,A 1        PWRGD_CHB_CPU1_DIMM1    
                                  2        PWRGD_FAIL_CPU1_AB      
R896             Q_RES_0402LF-33,5%,1/16W,CHIP,A 1        PWRGD_CHB_CPU1_DIMM2    
                                  2        PWRGD_FAIL_CPU1_AB      
R897             Q_RES_0402LF-33,5%,1/16W,CHIP,A 1        PWRGD_CHC_CPU1_DIMM1    
                                  2        PWRGD_FAIL_CPU1_CD      
R898             Q_RES_0402LF-33,5%,1/16W,CHIP,A 1        PWRGD_CHC_CPU1_DIMM2    
                                  2        PWRGD_FAIL_CPU1_CD      
R899             Q_RES_0402LF-33,5%,1/16W,CHIP,A 1        PWRGD_CHD_CPU1_DIMM1    
                                  2        PWRGD_FAIL_CPU1_CD      
R900             Q_RES_0402LF-33,5%,1/16W,CHIP,A 1        PWRGD_CHD_CPU1_DIMM2    
                                  2        PWRGD_FAIL_CPU1_CD      
R901             Q_RES_0402LF-33,5%,1/16W,CHIP,A 1        PWRGD_CHE_CPU1_DIMM1    
                                  2        PWRGD_FAIL_CPU1_EF      
R902             Q_RES_0402LF-33,5%,1/16W,CHIP,A 1        PWRGD_CHE_CPU1_DIMM2    
                                  2        PWRGD_FAIL_CPU1_EF      
R903             Q_RES_0402LF-33,5%,1/16W,CHIP,A 1        PWRGD_CHF_CPU1_DIMM1    
                                  2        PWRGD_FAIL_CPU1_EF      
R904             Q_RES_0402LF-33,5%,1/16W,CHIP,A 1        PWRGD_CHF_CPU1_DIMM2    
                                  2        PWRGD_FAIL_CPU1_EF      
R905             Q_RES_0402LF-33,5%,1/16W,CHIP,A 1        PWRGD_CHG_CPU1_DIMM1    
                                  2        PWRGD_FAIL_CPU1_GH      
R906             Q_RES_0402LF-33,5%,1/16W,CHIP,A 1        PWRGD_CHG_CPU1_DIMM2    
                                  2        PWRGD_FAIL_CPU1_GH      
R907             Q_RES_0402LF-33,5%,1/16W,CHIP,A 1        PWRGD_CHH_CPU1_DIMM1    
                                  2        PWRGD_FAIL_CPU1_GH      
R908             Q_RES_0402LF-33,5%,1/16W,CHIP,A 1        PWRGD_CHH_CPU1_DIMM2    
                                  2        PWRGD_FAIL_CPU1_GH      
R909             Q_RES_0402LF-33.2,1%,1/16W,CHIA 1        SMB_PEHPCPU0_GTL_SDA    
                                  2        SMB_PEHPCPU0_GTL_R_SDA  
R910             Q_RES_0402LF-240,1%,1/16W,CHIPA 1        PVNN_TERM_CPU0          
                                  2        SMB_PEHPCPU0_GTL_R_SCL  
R911             Q_RES_0402LF-240,1%,1/16W,CHIPA 1        PVNN_TERM_CPU0          
                                  2        SMB_PEHPCPU0_GTL_R_SDA  
R912             Q_RES_0402LF-4.75K,1%,1/16W,EMA 1        P3V3_AUX                
                                  2        CLK_CK440_SMB_ADDR0     
R913             Q_RES_0402LF-10K,1%,1/16W,CHIPA 1        PU_OC6_USB_N            
                                  2        P3V3_AUX                
R914             Q_RES_0402LF-2.2K ,5%,1/16W,CHA 1        P3V3_AUX                
                                  2        SMB_PCIE1_3V3AUX_SCL    
R915             Q_RES_0402LF-33.2,1%,1/16W,CHIA 1        SPI_PCH_IO0             
                                  2        SPI_SYS_MOSI            
R916             Q_RES_0402LF-33.2,1%,1/16W,CHIA 1        SPI_PCH_IO1             
                                  2        SPI_SYS_MISO            
R917             Q_RES_0402LF-33.2,1%,1/16W,CHIA 1        SPI_PCH_IO3             
                                  2        SPI_SYS_HOLD_IO3        
R918             Q_RES_0402LF-33.2,1%,1/16W,CHIA 1        SPI_PCH_IO2             
                                  2        SPI_SYS_WP_IO2          
R919             Q_RES_0402LF-10K,1%,1/16W,CHIPA 1        P3V3_AUX                
                                  2        JTAG_PLD_JTAGEN         
R920             Q_RES_0402LF-1K,5%,1/16W,EMPTYA 1        JTAG_PLD_JTAGEN         
                                  2        GND                     
R923             Q_RES_0402LF-33.2,1%,1/16W,CHIA 1        OCP_SFF_AUX_PWR_EN      
                                  2        OCP_SFF_AUX_PWR_EN_R2   
R927             Q_RES_0402LF-10K,1%,1/16W,CHIPA 1        P3V3_AUX                
                                  2        JTAG_BMC_PLD_TDI        
R928             Q_RES_0402LF-10K,1%,1/16W,CHIPA 1        P3V3_AUX                
                                  2        JTAG_BMC_PLD_TDO        
R929             Q_RES_0402LF-10K,1%,1/16W,CHIPA 1        P3V3_AUX                
                                  2        JTAG_BMC_PLD_TMS        
R930             Q_RES_0402LF-4.7K,1%,1/16W,CHIA 1        JTAG_BMC_PLD_TCK        
                                  2        GND                     
R931             Q_RES_0402LF-0,5%,1/16W,CHIP,CA 1        JTAG_PLD_JTAGEN         
                                  2        JTAG_PLD_JTAGEN_R       
R932             Q_RES_0402LF-10K,1%,1/16W,CHIPA 1        RST_CPU0_DRAM_AB_N      
                                  2        GND                     
R933             Q_RES_0402LF-10K,1%,1/16W,CHIPA 1        RST_CPU1_DRAM_AB_N      
                                  2        GND                     
R934             Q_RES_0402LF-10K,1%,1/16W,CHIPA 1        RST_CPU0_DRAM_CD_N      
                                  2        GND                     
R935             Q_RES_0402LF-10K,1%,1/16W,CHIPA 1        RST_CPU1_DRAM_CD_N      
                                  2        GND                     
R936             Q_RES_0402LF-10K,1%,1/16W,CHIPA 1        RST_CPU0_DRAM_EF_N      
                                  2        GND                     
R937             Q_RES_0402LF-10K,1%,1/16W,CHIPA 1        RST_CPU1_DRAM_EF_N      
                                  2        GND                     
R938             Q_RES_0402LF-10K,1%,1/16W,CHIPA 1        RST_CPU0_DRAM_GH_N      
                                  2        GND                     
R939             Q_RES_0402LF-10K,1%,1/16W,CHIPA 1        RST_CPU1_DRAM_GH_N      
                                  2        GND                     
R940             Q_RES_0402LF-1K,1%,1/16W,CHIP,A 1        P3V3_AUX                
                                  2        PWRGD_FAIL_CPU0_AB      
R941             Q_RES_0402LF-1K,1%,1/16W,CHIP,A 1        P3V3_AUX                
                                  2        PWRGD_FAIL_CPU0_CD      
R942             Q_RES_0402LF-1K,1%,1/16W,CHIP,A 1        P3V3_AUX                
                                  2        PWRGD_FAIL_CPU0_EF      
R943             Q_RES_0402LF-1K,1%,1/16W,CHIP,A 1        P3V3_AUX                
                                  2        PWRGD_FAIL_CPU0_GH      
R944             Q_RES_0402LF-1K,1%,1/16W,CHIP,A 1        P3V3_AUX                
                                  2        PWRGD_FAIL_CPU1_AB      
R945             Q_RES_0402LF-1K,1%,1/16W,CHIP,A 1        P3V3_AUX                
                                  2        PWRGD_FAIL_CPU1_CD      
R946             Q_RES_0402LF-1K,1%,1/16W,CHIP,A 1        P3V3_AUX                
                                  2        PWRGD_FAIL_CPU1_EF      
R947             Q_RES_0402LF-1K,1%,1/16W,CHIP,A 1        P3V3_AUX                
                                  2        PWRGD_FAIL_CPU1_GH      
R948             Q_RES_0402LF-0,5%,1/16W,CHIP,CA 1        IRQ_PDB_R_N             
                                  2        FM_UV_ADR_TRIGGER_N     
R951             Q_RES_0402LF-0,5%,1/16W,CHIP,CA 1        IRQ_SML1_PMBUS_ALERT_N  
                                  2        IRQ_SML1_PMBUS_ALERT_R_N
R952             Q_RES_0402LF-4.7K,1%,1/16W,EMPA 1        P3V3_AUX                
                                  2        IRQ_PDB_R_N             
R953             Q_RES_0402LF-4.75K,1%,1/16W,CHA 1        CLK_CK440_SMB_ADDR0     
                                  2        GND                     
R955             Q_RES_0402LF-33,5%,1/16W,CHIP,A 1        PWRGD_HSC_P12V_PWROK    
                                  2        PWRGD_PS_PWROK_PLD      
R960             Q_RES_0402LF-33.2,1%,1/16W,CHIA 1        SMB_PEHPCPU0_GTL_SCL    
                                  2        SMB_PEHPCPU0_GTL_R_SCL  
R961             Q_RES_0402LF-33.2,1%,1/16W,CHIA 1        SMB_PEHPCPU1_GTL_SCL    
                                  2        SMB_PEHPCPU1_GTL_R_SCL  
R962             Q_RES_0402LF-33.2,1%,1/16W,CHIA 1        SMB_PEHPCPU1_GTL_SDA    
                                  2        SMB_PEHPCPU1_GTL_R_SDA  
R963             Q_RES_0402LF-240,1%,1/16W,CHIPA 1        PVNN_TERM_CPU1          
                                  2        SMB_PEHPCPU1_GTL_R_SCL  
R964             Q_RES_0402LF-240,1%,1/16W,CHIPA 1        PVNN_TERM_CPU1          
                                  2        SMB_PEHPCPU1_GTL_R_SDA  
R965             Q_RES_0402LF-1K,1%,1/16W,CHIP,A 1        P3V3_AUX                
                                  2        SMB_PEHPCPU0_LVC3_SCL   
R966             Q_RES_0402LF-1K,1%,1/16W,CHIP,A 1        P3V3_AUX                
                                  2        SMB_PEHPCPU1_LVC3_SCL   
R967             Q_RES_0402LF-1K,1%,1/16W,CHIP,A 1        P3V3_AUX                
                                  2        SMB_PEHPCPU0_LVC3_SDA   
R968             Q_RES_0402LF-1K,1%,1/16W,CHIP,A 1        P3V3_AUX                
                                  2        SMB_PEHPCPU1_LVC3_SDA   
R969             Q_RES_0402LF-240,1%,1/16W,CHIPA 1        PVNN_TERM_CPU0          
                                  2        SMB_S3M_CPU0_R_SCL      
R970             Q_RES_0402LF-240,1%,1/16W,CHIPA 1        PVNN_TERM_CPU1          
                                  2        SMB_S3M_CPU1_R_SCL      
R971             Q_RES_0402LF-240,1%,1/16W,CHIPA 1        PVNN_TERM_CPU0          
                                  2        SMB_S3M_CPU0_R_SDA      
R972             Q_RES_0402LF-240,1%,1/16W,CHIPA 1        PVNN_TERM_CPU1          
                                  2        SMB_S3M_CPU1_R_SDA      
R973             Q_RES_0402LF-33.2,1%,1/16W,CHIA 1        SMB_S3M_CPU0_R_SCL      
                                  2        SMB_S3M_CPU0_LVC1_SCL   
R974             Q_RES_0402LF-33.2,1%,1/16W,CHIA 1        SMB_S3M_CPU0_R_SDA      
                                  2        SMB_S3M_CPU0_LVC1_SDA   
R975             Q_RES_0402LF-33.2,1%,1/16W,CHIA 1        SMB_S3M_CPU1_R_SCL      
                                  2        SMB_S3M_CPU1_LVC1_SCL   
R976             Q_RES_0402LF-33.2,1%,1/16W,CHIA 1        SMB_S3M_CPU1_R_SDA      
                                  2        SMB_S3M_CPU1_LVC1_SDA   
R977             Q_RES_0402LF-412,1%,1/16W,CHIPA 1        P3V3_AUX                
                                  2        SMB_S3M_CPU0_3V3AUX_SCL 
R978             Q_RES_0402LF-412,1%,1/16W,CHIPA 1        P3V3_AUX                
                                  2        SMB_S3M_CPU1_3V3AUX_SCL 
R979             Q_RES_0402LF-412,1%,1/16W,CHIPA 1        P3V3_AUX                
                                  2        SMB_S3M_CPU0_3V3AUX_SDA 
R980             Q_RES_0402LF-412,1%,1/16W,CHIPA 1        P3V3_AUX                
                                  2        SMB_S3M_CPU1_3V3AUX_SDA 
R981             Q_RES_0402LF-33,5%,1/16W,CHIP,A 1        FM_PVCCIN_CPU0_R_EN     
                                  2        FM_PVCCIN_CPU0_EN       
R982             Q_RES_0402LF-33,5%,1/16W,CHIP,A 1        FM_PVCCFA_EHV_CPU0_R_EN 
                                  2        FM_PVCCFA_EHV_CPU0_EN   
R983             Q_RES_0402LF-33,5%,1/16W,CHIP,A 1        FM_PVCCINFAON_CPU0_R_EN 
                                  2        FM_PVCCINFAON_CPU0_EN   
R984             Q_RES_0402LF-33,5%,1/16W,CHIP,A 1        FM_PVCCFA_EHV_FIVRA_CPU0_R_EN
                                  2        FM_PVCCFA_EHV_FIVRA_CPU0_EN
R985             Q_RES_0402LF-33,5%,1/16W,CHIP,A 1        FM_PVCCIN_CPU1_R_EN     
                                  2        FM_PVCCIN_CPU1_EN       
R986             Q_RES_0402LF-33,5%,1/16W,CHIP,A 1        FM_PVCCFA_EHV_CPU1_R_EN 
                                  2        FM_PVCCFA_EHV_CPU1_EN   
R987             Q_RES_0402LF-33,5%,1/16W,CHIP,A 1        FM_PVCCINFAON_CPU1_R_EN 
                                  2        FM_PVCCINFAON_CPU1_EN   
R988             Q_RES_0402LF-33,5%,1/16W,CHIP,A 1        FM_PVCCFA_EHV_FIVRA_CPU1_R_EN
                                  2        FM_PVCCFA_EHV_FIVRA_CPU1_EN
R989             Q_RES_0402LF-10K,1%,1/16W,CHIPA 1        FM_INTRUDER_HDR_PCH_N   
                                  2        P3V3_RTC_AUX            
R990             Q_RES_0402LF-2K,1%,1/16W,CHIP,A 1        FM_PLD_CLK_25M_R_EN     
                                  2        GND                     
R991             Q_RES_0402LF-2K,1%,1/16W,CHIP,A 1        FM_AUX_SW_EN            
                                  2        GND                     
R992             Q_RES_0402LF-2K,1%,1/16W,CHIP,A 1        PWRGD_CPU0_LVC1_R       
                                  2        GND                     
R993             Q_RES_0402LF-33.2,1%,1/16W,CHIA 1        SMB_S3M_CPU0_SCL        
                                  2        SMB_S3M_CPU0_R_SCL      
R994             Q_RES_0402LF-33.2,1%,1/16W,CHIA 1        SMB_S3M_CPU0_SDA        
                                  2        SMB_S3M_CPU0_R_SDA      
R995             Q_RES_0402LF-33.2,1%,1/16W,CHIA 1        SMB_S3M_CPU1_SCL        
                                  2        SMB_S3M_CPU1_R_SCL      
R996             Q_RES_0402LF-33.2,1%,1/16W,CHIA 1        SMB_S3M_CPU1_SDA        
                                  2        SMB_S3M_CPU1_R_SDA      
R997             Q_RES_0402LF-10K,1%,1/16W,EMPTA 1        PU_PIROM_CPU0_SM_WP     
                                  2        GND                     
R998             Q_RES_0402LF-0,5%,1/16W,CHIP,CA 1        FM_SMB_PEHPCPU0_PCIE_ALERT_N
                                  2        FM_SMB_PEHPCPU0_PCIE_ALERT_R_N
R999             Q_RES_0402LF-0,5%,1/16W,CHIP,CA 1        FM_SMB_PEHPCPU1_PCIE_ALERT_N
                                  2        FM_SMB_PEHPCPU1_PCIE_ALERT_R_N
R1000            Q_RES_0402LF-4.7K,5%,1/16W,CHIA 1        P3V3                    
                                  2        FM_SMB_PEHPCPU0_PCIE_ALERT_R_N
R1001            Q_RES_0402LF-4.7K,5%,1/16W,CHIA 1        P3V3                    
                                  2        FM_SMB_PEHPCPU1_PCIE_ALERT_R_N
R1002            Q_RES_0402LF-4.7K,5%,1/16W,CHIA 1        P3V3                    
                                  2        FM_SMB_CPU0_ALERT_R1    
R1003            Q_RES_0402LF-4.7K,5%,1/16W,CHIA 1        P3V3                    
                                  2        FM_SMB_CPU1_ALERT_R1    
R1004            Q_RES_0402LF-1K,1%,1/16W,CHIP,A 1        P3V3_AUX                
                                  2        PU_PIROM_CPU1_SM_WP     
R1005            Q_RES_0402LF-10K,1%,1/16W,EMPTA 1        PU_PIROM_CPU1_SM_WP     
                                  2        GND                     
R1006            Q_RES_0402LF-4.7K,5%,1/16W,CHIA 1        PVNN_TERM_CPU0          
                                  2        FM_PEHPCPU0_ALERT_N     
R1007            Q_RES_0402LF-4.7K,5%,1/16W,CHIA 1        PVNN_TERM_CPU1          
                                  2        FM_PEHPCPU1_ALERT_N     
R1008            Q_RES_0402LF-1K,1%,1/16W,EMPTYA 1        PVNN_TERM_CPU1          
                                  2        PU_TAP_ODT_CPU1_EN      
R1009            Q_RES_0402LF-1K,1%,1/16W,EMPTYA 1        PVNN_TERM_CPU0          
                                  2        PU_TAP_ODT_CPU0_EN      
R1010            Q_RES_0402LF-0,5%,1/16W,CHIP,CA 1        CLK_25M_CK440_ISCLK_REF_DP
                                  2        CLK_25M_PCH_REF_NS_DP   
R1011            Q_RES_0402LF-0,5%,1/16W,CHIP,CA 1        CLK_25M_CK440_ISCLK_REF_DN
                                  2        CLK_25M_PCH_REF_NS_DN   
R1012            Q_RES_0402LF-0,5%,1/16W,CHIP,CA 1        CLK_25M_CK440_CPU0_DP   
                                  2        CLK_25M_CK440_CPU0_R_DP 
R1013            Q_RES_0402LF-0,5%,1/16W,EMPTY,A 1        CLK_25M_PCH_CPU0_DP     
                                  2        CLK_25M_NSSC_CPU0_DP    
R1014            Q_RES_0402LF-0,5%,1/16W,CHIP,CA 1        CLK_25M_CK440_CPU0_DN   
                                  2        CLK_25M_CK440_CPU0_R_DN 
R1015            Q_RES_0402LF-0,5%,1/16W,EMPTY,A 1        CLK_25M_PCH_CPU0_DN     
                                  2        CLK_25M_NSSC_CPU0_DN    
R1016            Q_RES_0402LF-0,5%,1/16W,CHIP,CA 1        CLK_25M_CK440_CPU1_DP   
                                  2        CLK_25M_CK440_CPU1_R_DP 
R1017            Q_RES_0402LF-0,5%,1/16W,EMPTY,A 1        CLK_25M_PCH_CPU1_DP     
                                  2        CLK_25M_NSSC_CPU1_DP    
R1018            Q_RES_0402LF-0,5%,1/16W,CHIP,CA 1        CLK_25M_CK440_CPU1_DN   
                                  2        CLK_25M_CK440_CPU1_R_DN 
R1019            Q_RES_0402LF-0,5%,1/16W,EMPTY,A 1        CLK_25M_PCH_CPU1_DN     
                                  2        CLK_25M_NSSC_CPU1_DN    
R1020            Q_RES_0402LF-0,5%,1/16W,CHIP,CA 1        CLK_25M_CK440_CPU0_R_DP 
                                  2        CLK_25M_NSSC_CPU0_DP    
R1021            Q_RES_0402LF-0,5%,1/16W,CHIP,CA 1        CLK_25M_CK440_CPU0_R_DN 
                                  2        CLK_25M_NSSC_CPU0_DN    
R1022            Q_RES_0402LF-0,5%,1/16W,CHIP,CA 1        CLK_25M_CK440_CPU1_R_DP 
                                  2        CLK_25M_NSSC_CPU1_DP    
R1023            Q_RES_0402LF-0,5%,1/16W,CHIP,CA 1        CLK_25M_CK440_CPU1_R_DN 
                                  2        CLK_25M_NSSC_CPU1_DN    
R1024            Q_RES_0402LF-100,1%,1/16W,CHIPA 1        JTAG_DBP_TCK_PCH        
                                  2        GND                     
R1025            Q_RES_0402LF-75,1%,1/16W,EMPTYA 1        JTAG_DBP_CPU_GTL_TCK    
                                  2        GND                     
R1026            Q_RES_0402LF-1K,1%,1/16W,CHIP,A 1        JTAG_DBP_PMODE          
                                  2        P1V05_PCH_AUX           
R1051            Q_RES_0402LF-0,5%,1/16W,CHIP,CA 1        SMB_PCIE0_3V3AUX_SCL_R2 
                                  2        SMB_RISER2_1_3V3AUX_SCL 
R1052            Q_RES_0402LF-0,5%,1/16W,CHIP,CA 1        SMB_PCIE0_3V3AUX_SDA_R2 
                                  2        SMB_RISER2_1_3V3AUX_SDA 
R1053            Q_RES_0402LF-0,5%,1/16W,CHIP,CA 1        SMB_OCP_SFF_3V3AUX_SCL  
                                  2        SMB_PCIE_3V3AUX_SCL_R4  
R1054            Q_RES_0402LF-0,5%,1/16W,CHIP,CA 1        SMB_OCP_SFF_3V3AUX_SDA  
                                  2        SMB_PCIE_3V3AUX_SDA_R4  
R1055            Q_RES_0402LF-0,5%,1/16W,CHIP,CA 1        SMB_RISER3_3V3AUX_SCL   
                                  2        SMB_PCIE_3V3AUX_SCL_R3  
R1056            Q_RES_0402LF-0,5%,1/16W,CHIP,CA 1        SMB_RISER3_3V3AUX_SDA   
                                  2        SMB_PCIE_3V3AUX_SDA_R3  
R1057            Q_RES_0402LF-33.2,1%,1/16W,CHIA 1        SMB_E1S_0_3V3AUX_SCL    
                                  2        SMB_PCIE1_3V3AUX_SCL_R0 
R1058            Q_RES_0402LF-0,5%,1/16W,CHIP,CA 1        SMB_E1S_0_3V3AUX_SDA    
                                  2        SMB_PCIE1_3V3AUX_SDA_R0 
R1059            Q_RES_0402LF-0,5%,1/16W,CHIP,CA 1        SMB_E1S_1_3V3AUX_SCL    
                                  2        SMB_PCIE1_3V3AUX_SCL_R1 
R1060            Q_RES_0402LF-0,5%,1/16W,CHIP,CA 1        SMB_E1S_1_3V3AUX_SDA    
                                  2        SMB_PCIE1_3V3AUX_SDA_R1 
R1061            Q_RES_0402LF-0,5%,1/16W,CHIP,CA 1        SMB_PCIE1_3V3AUX_SCL_R2 
                                  2        SMB_E1S_2_3V3AUX_SCL    
R1062            Q_RES_0402LF-0,5%,1/16W,CHIP,CA 1        SMB_PCIE1_3V3AUX_SDA_R2 
                                  2        SMB_E1S_2_3V3AUX_SDA    
R1063            Q_RES_0402LF-0,5%,1/16W,CHIP,CA 1        SMB_PCIE1_3V3AUX_SCL_R3 
                                  2        SMB_E1S_3_3V3AUX_SCL    
R1064            Q_RES_0402LF-0,5%,1/16W,CHIP,CA 1        SMB_PCIE1_3V3AUX_SDA_R3 
                                  2        SMB_E1S_3_3V3AUX_SDA    
R1065            Q_RES_0402LF-2.2K ,5%,1/16W,EMA 1        P3V3_AUX                
                                  2        SMB_E1S_0_3V3AUX_SCL    
R1066            Q_RES_0402LF-2.2K ,5%,1/16W,EMA 1        P3V3_AUX                
                                  2        SMB_E1S_0_3V3AUX_SDA    
R1067            Q_RES_0402LF-2.2K ,5%,1/16W,EMA 1        P3V3_AUX                
                                  2        SMB_E1S_1_3V3AUX_SCL    
R1068            Q_RES_0402LF-2.2K ,5%,1/16W,EMA 1        P3V3_AUX                
                                  2        SMB_E1S_1_3V3AUX_SDA    
R1069            Q_RES_0402LF-2.2K ,5%,1/16W,EMA 1        P3V3_AUX                
                                  2        SMB_E1S_2_3V3AUX_SCL    
R1070            Q_RES_0402LF-2.2K ,5%,1/16W,EMA 1        P3V3_AUX                
                                  2        SMB_E1S_2_3V3AUX_SDA    
R1071            Q_RES_0402LF-2.2K ,5%,1/16W,EMA 1        P3V3_AUX                
                                  2        SMB_E1S_3_3V3AUX_SCL    
R1072            Q_RES_0402LF-2.2K ,5%,1/16W,EMA 1        P3V3_AUX                
                                  2        SMB_E1S_3_3V3AUX_SDA    
R1089            Q_RES_0402LF-2.2K ,5%,1/16W,CHA 1        P3V3_AUX                
                                  2        SMB_SENSOR_M2_P0_3V3AUX_SCL
R1090            Q_RES_0402LF-2.2K ,5%,1/16W,CHA 1        P3V3_AUX                
                                  2        SMB_SENSOR_M2_P0_3V3AUX_SDA
R1091            Q_RES_0402LF-2.2K ,5%,1/16W,CHA 1        P3V3_AUX                
                                  2        SMB_RISER1_3V3AUX_SCL   
R1092            Q_RES_0402LF-2.2K ,5%,1/16W,CHA 1        P3V3_AUX                
                                  2        SMB_RISER1_3V3AUX_SDA   
R1099            Q_RES_0402LF-10K,1%,1/16W,CHIPA 1        P3V3_AUX                
                                  2        PU_CLK25M_OSC_FPGA_EN   
R1100            Q_RES_0402LF-33.2,1%,1/16W,CHIA 1        CLK_25M_OSC_FPGA_R      
                                  2        CLK_25M_OSC_MAIN_FPGA   
R1103            Q_RES_0402LF-1.33K,1%,1/16W,CHA 1        P3V3_E1S_0_ILM          
                                  2        GND                     
R1104            Q_RES_0402LF-10K,1%,1/16W,CHIPA 1        P3V3_AUX                
                                  2        P3V3_E1S_0_FLT_N        
R1106            Q_RES_0402LF-10K,1%,1/16W,CHIPA 1        P3V3_AUX                
                                  2        FM_PLD_REV_R_N          
R1123            Q_RES_0402LF-1K,5%,1/16W,EMPTYA 1        P3V3_AUX                
                                  2        PD_SMB_OCP1_HP_ADD2     
R1124            Q_RES_0402LF-1K,5%,1/16W,CHIP,A 1        PD_SMB_OCP1_HP_ADD2     
                                  2        GND                     
R1125            Q_RES_0402LF-1K,5%,1/16W,EMPTYA 1        P3V3_AUX                
                                  2        PD_SMB_OCP1_HP_ADD1     
R1126            Q_RES_0402LF-1K,5%,1/16W,CHIP,A 1        PD_SMB_OCP1_HP_ADD1     
                                  2        GND                     
R1127            Q_RES_0402LF-1K,5%,1/16W,EMPTYA 1        P3V3_AUX                
                                  2        PD_SMB_OCP1_HP_ADD0     
R1128            Q_RES_0402LF-1K,5%,1/16W,CHIP,A 1        PD_SMB_OCP1_HP_ADD0     
                                  2        GND                     
R1129            Q_RES_0402LF-1K,5%,1/16W,CHIP,A 1        P3V3_AUX                
                                  2        HP_LVC3_OCP_V3_1_PRSNT2 
R1130            Q_RES_0402LF-33,5%,1/16W,CHIP,A 1        SMB_PEHPCPU0_LVC3_SCL   
                                  2        SMB_PEHPCPU0_LVC3_R_SCL 
R1131            Q_RES_0402LF-33,5%,1/16W,CHIP,A 1        SMB_PEHPCPU0_LVC3_SDA   
                                  2        SMB_PEHPCPU0_LVC3_R_SDA 
R1132            Q_RES_0402LF-1K,5%,1/16W,EMPTYA 1        P3V3_OCP_SFF            
                                  2        HP_LVC3_OCP_V3_1_PWRGD  
R1133            Q_RES_0402LF-10K,1%,1/16W,CHIPA 1        P3V3_AUX                
                                  2        HP_LVC3_OCP_V3_1_PWRGD_N
R1134            Q_RES_0402LF-0,5%,1/16W,CHIP,CA 1        P12V_OCP_LDSTRT11       
                                  2        GND                     
R1135            Q_RES_0402LF-0,5%,1/16W,EMPTY,A 1        P12V_OCP_NRETRY1        
                                  2        GND                     
R1136            Q_RES_0402LF-0,5%,1/16W,CHIP,CA 1        P12V_OCP_RETRY1         
                                  2        GND                     
R1137            Q_RES_0402LF-150,1%,1/16W,CHIPA 1        P12V_OCP_ILIM1          
                                  2        GND                     
R1138            Q_RES_0402LF-10K,1%,1/16W,CHIPA 1        P3V3_AUX                
                                  2        CLK_50M_EN              
R1139            Q_RES_0402LF-0,5%,1/16W,CHIP,CA 1        CLK_50M_RMII            
                                  2        CLK_50M_RMII_R          
R1140            Q_RES_0402LF-27.4,1%,1/16W,CHIA 1        CLK_50M_BMC_MAC_R       
                                  2        CLK_50M_RMII_BMC_OCP    
R1141            Q_RES_0402LF-27.4,1%,1/16W,CHIA 1        CLK_50M_NCSI_OCP_1      
                                  2        CLK_50M_NCSI_OCP_SFF    
R1142            Q_RES_0402LF-1K,5%,1/16W,CHIP,A 1        P3V3_OCP_ILM1           
                                  2        GND                     
R1143            Q_RES_0402LF-10K,1%,1/16W,CHIPA 1        P3V3_AUX                
                                  2        HP_LVC3_OCP_V3_1_FAULT_N
R1144            Q_RES_0402LF-562,1%,1/16W,CHIPA 1        P12V_OCP_IMON_1         
                                  2        GND                     
R1146            Q_RES_0402LF-1K,1%,1/16W,CHIP,A 1        P3V3_AUX                
                                  2        HP_LVC3_OCP_V3_1_HSC_PWRGD
R1147            Q_RES_0402LF-0,5%,1/16W,CHIP,CA 1        HP_LVC3_OCP_V3_1_PRSNT2_N_R
                                  2        HP_LVC3_OCP_V3_1_ATTN_OUT_SW_N
R1148            Q_RES_0402LF-0,5%,1/16W,CHIP,CA 1        HP_LVC3_OCP_V3_1_PRSNT2_N_R
                                  2        HP_LVC3_OCP_V3_1_PRSNT2_N
R1149            Q_RES_0402LF-10K,1%,1/16W,CHIPA 1        P3V3_AUX                
                                  2        HP_LVC3_OCP_V3_1_ATTN_OUT_SW_N
R1150            Q_RES_0402LF-10K,1%,1/16W,CHIPA 1        P3V3_AUX                
                                  2        HP_LVC3_OCP_V3_1_PRSNT2_N
R1184            Q_RES_0402LF-0,5%,1/16W,CHIP,CA 1        JTAG_BMC_DBP_TMS_R      
                                  2        JTAG_BMC_DBP_TMS        
R1194            Q_RES_0402LF-4.75K,1%,1/16W,EMA 1        P3V3_AUX                
                                  2        FM_CK440_MXCK_25M_100M  
R1195            Q_RES_0402LF-750,1%,1/16W,CHIPA 1        P3V3_AUX                
                                  2        PU_PLD_HEARTBEAT_LVC3   
R1196            Q_RES_0402LF-4.75K,1%,1/16W,CHA 1        FM_CK440_MXCK_25M_100M  
                                  2        GND                     
R1197            Q_RES_0402LF-1K,5%,1/16W,EMPTYA 1        GND                     
                                  2        PD_SUSCLK               
R1198            Q_RES_0402LF-10K,1%,1/16W,CHIPA 1        P3V3_AUX                
                                  2        PU_ACPRESENT            
R1200            Q_RES_0402LF-100,1%,1/16W,CHIPA 1        FM_PCH_TRIGGER0_N       
                                  2        FM_PCH_TRIGGER0_R_N     
R1201            Q_RES_0402LF-49.9     ,1%  ,1/A 1        FM_PCH_TRIGGER1_N       
                                  2        FM_PCH_TRIGGER1_R_N     
R1202            Q_RES_0402LF-20K,1%,1/16W,CHIPA 1        P3V3_RTC_AUX            
                                  2        RST_SRTCRST_N           
R1203            Q_RES_0402LF-1K,1%,1/16W,CHIP,A 1        P3V_BAT                 
                                  2        P3V_BAT_R               
R1204            Q_RES_0402LF-10K,1%,1/16W,EMPTA 1        P3V3_AUX                
                                  2        PU_CK440_SHFT_LD_N      
R1205            Q_RES_0402LF-33,5%,1/16W,CHIP,A 1        RST_PLTRST_N            
                                  2        RST_PLTRST_PLD_N        
R1206            Q_RES_0402LF-33,5%,1/16W,CHIP,A 1        RST_MB_STBY_R_N         
                                  2        RST_MB_STBY_N           
R1207            Q_RES_0402LF-33,5%,1/16W,CHIP,A 1        RST_RSMRST_PLD_R_N      
                                  2        RST_RSMRST_PCH_N        
R1214            Q_RES_0402LF-0,5%,1/16W,CHIP,CA 1        IRQ_LPC_PIRQA_N_ESPI_ALERT0_N
                                  2        IRQ_LPC_PIRQA_N_ESPI_ALERT0_R_N
R1215            Q_RES_0402LF-49.9     ,1%  ,1/A 1        IRQ_ESPI_LPC_SERIRQ_ALERT_N
                                  2        IRQ_ESPI_LPC_SERIRQ_ALERT_R_N
R1216            Q_RES_0402LF-10K,1%,1/16W,CHIPA 1        P3V3_AUX                
                                  2        FM_S3M_CPU0_CPLD_CRC_ERROR
R1217            Q_RES_0402LF-10K,1%,1/16W,CHIPA 1        P3V3_AUX                
                                  2        FM_S3M_CPU1_CPLD_CRC_ERROR
R1218            Q_RES_0402LF-33.2,1%,1/16W,CHIA 1        PWRGD_S0_PWROK_CPU0_LVC1
                                  2        PWRGD_S0_PWROK_CPU0_LVC1_R
R1219            Q_RES_0402LF-33.2,1%,1/16W,CHIA 1        PWRGD_S0_PWROK_CPU1_LVC1
                                  2        PWRGD_S0_PWROK_CPU1_LVC1_R
R1220            Q_RES_0402LF-1K,1%,1/16W,EMPTYA 1        P3V3_AUX                
                                  2        FM_PCH_MCRO_LDO         
R1221            Q_RES_0402LF-1K,1%,1/16W,CHIP,A 1        FM_PCH_MCRO_LDO         
                                  2        GND                     
R1222            Q_RES_0402LF-5.11K,1%,1/16W,CHA 1        P3V3_AUX                
                                  2        FM_PCH_SPARE0           
R1223            Q_RES_0402LF-10K,1%,1/16W,EMPTA 1        JTAG_CPU0_PLD_TDI       
                                  2        P3V3_AUX                
R1224            Q_RES_0402LF-10K,1%,1/16W,CHIPA 1        JTAG_CPU0_PLD_TMS       
                                  2        P3V3_AUX                
R1225            Q_RES_0402LF-10K,1%,1/16W,CHIPA 1        JTAG_CPU0_PLD_TDO       
                                  2        P3V3_AUX                
R1226            Q_RES_0402LF-1K,1%,1/16W,CHIP,A 1        JTAG_CPU0_PLD_TCK       
                                  2        GND                     
R1227            Q_RES_0402LF-10K,1%,1/16W,CHIPA 1        PD_JTAG_CPU1_PLD_TCK    
                                  2        GND                     
R1229            Q_RES_0402LF-240,1%,1/16W,EMPTA 1        PVNN_TERM_CPU1          
                                  2        PUD_XTAL_CPU1_MODE0     
R1230            Q_RES_0402LF-240,1%,1/16W,EMPTA 1        PVNN_TERM_CPU1          
                                  2        PUD_XTAL_CPU1_MODE1     
R1232            Q_RES_0402LF-240,1%,1/16W,EMPTA 1        PVNN_TERM_CPU0          
                                  2        PUD_XTAL_CPU0_MODE0     
R1233            Q_RES_0402LF-240,1%,1/16W,EMPTA 1        PVNN_TERM_CPU0          
                                  2        PUD_XTAL_CPU0_MODE1     
R1234            Q_RES_0402LF-240,1%,1/16W,EMPTA 1        GND                     
                                  2        PD_EXT_CLK_SEL_CPU1     
R1235            Q_RES_0402LF-240,1%,1/16W,EMPTA 1        GND                     
                                  2        PUD_XTAL_CPU1_MODE0     
R1236            Q_RES_0402LF-240,1%,1/16W,EMPTA 1        GND                     
                                  2        PUD_XTAL_CPU1_MODE1     
R1237            Q_RES_0402LF-240,1%,1/16W,EMPTA 1        GND                     
                                  2        PD_EXT_CLK_SEL_CPU0     
R1238            Q_RES_0402LF-240,1%,1/16W,EMPTA 1        GND                     
                                  2        PUD_XTAL_CPU0_MODE0     
R1239            Q_RES_0402LF-240,1%,1/16W,EMPTA 1        GND                     
                                  2        PUD_XTAL_CPU0_MODE1     
R1240            Q_RES_0402LF-0,5%,1/16W,CHIP,CA 1        H_CPU0_PM_FAST_WAKE_N   
                                  2        H_CPU_PM_FAST_WAKE_N    
R1241            Q_RES_0402LF-249,1%,1/16W,CHIPA 1        H_PMAX_TRIGGER_IO_CPU0  
                                  2        GND                     
R1242            Q_RES_0402LF-301,1%,1/16W,CHIPA 1        PVNN_TERM_CPU0          
                                  2        H_CPU_PM_FAST_WAKE_N    
R1243            Q_RES_0402LF-249,1%,1/16W,CHIPA 1        H_PMAX_TRIGGER_IO_CPU1  
                                  2        GND                     
R1244            Q_RES_0402LF-301,1%,1/16W,CHIPA 1        PVNN_TERM_CPU1          
                                  2        H_CPU_PM_FAST_WAKE_N    
R1245            Q_RES_0402LF-0,5%,1/16W,CHIP,CA 1        H_CPU_PM_FAST_WAKE_N    
                                  2        H_CPU1_PM_FAST_WAKE_N   
R1247            Q_RES_0402LF-0,5%,1/16W,CHIP,CA 1        FM_PCH_CPU_PWR_DEBUG_N  
                                  2        FM_CPU_FBRK_DEBUG_N     
R1249            Q_RES_0402LF-0,5%,1/16W,CHIP,CA 1        FM_THERMTRIP_DLY_LVC1_N 
                                  2        H_THERMTRIP_LVC1_N      
R1253            Q_RES_0402LF-1K,1%,1/16W,CHIP,A 1        PGPPA_AUX               
                                  2        IRQ_LPC_PIRQA_N_ESPI_ALERT0_N
R1254            Q_RES_0402LF-10K,1%,1/16W,CHIPA 1        PGPPA_AUX               
                                  2        IRQ_LPC_SERIRQ_ESPI_CS1_N
R1255            Q_RES_0402LF-1K,1%,1/16W,CHIP,A 1        PGPPA_AUX               
                                  2        ESPI_ALERT1_N_LPC_RCIN_N
R1256            Q_RES_0402LF-10K,1%,1/16W,CHIPA 1        P3V3_AUX                
                                  2        IRQ_PCH_SCI_WHEA_N      
R1257            Q_RES_0402LF-10K,1%,1/16W,CHIPA 1        P3V3_AUX                
                                  2        PU_PCH_VRALERT_N        
R1258            Q_RES_0402LF-10K,1%,1/16W,CHIPA 1        P3V3_AUX                
                                  2        FM_PCH_GLB_RST_WARN_N   
R1259            Q_RES_0402LF-10K,1%,1/16W,CHIPA 1        P3V3_AUX                
                                  2        PU_LPC_PME_N            
R1260            Q_RES_0402LF-10K,1%,1/16W,EMPTA 1        P1V05_PCH_AUX           
                                  2        H_CPU_ERR0_PCH_R_N      
R1261            Q_RES_0402LF-10K,1%,1/16W,EMPTA 1        P1V05_PCH_AUX           
                                  2        H_CPU_ERR1_PCH_R_N      
R1262            Q_RES_0402LF-10K,1%,1/16W,EMPTA 1        P1V05_PCH_AUX           
                                  2        H_CPU_ERR2_PCH_R_N      
R1263            Q_RES_0402LF-33,5%,1/16W,CHIP,A 1        FM_PLT_BMC_THERMTRIP_R_N
                                  2        FM_PCH_BMC_THERMTRIP_N  
R1266            Q_RES_0402LF-49.9     ,1%  ,1/B 1        P1V05_PCH_AUX           
                                  2        H_THERMTRIP_LVC1_N      
R1267            Q_RES_0402LF-1K,1%,1/16W,CHIP,A 1        PU_CK440_SHFT_LD_N      
                                  2        GND                     
R1268            Q_RES_0402LF-33,5%,1/16W,CHIP,A 1        IRQ_BMC_PCH_NMI_R1      
                                  2        IRQ_BMC_PCH_NMI         
R1269            Q_RES_0402LF-4.75K,1%,1/16W,CHA 1        IRQ_BMC_PCH_NMI         
                                  2        GND                     
R1270            Q_RES_0402LF-240,1%,1/16W,EMPTA 1        PD_CPU1_PROCDIS_COD_GTL_N
                                  2        GND                     
R1271            Q_RES_0402LF-2.21K    ,1%  ,1/A 1        PGPPA_AUX               
                                  2        FM_PCH_SATA_RAID_KEY    
R1273            Q_RES_0402LF-0,5%,1/16W,CHIP,CA 1        CLK_100M_OCP_SFF_2_R_DP 
                                  2        CLK_100M_OCP_SFF_2_DP   
R1274            Q_RES_0402LF-0,5%,1/16W,CHIP,CA 1        CLK_100M_OCP_SFF_2_R_DN 
                                  2        CLK_100M_OCP_SFF_2_DN   
R1275            Q_RES_0402LF-0,5%,1/16W,CHIP,CA 1        CLK_100M_OCP_SFF_3_R_DP 
                                  2        CLK_100M_OCP_SFF_3_DP   
R1276            Q_RES_0402LF-0,5%,1/16W,CHIP,CA 1        CLK_100M_OCP_SFF_3_R_DN 
                                  2        CLK_100M_OCP_SFF_3_DN   
R1277            Q_RES_0402LF-0,5%,1/16W,CHIP,CA 1        CLK_100M_EDSFF1A_R_DP   
                                  2        CLK_100M_EDSFF1A_DP     
R1278            Q_RES_0402LF-0,5%,1/16W,CHIP,CA 1        CLK_100M_EDSFF1A_R_DN   
                                  2        CLK_100M_EDSFF1A_DN     
R1279            Q_RES_0402LF-0,5%,1/16W,CHIP,CA 1        CLK_100M_EDSFF1B_R_DP   
                                  2        CLK_100M_EDSFF1B_DP     
R1280            Q_RES_0402LF-0,5%,1/16W,CHIP,CA 1        CLK_100M_EDSFF1B_R_DN   
                                  2        CLK_100M_EDSFF1B_DN     
R1281            Q_RES_0402LF-0,5%,1/16W,CHIP,CA 1        CLK_100M_EDSFF3_R_DP    
                                  2        CLK_100M_EDSFF3_DP      
R1282            Q_RES_0402LF-0,5%,1/16W,CHIP,CA 1        CLK_100M_EDSFF3_R_DN    
                                  2        CLK_100M_EDSFF3_DN      
R1283            Q_RES_0402LF-0,5%,1/16W,CHIP,CA 1        CLK_100M_EDSFF4A_R_DP   
                                  2        CLK_100M_EDSFF4A_DP     
R1284            Q_RES_0402LF-0,5%,1/16W,CHIP,CA 1        CLK_100M_EDSFF4A_R_DN   
                                  2        CLK_100M_EDSFF4A_DN     
R1289            Q_RES_0402LF-100K,1%,1/16W,CHIA 1        FB_BMC_ISOLATE          
                                  2        GND                     
R1290            Q_RES_0402LF-22,1%,1/16W,CHIP,A 1        OCP_SFF_RBT_ARB_IN      
                                  2        OCP_SFF_RBT_ARB_OUT     
R1291            Q_RES_0402LF-22,1%,1/16W,CHIP,A 1        NCSI_BMC_CRS_DV_R       
                                  2        RMII_OCP_BMC_CRSDV      
R1292            Q_RES_0402LF-22,1%,1/16W,CHIP,A 1        NCSI_BMC_RXD0_R         
                                  2        RMII_OCP_BMC_RXD_0      
R1293            Q_RES_0402LF-22,1%,1/16W,CHIP,A 1        NCSI_BMC_RXD1_R         
                                  2        RMII_OCP_BMC_RXD_1      
R1294            Q_RES_0402LF-22,1%,1/16W,CHIP,A 1        NCSI_BMC_TX_EN_R        
                                  2        RMII_BMC_OCP_TX_EN      
R1295            Q_RES_0402LF-22,1%,1/16W,CHIP,A 1        NCSI_BMC_TXD0_R         
                                  2        RMII_BMC_OCP_TXD_0      
R1296            Q_RES_0402LF-22,1%,1/16W,CHIP,A 1        NCSI_BMC_TXD1_R         
                                  2        RMII_BMC_OCP_TXD_1      
R1298            Q_RES_0402LF-1K,5%,1/16W,EMPTYA 1        P1V05_PCH_AUX           
                                  2        FM_MFG_MODE             
R1299            Q_RES_0402LF-10K,1%,1/16W,CHIPA 1        FM_MFG_MODE             
                                  2        GND                     
R1300            Q_RES_0402LF-33.2,1%,1/16W,CHIA 1        FM_BIOS_POST_CMPLT_N    
                                  2        FM_BIOS_POST_CMPLT_BMC_N
R1302            Q_RES_0402LF-2K,1%,1/16W,CHIP,A 1        PWRGD_DRAMPWRGD_CPU0_AB_R_LVC1
                                  2        GND                     
R1305            Q_RES_0402LF-10K,1%,1/16W,EMPTA 1        P3V3_AUX                
                                  2        FM_PLD_CLKS_DEV_EN      
R1306            Q_RES_0402LF-33.2,1%,1/16W,CHIA 1        FM_PS_PWROK_DLY_R_SEL   
                                  2        FM_PS_PWROK_DLY_SEL     
R1307            Q_RES_0402LF-33.2,1%,1/16W,CHIA 1        FM_THROTTLE_N           
                                  2        FM_THROTTLE_R_N         
R1308            Q_RES_0402LF-10K,1%,1/16W,EMPTA 1        FM_RST_PERST_BIT1       
                                  2        GND                     
R1309            Q_RES_0402LF-33.2,1%,1/16W,CHIA 1        IRQ_SMI_ACTIVE_N        
                                  2        IRQ_SMI_ACTIVE_BMC_N    
R1310            Q_RES_0402LF-33.2,1%,1/16W,CHIA 1        IRQ_PCH_CPU_NMI_EVENT_R_N
                                  2        IRQ_PCH_CPU_NMI_EVENT_N 
R1311            Q_RES_0402LF-10K,1%,1/16W,CHIPA 1        FM_XTAL_INPUT_FREQUENCY_0_MGPIO
                                  2        GND                     
R1312            Q_RES_0402LF-10K,1%,1/16W,EMPTA 1        FM_RST_PERST_BIT2       
                                  2        GND                     
R1313            Q_RES_0402LF-33.2,1%,1/16W,CHIA 1        FM_PCH_GLB_RST_WARN_N   
                                  2        FM_PCH_PLD_GLB_RST_WARN_N
R1314            Q_RES_0402LF-2.2K ,5%,1/16W,CHA 1        P3V3_AUX                
                                  2        SMB_PCIE1_3V3AUX_SDA    
R1315            Q_RES_0402LF-1K,5%,1/16W,EMPTYA 1        P1V05_PCH_AUX           
                                  2        FM_XTAL_INPUT_FREQUENCY_1_MGPIO
R1316            Q_RES_0603LF-200K,0.1%,1/10W,EA 1        XTAL_PCH_25M_IN_R       
                                  2        XTAL_PCH_25M_OUT        
R1317            Q_RES_0402LF-1K,1%,1/16W,CHIP,A 1        P1V05_PCH_AUX           
                                  2        PU_BIOS_RCVR_BOOT       
R1318            Q_RES_0402LF-33.2,1%,1/16W,CHIA 1        FM_THERMTRIP_DLY_LVC1_R_N
                                  2        FM_THERMTRIP_DLY_LVC1_N 
R1319            Q_RES_0402LF-2K,1%,1/16W,CHIP,A 1        SMB_HOST_3V3AUX_SCL     
                                  2        P3V3_AUX                
R1320            Q_RES_0402LF-1K,1%,1/16W,CHIP,A 1        P3V3_AUX                
                                  2        PU_SWAP_OVERRIDE_N      
R1321            Q_RES_0402LF-2K,1%,1/16W,CHIP,A 1        SMB_HOST_3V3AUX_SDA     
                                  2        P3V3_AUX                
R1324            Q_RES_0402LF-1K,1%,1/16W,CHIP,A 1        GND                     
                                  2        PD_BIOS_IMAGE_SWAP_N    
R1325            Q_RES_0402LF-1K,1%,1/16W,CHIP,A 1        P3V3_AUX                
                                  2        PU_FLASH_SECURITY_STRAP 
R1326            Q_RES_0402LF-2K,1%,1/16W,CHIP,A 1        PWRGD_DRAMPWRGD_CPU0_CD_R_LVC1
                                  2        GND                     
R1327            Q_RES_0402LF-2K,1%,1/16W,CHIP,A 1        PWRGD_DRAMPWRGD_CPU0_EF_R_LVC1
                                  2        GND                     
R1328            Q_RES_0402LF-2K,1%,1/16W,CHIP,A 1        PWRGD_DRAMPWRGD_CPU0_GH_R_LVC1
                                  2        GND                     
R1329            Q_RES_0402LF-2K,1%,1/16W,CHIP,A 1        PWRGD_DRAMPWRGD_CPU1_AB_R_LVC1
                                  2        GND                     
R1330            Q_RES_0402LF-2K,1%,1/16W,CHIP,A 1        PWRGD_DRAMPWRGD_CPU1_CD_R_LVC1
                                  2        GND                     
R1331            Q_RES_0402LF-4.7K,5%,1/16W,CHIA 1        P3V3_AUX                
                                  2        SMB_SENSOR_3V3AUX_SCL   
R1332            Q_RES_0402LF-4.7K,5%,1/16W,CHIA 1        P3V3_AUX                
                                  2        SMB_SENSOR_3V3AUX_SDA   
R1333            Q_RES_0402LF-1K,1%,1/16W,CHIP,A 1        GND                     
                                  2        PD_RST_RTCRST_N         
R1334            Q_RES_0402LF-1K,1%,1/16W,CHIP,A 1        GND                     
                                  2        PD_ME_RCVR_N            
R1335            Q_RES_0402LF-1K,1%,1/16W,CHIP,A 1        GND                     
                                  2        PD_PASSWORD_CLEAR       
R1336            Q_RES_0402LF-2.2K ,5%,1/16W,CHA 1        SMB_SENSOR_3V3AUX_SCL   
                                  2        P3V3_AUX                
R1337            Q_RES_0402LF-10K,1%,1/16W,CHIPA 1        FM_FLASH_SECURITY_STRAP 
                                  2        GND                     
R1338            Q_RES_0402LF-10K,1%,1/16W,CHIPA 1        FM_PCH_BIOS_RCVR_MODE   
                                  2        GND                     
R1339            Q_RES_0402LF-10K,1%,1/16W,CHIPA 1        P3V3_AUX                
                                  2        FM_BIOS_IMAGE_SWAP_N    
R1340            Q_RES_0402LF-20K,5%,1/16W,CHIPA 1        P3V3_RTC_AUX            
                                  2        RST_RTCRST_N            
R1341            Q_RES_0402LF-10K,1%,1/16W,CHIPA 1        FM_ADR_COMPLETE         
                                  2        GND                     
R1342            Q_RES_0402LF-10K,1%,1/16W,CHIPA 1        P1V05_PCH_AUX           
                                  2        FM_ME_RCVR_N            
R1343            Q_RES_0402LF-10K,1%,1/16W,CHIPA 1        P1V05_PCH_AUX           
                                  2        FM_PASSWORD_CLEAR_N     
R1345            Q_RES_0402LF-0,5%,1/16W,CHIP,CA 1        JTAG_BMC_DBP_TDI_R      
                                  2        JTAG_BMC_DBP_TDI        
R1346            Q_RES_0402LF-1K,1%,1/16W,CHIP,A 1        PD_GTL2014_BMC_JTAG_VREF_2
                                  2        GND                     
R1347            Q_RES_0402LF-1K,1%,1/16W,CHIP,A 1        PD_GTL2014_BMC_JTAG_VREF_1
                                  2        GND                     
R1348            Q_RES_0402LF-0,5%,1/16W,CHIP,CA 1        JTAG_DBP_CPU_GTL_TCK_R1 
                                  2        JTAG_DBP_CPU_GTL_TCK    
R1349            Q_RES_0402LF-0,5%,1/16W,CHIP,CA 1        JTAG_DBP_TCK_PCH_R      
                                  2        JTAG_DBP_TCK_PCH        
R1350            Q_RES_0402LF-100K,1%,1/16W,CHIA 1        RMII_OCP_BMC_CRSDV      
                                  2        GND                     
R1351            Q_RES_0402LF-100K,1%,1/16W,CHIA 1        RMII_OCP_BMC_RXD_0      
                                  2        GND                     
R1352            Q_RES_0402LF-100K,1%,1/16W,CHIA 1        RMII_OCP_BMC_RXD_1      
                                  2        GND                     
R1353            Q_RES_0402LF-100K,1%,1/16W,CHIA 1        RMII_BMC_OCP_TX_EN      
                                  2        GND                     
R1354            Q_RES_0402LF-100K,1%,1/16W,CHIA 1        RMII_BMC_OCP_TXD_0      
                                  2        GND                     
R1355            Q_RES_0402LF-100K,1%,1/16W,CHIA 1        RMII_BMC_OCP_TXD_1      
                                  2        GND                     
R1356            Q_RES_0402LF-1K,1%,1/16W,CHIP,A 1        RMII_BMC_OCP_RX_ER      
                                  2        GND                     
R1361            Q_RES_0402LF-0,5%,1/16W,CHIP,CA 1        CLK_100M_EDSFF2A_R_DP   
                                  2        CLK_100M_EDSFF2A_DP     
R1362            Q_RES_0402LF-0,5%,1/16W,CHIP,CA 1        CLK_100M_EDSFF2A_R_DN   
                                  2        CLK_100M_EDSFF2A_DN     
R1363            Q_RES_0402LF-0,5%,1/16W,CHIP,CA 1        CLK_100M_EDSFF2B_R_DP   
                                  2        CLK_100M_EDSFF2B_DP     
R1364            Q_RES_0402LF-0,5%,1/16W,CHIP,CA 1        CLK_100M_EDSFF2B_R_DN   
                                  2        CLK_100M_EDSFF2B_DN     
R1365            Q_RES_0402LF-1K,1%,1/16W,CHIP,A 1        FM_JTAG_TCK_MUX_SEL     
                                  2        GND                     
R1366            Q_RES_0402LF-100,1%,1/16W,CHIPB 1        JTAG_DBP_TDO            
                                  2        JTAG_DBP_FB_TDO         
R1367            Q_RES_0402LF-100,1%,1/16W,CHIPB 1        JTAG_DBP_PRDY_N         
                                  2        JTAG_DBP_PRDY_R_N       
R1368            Q_RES_0402LF-1K,1%,1/16W,CHIP,A 1        PD_JTAG_DBP_B2          
                                  2        GND                     
R1369            Q_RES_0402LF-1K,1%,1/16W,CHIP,A 1        PD_JTAG_DBP_B0          
                                  2        GND                     
R1370            Q_RES_0402LF-100,1%,1/16W,EMPTA 1        P3V3_AUX                
                                  2        FM_REMOTE_DEBUG_DET_R   
R1371            Q_RES_0402LF-1K,1%,1/16W,CHIP,A 1        JTAG_BMC_PCH_TCK        
                                  2        GND                     
R1372            Q_RES_0402LF-1K,1%,1/16W,CHIP,A 1        FM_REMOTE_DEBUG_DET_R   
                                  2        GND                     
R1373            Q_RES_0402LF-1K,1%,1/16W,CHIP,A 1        JTAG_BMC_CPU_TCK        
                                  2        GND                     
R1374            Q_RES_0402LF-1K,1%,1/16W,CHIP,A 1        PD_JTAG_BMC_NTRST_N     
                                  2        GND                     
R1375            Q_RES_0402LF-10K,1%,1/16W,CHIPA 1        FM_BMC_EN_DET           
                                  2        GND                     
R1376            Q_RES_0402LF-1K,1%,1/16W,CHIP,A 1        P3V3_AUX                
                                  2        PU_GTL2014_BMC_JTAG_DIR_2
R1377            Q_RES_0402LF-1K,1%,1/16W,CHIP,A 1        P3V3_AUX                
                                  2        PU_GTL2014_BMC_JTAG_DIR_1
R1378            Q_RES_0402LF-33.2,1%,1/16W,CHIA 1        JTAG_DBP_BMC_PRDY_R1_N  
                                  2        JTAG_DBP_BMC_PRDY_N     
R1379            Q_RES_0402LF-33.2,1%,1/16W,CHIA 1        JTAG_DBP_BMC_PREQ_R1_N  
                                  2        JTAG_BMC_DBP_PREQ_N     
R1380            Q_RES_0402LF-1K,1%,1/16W,CHIP,A 1        P3V3_AUX                
                                  2        JTAG_BMC_DBP_TDO        
R1381            Q_RES_0402LF-1K,1%,1/16W,CHIP,A 1        P3V3_AUX                
                                  2        FM_BMC_CPU_FBRK_OUT_N   
R1382            Q_RES_0402LF-1K,1%,1/16W,CHIP,A 1        P3V3_AUX                
                                  2        JTAG_DBP_BMC_PRDY_N     
R1383            Q_RES_0402LF-1K,1%,1/16W,CHIP,A 1        P3V3_AUX                
                                  2        JTAG_BMC_DBP_PREQ_N     
R1384            Q_RES_0402LF-2K,1%,1/16W,CHIP,A 1        SMB_SML0_3V3AUX_SCL     
                                  2        P3V3_AUX                
R1385            Q_RES_0402LF-2K,1%,1/16W,CHIP,A 1        SMB_SML0_3V3AUX_SDA     
                                  2        P3V3_AUX                
R1386            Q_RES_0402LF-2K,1%,1/16W,CHIP,A 1        SMB_SML1_PMBUS_3V3AUX_PCH_SCL
                                  2        P3V3_AUX                
R1387            Q_RES_0402LF-2K,1%,1/16W,CHIP,A 1        SMB_SML1_PMBUS_3V3AUX_PCH_SDA
                                  2        P3V3_AUX                
R1388            Q_RES_0402LF-2K,1%,1/16W,CHIP,A 1        PWRGD_DRAMPWRGD_CPU1_EF_R_LVC1
                                  2        GND                     
R1389            Q_RES_0402LF-2K,1%,1/16W,CHIP,A 1        PWRGD_DRAMPWRGD_CPU1_GH_R_LVC1
                                  2        GND                     
R1390            Q_RES_0402LF-1K,1%,1/16W,EMPTYA 1        FM_PLD_CLKS_DEV_EN      
                                  2        GND                     
R1391            Q_RES_0402LF-240,1%,1/16W,EMPTA 1        GND                     
                                  2        FM_S3M_CPU0_LVC1_GPIO_2 
R1392            Q_RES_0402LF-240,1%,1/16W,EMPTA 1        GND                     
                                  2        FM_S3M_CPU0_LVC1_GPIO_3 
R1393            Q_RES_0402LF-240,1%,1/16W,EMPTA 1        GND                     
                                  2        FM_S3M_CPU1_LVC1_GPIO_2 
R1394            Q_RES_0402LF-240,1%,1/16W,EMPTA 1        GND                     
                                  2        FM_S3M_CPU1_LVC1_GPIO_3 
R1395            Q_RES_0402LF-33.2,1%,1/16W,CHIA 1        SPI_PCH_TPM_CS_N        
                                  2        SPI_TPM_CS_N            
R1396            Q_RES_0402LF-10K,1%,1/16W,CHIPA 1        FM_M2_SSD_1_PEDET       
                                  2        P3V3_AUX                
R1398            Q_RES_0402LF-2K,1%,1/16W,CHIP,A 1        PWRGD_CPU1_LVC1_R       
                                  2        GND                     
R1399            Q_RES_0402LF-10K,1%,1/16W,CHIPA 1        FM_PFR_DSW_PWROK_N      
                                  2        P3V3_AUX                
R1401            Q_RES_0402LF-10K,1%,1/16W,CHIPA 1        PU_MAIN_FPGA_CONFIG_DONE
                                  2        P3V3_AUX                
R1402            Q_RES_0402LF-2K,1%,1/16W,CHIP,A 1        PWRGD_SYS_PWROK         
                                  2        GND                     
R1403            Q_RES_0402LF-2K,1%,1/16W,CHIP,A 1        PWRGD_PCH_PWROK         
                                  2        GND                     
R1404            Q_RES_0402LF-2K,1%,1/16W,CHIP,A 1        FM_PCH_P1V8_AUX_EN      
                                  2        GND                     
R1405            Q_RES_0402LF-2K,1%,1/16W,CHIP,A 1        FM_PVCCIN_CPU0_R_EN     
                                  2        GND                     
R1406            Q_RES_0402LF-2K,1%,1/16W,CHIP,A 1        FM_PVCCIN_CPU1_R_EN     
                                  2        GND                     
R1407            Q_RES_0402LF-2K,1%,1/16W,CHIP,A 1        FM_PVCCINFAON_CPU0_R_EN 
                                  2        GND                     
R1408            Q_RES_0402LF-2K,1%,1/16W,CHIP,A 1        FM_PVCCINFAON_CPU1_R_EN 
                                  2        GND                     
R1409            Q_RES_0402LF-2K,1%,1/16W,CHIP,A 1        FM_PVCCFA_EHV_CPU0_R_EN 
                                  2        GND                     
R1410            Q_RES_0402LF-2K,1%,1/16W,CHIP,A 1        FM_PVCCFA_EHV_CPU1_R_EN 
                                  2        GND                     
R1411            Q_RES_0402LF-2K,1%,1/16W,CHIP,A 1        FM_PVCCFA_EHV_FIVRA_CPU0_R_EN
                                  2        GND                     
R1412            Q_RES_0402LF-2K,1%,1/16W,CHIP,A 1        FM_PVCCFA_EHV_FIVRA_CPU1_R_EN
                                  2        GND                     
R1413            Q_RES_0402LF-2K,1%,1/16W,CHIP,A 1        FM_PVCCD_HV_CPU0_EN     
                                  2        GND                     
R1414            Q_RES_0402LF-2K,1%,1/16W,CHIP,A 1        FM_PVCCD_HV_CPU1_EN     
                                  2        GND                     
R1415            Q_RES_0402LF-2K,1%,1/16W,CHIP,A 1        RST_CPU0_LVC1_R_N       
                                  2        GND                     
R1416            Q_RES_0402LF-2K,1%,1/16W,CHIP,A 1        RST_CPU1_LVC1_R_N       
                                  2        GND                     
R1417            Q_RES_0402LF-2K,1%,1/16W,CHIP,A 1        RST_PCIE_CPU0_DEV_PERST_N
                                  2        GND                     
R1418            Q_RES_0402LF-2K,1%,1/16W,CHIP,A 1        RST_PCIE_CPU1_DEV_PERST_N
                                  2        GND                     
R1419            Q_RES_0402LF-2K,1%,1/16W,CHIP,A 1        RST_PCIE_PCH_DEV_PERST_N
                                  2        GND                     
R1420            Q_RES_0402LF-2K,1%,1/16W,CHIP,A 1        RST_PLTRST_PLD_B_N      
                                  2        GND                     
R1421            Q_RES_0402LF-2K,1%,1/16W,CHIP,A 1        RST_RSMRST_PLD_R_N      
                                  2        GND                     
R1423            Q_RES_0402LF-33.2,1%,1/16W,CHIA 1        PWRGD_SYS_PWROK_R       
                                  2        PWRGD_SYS_PWROK         
R1425            Q_RES_0402LF-100,1%,1/16W,CHIPA 1        H_CPU0_MEMHOT_OUT_LVC1_N
                                  2        PVCCIO_PLDIO5           
R1426            Q_RES_0402LF-100,1%,1/16W,CHIPA 1        H_CPU1_MEMHOT_OUT_LVC1_N
                                  2        PVCCIO_PLDIO5           
R1427            Q_RES_0402LF-100,1%,1/16W,CHIPA 1        H_CPU0_THERMTRIP_LVC1_N 
                                  2        PVCCIO_PLDIO5           
R1428            Q_RES_0402LF-100,1%,1/16W,CHIPA 1        H_CPU1_THERMTRIP_LVC1_N 
                                  2        PVCCIO_PLDIO5           
R1429            Q_RES_0402LF-100,1%,1/16W,CHIPA 1        H_CPU0_MEMTRIP_LVC1_N   
                                  2        PVCCIO_PLDIO5           
R1430            Q_RES_0402LF-100,1%,1/16W,CHIPA 1        H_CPU1_MEMTRIP_LVC1_N   
                                  2        PVCCIO_PLDIO5           
R1431            Q_RES_0402LF-150,1%,1/16W,CHIPA 1        H_CPU_ERR0_LVC1_N       
                                  2        PVCCIO_PLDIO5           
R1432            Q_RES_0402LF-150,1%,1/16W,CHIPA 1        H_CPU_ERR1_LVC1_N       
                                  2        PVCCIO_PLDIO5           
R1433            Q_RES_0402LF-150,1%,1/16W,CHIPA 1        H_CPU_ERR2_LVC1_N       
                                  2        PVCCIO_PLDIO5           
R1434            Q_RES_0402LF-10K,1%,1/16W,CHIPA 1        FM_SYS_THROTTLE_R_N     
                                  2        P3V3_AUX                
R1435            Q_RES_0402LF-10K,1%,1/16W,CHIPA 1        FM_ADR_TRIGGER_N        
                                  2        P3V3_AUX                
R1436            Q_RES_0402LF-10K,1%,1/16W,CHIPA 1        PU_MAIN_FPGA_STATUS_N   
                                  2        P3V3_AUX                
R1437            Q_RES_0402LF-10K,1%,1/16W,CHIPA 1        FM_PLD_HEARTBEAT_LVC3   
                                  2        P3V3_AUX                
R1438            Q_RES_0402LF-10K,1%,1/16W,CHIPA 1        JTAG_PLD_TDI_R          
                                  2        P3V3_AUX                
R1439            Q_RES_0402LF-10K,1%,1/16W,CHIPA 1        JTAG_PLD_TMS_R          
                                  2        P3V3_AUX                
R1440            Q_RES_0402LF-10K,1%,1/16W,EMPTA 1        JTAG_PLD_TDO_R          
                                  2        P3V3_AUX                
R1441            Q_RES_0402LF-1K,1%,1/16W,CHIP,A 1        JTAG_PLD_TCK_R          
                                  2        GND                     
R1442            Q_RES_0402LF-33.2,1%,1/16W,CHIA 1        PWRGD_PCH_PWROK_R       
                                  2        PWRGD_PCH_PWROK         
R1443            Q_RES_0402LF-33.2,1%,1/16W,CHIA 1        PWRGD_CPUPWRGD_LVC1     
                                  2        PWRGD_CPUPWRGD_LVC1_R   
R1444            Q_RES_0402LF-33.2,1%,1/16W,CHIA 1        PWRGD_P1V8_PCH_AUX      
                                  2        PWRGD_P1V8_PCH_AUX_PLD  
R1445            Q_RES_0402LF-2K,1%,1/16W,CHIP,A 1        FM_PVNN_MAIN_CPU0_EN    
                                  2        GND                     
R1446            Q_RES_0402LF-33.2,1%,1/16W,CHIA 1        PWRGD_PS_PWROK_PLD      
                                  2        PWRGD_PS_PWROK_PLD_R    
R1447            Q_RES_0402LF-33.2,1%,1/16W,CHIA 1        FM_CPU0_SKTOCC_LVT3_N   
                                  2        FM_CPU0_SKTOCC_LVT3_PLD_N
R1448            Q_RES_0402LF-33.2,1%,1/16W,CHIA 1        FM_CPU1_SKTOCC_LVT3_N   
                                  2        FM_CPU1_SKTOCC_LVT3_PLD_N
R1449            Q_RES_0402LF-10K,1%,1/16W,CHIPA 1        P3V3_AUX                
                                  2        FM_BIOS_POST_CMPLT_N    
R1450            Q_RES_0402LF-10K,1%,1/16W,CHIPA 1        P3V3_AUX                
                                  2        FM_THROTTLE_N           
R1451            Q_RES_0402LF-2K,1%,1/16W,CHIP,A 1        PU_SMB_SML3_3V3AUX_PCH_SCL
                                  2        P3V3_AUX                
R1452            Q_RES_0402LF-2K,1%,1/16W,CHIP,A 1        PU_SMB_SML3_3V3AUX_PCH_SDA
                                  2        P3V3_AUX                
R1453            Q_RES_0402LF-2K,1%,1/16W,CHIP,A 1        PU_SMB_SML4_3V3AUX_PCH_SCL
                                  2        P3V3_AUX                
R1454            Q_RES_0402LF-2K,1%,1/16W,CHIP,A 1        PU_SMB_SML4_3V3AUX_PCH_SDA
                                  2        P3V3_AUX                
R1455            Q_RES_0402LF-49.9     ,1%  ,1/A 1        FM_ADR_MODE0_R          
                                  2        FM_ADR_MODE0            
R1456            Q_RES_0402LF-49.9     ,1%  ,1/A 1        FM_CPU_RMCA_CATERR_DLY_LVT3_R_N
                                  2        FM_CPU_RMCA_CATERR_DLY_N
R1457            Q_RES_0402LF-10K,1%,1/16W,CHIPA 1        FM_XTAL_INPUT_FREQUENCY_1_MGPIO
                                  2        GND                     
R1458            Q_RES_0402LF-10K,1%,1/16W,CHIPA 1        P3V3_AUX                
                                  2        IRQ_SMI_ACTIVE_N        
R1459            Q_RES_0402LF-10K,1%,1/16W,CHIPA 1        P3V3_AUX                
                                  2        IRQ_PCH_CPU_NMI_EVENT_R_N
R1460            Q_RES_0402LF-2.2K ,5%,1/16W,CHA 1        SMB_SENSOR_3V3AUX_SDA   
                                  2        P3V3_AUX                
R1461            Q_RES_0402LF-0,5%,1/16W,CHIP,CA 1        FM_EUP_LOT6_N           
                                  2        FM_SUSACK_N             
R1462            Q_RES_0402LF-1K,1%,1/16W,CHIP,A 1        PD_CK440_SBI_CLK        
                                  2        GND                     
R1463            Q_RES_0402LF-0,5%,1/16W,CHIP,CA 1        P1V05_PCH_AUX           
                                  2        P1V05_PCH_PLL_AUX       
R1464            Q_RES_0402LF-0,5%,1/16W,CHIP,CA 1        P1V8_PCH_AUX            
                                  2        P1V8_PCH_PLL_AUX        
R1465            Q_RES_0402LF-10K,1%,1/16W,EMPTA 1        P3V3_AUX                
                                  2        IRQ_BMC_CPU_NMI_R1      
R1467            Q_RES_0402LF-4.7K,1%,1/16W,CHIA 1        P3V3_AUX                
                                  2        SMB_PLD_3V3AUX_SDA_R    
R1469            Q_RES_0402LF-33.2,1%,1/16W,CHIA 1        RST_PLTRST_PLD_B_N      
                                  2        RST_PLTRST_B_N          
R1470            Q_RES_0402LF-33.2,1%,1/16W,CHIA 1        RST_PLTRST_PLD_B_N      
                                  2        RST_PLTRST_B_MUX_N      
R1471            Q_RES_0402LF-4.75K,1%,1/16W,CHA 1        P3V3_AUX                
                                  2        FM_CLK_CK440_SS_EN      
R1472            Q_RES_0402LF-33.2,1%,1/16W,CHIA 1        JTAG_DBP_PRESENT_R_N    
                                  2        FM_BMC_DBP_PRESENT_R_N  
R1473            Q_RES_0402LF-1K,1%,1/16W,CHIP,A 1        FM_RST_PERST_BIT1       
                                  2        P3V3_AUX                
R1474            Q_RES_0402LF-1K,1%,1/16W,CHIP,A 1        FM_RST_PERST_BIT2       
                                  2        P3V3_AUX                
R1475            Q_RES_0402LF-1K,1%,1/16W,EMPTYA 1        P3V3_AUX                
                                  2        FM_PCH_RING_OSC_BYPASS_MGPIO_TE
R1476            Q_RES_0402LF-1K,1%,1/16W,CHIP,A 1        FM_PCH_RING_OSC_BYPASS_MGPIO_TE
                                  2        GND                     
R1477            Q_RES_0402LF-1K,1%,1/16W,EMPTYA 1        P3V3_AUX                
                                  2        FM_PCH_XTAL_INPUT_MODE_MGPIO_TE
R1478            Q_RES_0402LF-10K,1%,1/16W,CHIPA 1        FM_PCH_XTAL_INPUT_MODE_MGPIO_TE
                                  2        GND                     
R1479            Q_RES_0402LF-33.2,1%,1/16W,CHIA 1        ESPI_LFRAME_N_BMC_CS0_N 
                                  2        ESPI_HOST_LPC_BMC_LFRAME_N
R1481            Q_RES_0402LF-33.2,1%,1/16W,CHIA 1        IRQ_LVC3_WAKE_N         
                                  2        IRQ_LVC3_WAKE_R2_N      
R1482            Q_RES_0402LF-33.2,1%,1/16W,CHIA 1        IRQ_LVC3_WAKE_R3_N      
                                  2        IRQ_LVC3_WAKE_N         
R1483            Q_RES_0402LF-10K,1%,1/16W,EMPTA 1        P3V3_AUX                
                                  2        FM_CK440Q_DEV_25M_EN    
R1484            Q_RES_0402LF-1K,1%,1/16W,EMPTYA 1        FM_CK440Q_DEV_25M_EN    
                                  2        GND                     
R1485            Q_RES_0402LF-200,1%,1/16W,EMPTA 1        PVNN_TERM_CPU0          
                                  2        FM_PCH_TRIGGER0_R_N     
R1486            Q_RES_0402LF-200,1%,1/16W,EMPTA 1        PVNN_TERM_CPU0          
                                  2        FM_PCH_TRIGGER1_R_N     
R1487            Q_RES_0402LF-100,1%,1/16W,CHIPA 1        FM_PCH_SATA_RAID_KEY    
                                  2        GND                     
R1488            Q_RES_0402LF-10K,1%,1/16W,CHIPA 1        PU_MAIN_FPGA_CONFIG_N   
                                  2        P3V3_AUX                
R1491            Q_RES_0402LF-1K,1%,1/16W,CHIP,A 1        PD_MAIN_FPGA_CONFIG_SEL 
                                  2        GND                     
R1492            Q_RES_0402LF-10K,1%,1/16W,EMPTA 1        FM_DIS_PS_PWROK_DLY     
                                  2        P3V3_AUX                
R1493            Q_RES_0402LF-1K,1%,1/16W,EMPTYA 1        FM_FORCE_PWRON_LVC3     
                                  2        P3V3_AUX                
R1494            Q_RES_0402LF-1K,1%,1/16W,CHIP,A 1        FM_DIS_PS_PWROK_DLY     
                                  2        GND                     
R1495            Q_RES_0402LF-10K,1%,1/16W,CHIPA 1        FM_FORCE_PWRON_LVC3     
                                  2        GND                     
R1496            Q_RES_0402LF-10K,1%,1/16W,CHIPA 1        P3V3_AUX                
                                  2        FM_PCH_DFXTESTMODE      
R1497            Q_RES_0402LF-12K,1%,1/16W,EMPTA 1        FM_PCH_DFXTESTMODE      
                                  2        GND                     
R1498            Q_RES_0402LF-1K,1%,1/16W,EMPTYA 1        P3V3_AUX                
                                  2        FM_BIOS_ADV_FUNCTIONS   
R1499            Q_RES_0402LF-1K,1%,1/16W,CHIP,A 1        FM_BIOS_ADV_FUNCTIONS   
                                  2        GND                     
R1500            Q_RES_0402LF-4.75K,1%,1/16W,CHA 1        PD_CK440_SBI_DATA_IN    
                                  2        GND                     
R1502            Q_RES_0402LF-4.75K,1%,1/16W,CHA 1        FM_CLK_CK440_SS_EN      
                                  2        GND                     
R1504            Q_RES_0402LF-33.2,1%,1/16W,CHIA 1        RST_OCP_V3_1_BUF_N      
                                  2        RST_PERST2_OCP_SFF_N    
R1505            Q_RES_0402LF-33.2,1%,1/16W,CHIA 1        RST_OCP_V3_1_BUF_N      
                                  2        RST_PERST3_OCP_SFF_N    
R1512            Q_RES_0402LF-33.2,1%,1/16W,CHIA 1        RST_PCIE_CPU0_DEV_PERST_N
                                  2        RST_PCIE_EDSFF2A_PERST_N
R1513            Q_RES_0402LF-33.2,1%,1/16W,CHIA 1        RST_PCIE_CPU0_DEV_PERST_N
                                  2        RST_PCIE_RISER2_N       
R1514            Q_RES_0402LF-33.2,1%,1/16W,CHIA 1        RST_PCIE_CPU0_DEV_PERST_N
                                  2        RST_OCP_V3_1_N          
R1515            Q_RES_0402LF-33.2,1%,1/16W,CHIA 1        RST_PCIE_CPU0_DEV_PERST_N
                                  2        RST_PCIE_EDSFF1A_PERST_N
R1516            Q_RES_0402LF-33.2,1%,1/16W,CHIA 1        RST_PCIE_CPU0_DEV_PERST_N
                                  2        RST_PCIE_EDSFF1B_PERST_N
R1518            Q_RES_0402LF-33.2,1%,1/16W,CHIA 1        RST_PCIE_CPU1_DEV_PERST_N
                                  2        RST_PCIE_RISER3_N       
R1519            Q_RES_0402LF-33.2,1%,1/16W,CHIA 1        RST_PCIE_CPU1_DEV_PERST_N
                                  2        RST_PCIE_EDSFF4B_PERST_N
R1520            Q_RES_0402LF-33.2,1%,1/16W,CHIA 1        RST_PCIE_CPU1_DEV_PERST_N
                                  2        RST_PCIE_EDSFF3_PERST_N 
R1521            Q_RES_0402LF-33.2,1%,1/16W,CHIA 1        RST_PCIE_CPU1_DEV_PERST_N
                                  2        RST_PCIE_EDSFF4A_PERST_N
R1522            Q_RES_0402LF-10K,1%,1/16W,CHIPA 1        P3V3_AUX                
                                  2        PU_RST_SMB_EDSFF_N      
R1525            Q_RES_0402LF-0,5%,1/16W,CHIP,CA 1        SMB_HOST_3V3AUX_SCL_R   
                                  2        SMB_HOST_CLK_3V3AUX_SCL 
R1526            Q_RES_0402LF-33.2,1%,1/16W,CHIA 1        SMB_HOST_3V3AUX_SDA_R   
                                  2        SMB_HOST_CLK_3V3AUX_SDA 
R1527            Q_RES_0402LF-1K,1%,1/16W,CHIP,A 1        FM_CLK_GEN1_OE0_N       
                                  2        GND                     
R1528            Q_RES_0402LF-4.7K,5%,1/16W,EMPA 1        JTAG_RISER2_TDO         
                                  2        P3V3_AUX                
R1529            Q_RES_0402LF-4.7K,5%,1/16W,EMPA 1        JTAG_RISER2_TMS         
                                  2        P3V3_AUX                
R1530            Q_RES_0402LF-4.7K,5%,1/16W,EMPA 1        JTAG_RISER2_TCK         
                                  2        GND                     
R1531            Q_RES_0402LF-4.7K,5%,1/16W,EMPA 1        JTAG_RISER2_TRST_N      
                                  2        GND                     
R1532            Q_RES_0402LF-4.7K,5%,1/16W,EMPA 1        JTAG_RISER3_TDI         
                                  2        P3V3_AUX                
R1533            Q_RES_0402LF-4.7K,5%,1/16W,EMPA 1        JTAG_RISER3_TDO         
                                  2        P3V3_AUX                
R1534            Q_RES_0402LF-4.7K,5%,1/16W,EMPA 1        JTAG_RISER3_TMS         
                                  2        P3V3_AUX                
R1535            Q_RES_0402LF-4.7K,5%,1/16W,EMPA 1        JTAG_RISER3_TCK         
                                  2        GND                     
R1536            Q_RES_0402LF-4.7K,5%,1/16W,EMPA 1        JTAG_RISER3_TRST_N      
                                  2        GND                     
R1537            Q_RES_0402LF-33.2,1%,1/16W,CHIA 1        SMB_SML1_PMBUS_3V3AUX_PCH_SCL
                                  2        SMB_PMBUS_PSU1_SCL      
R1538            Q_RES_0402LF-33.2,1%,1/16W,CHIA 1        SMB_SML1_PMBUS_3V3AUX_PCH_SDA
                                  2        SMB_PMBUS_PSU1_SDA      
R1539            Q_RES_0402LF-10K,1%,1/16W,CHIPA 1        FM_PSU_THROTTLE_L       
                                  2        GND                     
R1540            Q_RES_0402LF-100K,1%,1/16W,EMPB 1        P3V3_AUX                
                                  2        FM_PSU_THROTTLE_N       
R1541            Q_RES_0402LF-100K,1%,1/16W,CHIA 1        GND                     
                                  2        RST_PLTRST_N            
R1542            Q_RES_0402LF-10K,1%,1/16W,CHIPA 1        P3V3                    
                                  2        EDSFF1A_PERST1_CLKREQ_N 
R1543            Q_RES_0402LF-0,5%,1/16W,CHIP,CA 1        HP_LVC3_OCP_V3_1_PRSNT2_N
                                  2        FM_DB2000_8_OE_N        
R1544            Q_RES_0402LF-0,5%,1/16W,CHIP,CA 1        EDSFF1A_PERST1_CLKREQ_N 
                                  2        FM_DB2000_12_OE_N       
R1545            Q_RES_0402LF-2K,1%,1/16W,CHIP,A 1        SMB_SML0B_3V3AUX_SCL    
                                  2        P3V3_AUX                
R1546            Q_RES_0402LF-2K,1%,1/16W,CHIP,A 1        SMB_SML0B_3V3AUX_SDA    
                                  2        P3V3_AUX                
R1547            Q_RES_0402LF-0,5%,1/16W,CHIP,CA 1        FM_TPM_PRSNT_R_N        
                                  2        FM_TPM_PRSNT_N          
R1549            Q_RES_0402LF-4.7K,1%,1/16W,CHIA 1        P3V3_AUX                
                                  2        SMB_PCIE_3V3AUX_SDA     
R1550            Q_RES_0402LF-4.7K,1%,1/16W,CHIA 1        P3V3_AUX                
                                  2        SMB_PCIE_3V3AUX_SCL     
R1551            Q_RES_0402LF-4.7K,1%,1/16W,CHIA 1        P3V3_AUX                
                                  2        SMB_PLD_3V3AUX_SCL_R    
R1554            Q_RES_0402LF-10K,1%,1/16W,CHIPA 1        P3V3_AUX                
                                  2        FM_ME_AUTHN_FAIL        
R1558            Q_RES_0402LF-10K,1%,1/16W,CHIPA 1        FM_CPU_RMCA_CATERR_LVT3_R_N
                                  2        P3V3_AUX                
R1559            Q_RES_0402LF-0,5%,1/16W,EMPTY,A 1        SMB_PCIE_3V3AUX_B_SDA   
                                  2        SMB_PCIE_3V3AUX_SDA     
R1560            Q_RES_0402LF-0,5%,1/16W,EMPTY,A 1        SMB_PCIE_3V3AUX_B_SCL   
                                  2        SMB_PCIE_3V3AUX_SCL     
R1573            Q_RES_0402LF-0,5%,1/16W,CHIP,CA 1        FM_SYS_THROTTLE_R_N     
                                  2        FM_RISER2_PWRBRK_N      
R1574            Q_RES_0402LF-100,1%,1/16W,CHIPA 1        PD_RISER2_PRSNT1        
                                  2        GND                     
R1575            Q_RES_0402LF-10K,5%,1/16W,CHIPA 1        P3V3_AUX                
                                  2        RISER2_CLK3_EN_N        
R1576            Q_RES_0402LF-10K,5%,1/16W,CHIPA 1        P3V3_AUX                
                                  2        RISER2_CLK2_EN_N        
R1577            Q_RES_0402LF-0,5%,1/16W,CHIP,CA 1        FM_SYS_THROTTLE_R_N     
                                  2        FM_RISER3_PWRBRK_N      
R1578            Q_RES_0402LF-100,1%,1/16W,CHIPA 1        PD_RISER3_PRSNT1        
                                  2        GND                     
R1579            Q_RES_0402LF-10K,5%,1/16W,CHIPA 1        P3V3_AUX                
                                  2        RISER3_CLK4_EN_N        
R1580            Q_RES_0402LF-10K,5%,1/16W,CHIPA 1        P3V3_AUX                
                                  2        RISER3_CLK5_EN_N        
R1581            Q_RES_0402LF-2K,1%,1/16W,CHIP,A 1        PU_SMB_PCH_PLD_3V3AUX_SCL
                                  2        P3V3_AUX                
R1582            Q_RES_0402LF-2K,1%,1/16W,CHIP,A 1        PU_SMB_PCH_PLD_3V3AUX_SDA
                                  2        P3V3_AUX                
R1583            Q_RES_0402LF-10K,1%,1/16W,CHIPA 1        PU_PCH_PLD_3V3AUX_ALERT_N
                                  2        P3V3_AUX                
R1584            Q_RES_0402LF-10K,5%,1/16W,EMPTA 1        P3V3_AUX                
                                  2        FM_SYS_THROTTLE_R_N     
R1585            Q_RES_0402LF-0,5%,1/16W,CHIP,CA 1        FM_SYS_THROTTLE_R_N     
                                  2        FM_EDSFF2A_PWRBRK_N     
R1586            Q_RES_0402LF-10K,5%,1/16W,EMPTA 1        P3V3_AUX                
                                  2        FM_SYS_THROTTLE_R_N     
R1587            Q_RES_0402LF-0,5%,1/16W,CHIP,CA 1        FM_SYS_THROTTLE_R_N     
                                  2        FM_EDSFF2B_PWRBRK_N     
R1588            Q_RES_0402LF-10K,5%,1/16W,EMPTA 1        P3V3_AUX                
                                  2        FM_SYS_THROTTLE_R_N     
R1589            Q_RES_0402LF-0,5%,1/16W,CHIP,CA 1        FM_SYS_THROTTLE_R_N     
                                  2        FM_EDSFF3_PWRBRK_N      
R1592            Q_RES_0402LF-10K,1%,1/16W,CHIPA 1        P3V3_OCP_SFF            
                                  2        PU_OCP_SFF_WAKE_OE      
R1593            Q_RES_0402LF-4.7K,1%,1/16W,EMPA 1        P3V3_AUX                
                                  2        OCP_SFF_PWRBRK_BUFF_N   
R1594            Q_RES_0402LF-33.2,1%,1/16W,CHIA 1        OCP_SFF_WAKE_BUFF_N     
                                  2        IRQ_LVC3_WAKE_N         
R1595            Q_RES_0402LF-33.2,1%,1/16W,CHIA 1        OCP_SFF_PWRBRK_BUFF_N   
                                  2        OCP_SFF_PWRBRK_N        
R1600            Q_RES_0402LF-33,5%,1/16W,CHIP,A 1        IRQ_SML0_ALERT_N        
                                  2        IRQ_SML0_ALERT_R_N      
R1601            Q_RES_0402LF-10K,1%,1/16W,CHIPA 1        IRQ_SML0_ALERT_N        
                                  2        P3V3_AUX                
R1605            Q_RES_0402LF-1K,1%,1/16W,CHIP,A 1        PD_M2_1_DEVSLP          
                                  2        GND                     
R1606            Q_RES_0402LF-0,5%,1/16W,CHIP,CA 1        FM_OCP_SFF_PWR_GOOD     
                                  2        FM_OCP_SFF_PWR_GOOD_R   
R1607            Q_RES_0402LF-0,5%,1/16W,CHIP,CA 1        FM_PS_EN_PLD_R          
                                  2        VR_P5V_EN               
R1608            Q_RES_0402LF-4.7K,1%,1/16W,EMPA 1        P3V3_AUX                
                                  2        IRQ_PSU_ALERT_N         
R1609            Q_RES_0402LF-10K,1%,1/16W,CHIPA 1        P3V3_AUX                
                                  2        FM_EDSFF2A_TYPE_ID      
R1610            Q_RES_0402LF-10K,1%,1/16W,CHIPA 1        P3V3_AUX                
                                  2        FM_EDSFF2B_TYPE_ID      
R1613            Q_RES_0402LF-4.7K,5%,1/16W,CHIA 1        RST_SMB_EDSFF2A_N       
                                  2        P3V3_AUX                
R1614            Q_RES_0402LF-100,1%,1/16W,CHIPA 1        PD_PCIE_EDSFF2A_PRSNT_0_N
                                  2        GND                     
R1615            Q_RES_0402LF-4.7K,5%,1/16W,CHIA 1        RST_SMB_EDSFF2B_N       
                                  2        P3V3_AUX                
R1616            Q_RES_0402LF-100,1%,1/16W,CHIPA 1        PD_PCIE_EDSFF2B_PRSNT_0_N
                                  2        GND                     
R1617            Q_RES_0402LF-4.7K,5%,1/16W,CHIA 2        P3V3_AUX                
R1618            Q_RES_0402LF-100,1%,1/16W,CHIPA 1        EDSFF3_PRSNT_0_N        
                                  2        GND                     
R1640            Q_RES_0402LF-0,5%,1/16W,EMPTY,A 1        FM_P5V_EN               
                                  2        VR_P5V_EN               
R1641            Q_RES_0402LF-100,1%,1/16W,CHIPA 1        VR_P5V_EN               
                                  2        GND                     
R1642            Q_RES_0402LF-10K,5%,1/16W,CHIPA 1        P12V_AUX                
                                  2        VR_P5V_EN_D_R           
R1643            Q_RES_0402LF-100K,5%,1/16W,CHIA 1        P12V_AUX                
                                  2        VR_P5V_EN_N             
R1645            Q_RES_0402LF-4.7K,5%,1/16W,EMPA 1        P3V3_AUX                
                                  2        FM_FAN_ID               
R1646            Q_RES_0402LF-4.7K,5%,1/16W,CHIA 1        FM_FAN_ID               
                                  2        GND                     
R1648            Q_RES_0402LF-0,5%,1/16W,EMPTY,A 1        SMB_S3M_CPU0_3V3AUX_SDA 
                                  2        SMB_S3M_CPU1_3V3AUX_SDA 
R1649            Q_RES_0402LF-2K,1%,1/16W,CHIP,A 1        FM_P1V05_PCH_AUX_R_EN   
                                  2        GND                     
R1652            Q_RES_0402LF-0,5%,1/16W,CHIP,CA 1        PWRGD_PVNN_MAIN_CPU0_R  
                                  2        PWRGD_PVNN_MAIN_CPU0    
R1654            Q_RES_0402LF-1K,5%,1/16W,CHIP,A 1        VR_P5V_EN_D_R           
                                  2        VR_P5V_EN_D_R1          
R1655            Q_RES_0402LF-10K,5%,1/16W,CHIPA 1        P5V                     
                                  2        PWRGD_P5V               
R1656            Q_RES_0402LF-33,5%,1/16W,CHIP,A 1        IRQ_SML1_PMBUS_ALERT_N  
                                  2        IRQ_SML1_PMBUS_PLD_ALERT_N
R1657            Q_RES_0402LF-33,5%,1/16W,CHIP,A 1        IRQ_SML1_PMBUS_ALERT_N  
                                  2        IRQ_SML1_PMBUS_BMC_ALERT_N
R1658            Q_RES_0402LF-10K,1%,1/16W,CHIPA 1        IRQ_SML1_PMBUS_ALERT_N  
                                  2        P3V3_AUX                
R1659            Q_RES_0402LF-10K,1%,1/16W,CHIPA 1        FM_PMBUS_ALERT_B_EN     
                                  2        P3V3_AUX                
R1660            Q_RES_0402LF-10K,1%,1/16W,EMPTA 1        FM_SLP_SUS_RSM_RST_N    
                                  2        P3V3_AUX                
R1661            Q_RES_0402LF-33,5%,1/16W,CHIP,A 1        SMB_VR_3V3AUX_SCL       
                                  2        SMB_VR_3V3AUX_SCL_R     
R1662            Q_RES_0402LF-33,5%,1/16W,CHIP,A 1        SMB_VR_3V3AUX_SDA       
                                  2        SMB_VR_3V3AUX_SDA_R     
R1667            Q_RES_0402LF-10K,1%,1/16W,CHIPA 1        P3V3_AUX                
                                  2        PU_RST_SMB_PCIE3_N      
R1671            Q_RES_0402LF-0,5%,1/16W,CHIP,CA 1        OCP_SFF_AUX_PWR_EN      
                                  2        OCP_SFF_AUX_PWR_EN_R    
R1673            Q_RES_0402LF-10K,1%,1/16W,EMPTA 1        P3V3_E1S_0              
                                  2        RST_SMB_E1S_0_N         
R1675            Q_RES_0402LF-2.49K,1%,1/16W,CHA 1        FM_PCIE_EV_BIF_EN       
                                  2        P3V3_AUX                
R1676            Q_RES_0402LF-1K,1%,1/16W,EMPTYA 1        FM_PCIE_EV_BIF_EN       
                                  2        GND                     
R1680            Q_RES_0402LF-0,5%,1/16W,CHIP,CA 1        FM_PLD_CLK_25M_EN       
                                  2        FM_CK440Q_DEV_25M_EN    
R1681            Q_RES_0402LF-10K,1%,1/16W,CHIPA 1        P3V3_AUX                
                                  2        PU_RST_DEDI_BUSY_PLD_N  
R1682            Q_RES_0402LF-10K,5%,1/16W,CHIPA 1        PWRGD_P3V3_R            
                                  2        PWRGD_P3V3              
R1688            Q_RES_0402LF-100K,1%,1/16W,CHIA 1        P12V_AUX                
                                  2        FM_COMP_P3V3_AUX_VIN    
R1689            Q_RES_0402LF-6.19K,1%,1/16W,CHA 1        FM_COMP_P3V3_AUX_VIN    
                                  2        GND                     
R1690            Q_RES_0402LF-10K,1%,1/16W,CHIPA 1        P3V3_AUX                
                                  2        FM_COMP_P3V3_AUX_ENIN   
R1691            Q_RES_0402LF-10K,1%,1/16W,EMPTA 1        P3V3_AUX                
                                  2        PWRGD_DSW_PWROK_R1      
R1692            Q_RES_0402LF-100K,1%,1/16W,CHIA 1        PWRGD_DSW_PWROK_R1      
                                  2        GND                     
R1693            Q_RES_0402LF-33.2,1%,1/16W,CHIA 1        PWRGD_DSW_PWROK_R2      
                                  2        PWRGD_DSW_PWROK         
R1694            Q_RES_0402LF-10K,1%,1/16W,CHIPA 1        P3V3_AUX                
                                  2        PWRGD_DSW_PWROK         
R1695            Q_RES_0402LF-0,5%,1/16W,EMPTY,A 1        PWRGD_DSW_PWROK         
                                  2        RST_RSMRST_PCH_N        
R1697            Q_RES_0402LF-10K,1%,1/16W,CHIPA 1        PGPPA_AUX               
                                  2        M2_SSD0_CLKREQ_LV_EN_N  
R1698            Q_RES_0402LF-20K,5%,1/16W,CHIPA 1        PWRGD_P3V3              
                                  2        GND                     
R1700            Q_RES_0402LF-4.7K,5%,1/16W,CHIA 1        P1V8_PCH_AUX            
                                  2        SMB_PCIE_M2_EN          
R1701            Q_RES_0402LF-100K,1%,1/16W,EMPB 1        SMB_PCIE_M2_EN          
                                  2        GND                     
R1702            Q_RES_0402LF-4.7K,5%,1/16W,CHIA 1        P1V8_PCH_AUX            
                                  2        SMB_M2_P0_1V8AUX_SDA    
R1703            Q_RES_0402LF-4.7K,5%,1/16W,CHIA 1        P1V8_PCH_AUX            
                                  2        SMB_M2_P0_1V8AUX_SCL    
R1706            Q_RES_0402LF-4.7K,5%,1/16W,EMPA 1        P3V3                    
                                  2        PWRGD_P3V3              
R1710            Q_RES_0402LF-49.9     ,1%  ,1/A 1        FM_PLD_REV_R_N          
                                  2        FM_PLD_REV_N            
R1712            Q_RES_0402LF-1K,1%,1/16W,CHIP,A 1        SMB_VR_3V3AUX_SDA_R     
                                  2        P3V3_AUX                
R1713            Q_RES_0402LF-1K,1%,1/16W,CHIP,A 1        SMB_VR_3V3AUX_SCL_R     
                                  2        P3V3_AUX                
R1717            Q_RES_0402LF-49.9     ,1%  ,1/A 1        PVNN_TERM_CPU0          
                                  2        SVID_CLK1_CPU0_R        
R1719            Q_RES_0402LF-33.2,1%,1/16W,CHIA 1        OCP_SFF_AUX_PWR_EN      
                                  2        OCP_SFF_AUX_PWR_EN_R1   
R1720            Q_RES_0402LF-0,5%,1/16W,EMPTY,A 1        XTAL_PCH_25M_IN_R       
                                  2        XTAL_PCH_25M_IN         
R1721            Q_RES_0402LF-0,5%,1/16W,CHIP,CA 1        XTAL_PCH_RTC2_R         
                                  2        XTAL_PCH_RTC2           
R1724            Q_RES_0402LF-0,5%,1/16W,CHIP,CA 1        XTAL_CLK_GEN1_25M_X1_R  
                                  2        XTAL_CLK_GEN1_25M_X1    
R1731            Q_RES_0402LF-2K,1%,1/16W,CHIP,A 1        SMB_VR_3V3AUX_SCL       
                                  2        P3V3_AUX                
R1732            Q_RES_0402LF-2K,1%,1/16W,CHIP,A 1        SMB_VR_3V3AUX_SDA       
                                  2        P3V3_AUX                
R1735            Q_RES_0402LF-100,1%,1/16W,CHIPA 1        PVNN_TERM_CPU0          
                                  2        SVID_DIO1_CPU0_R        
R1736            Q_RES_0402LF-0,5%,1/16W,CHIP,CA 1        FM_PCH_SLP_SUS_N        
                                  2        FM_SLP_SUS_RSM_RST_N    
R1738            Q_RES_0402LF-100,1%,1/16W,CHIPA 1        PD_MAIN_FPGA_N13        
                                  2        GND                     
R1739            Q_RES_0402LF-100,1%,1/16W,CHIPA 1        PD_MAIN_FPGA_F7         
                                  2        GND                     
R1741            Q_RES_0402LF-1K,1%,1/16W,CHIP,A 1        FM_RST_PERST_BIT0       
                                  2        P3V3_AUX                
R1742            Q_RES_0402LF-10K,1%,1/16W,EMPTA 1        FM_RST_PERST_BIT0       
                                  2        GND                     
R1744            Q_RES_0402LF-0,5%,1/16W,CHIP,CA 1        FM_BMC_PWRBTN_OUT_N     
                                  2        FM_BMC_PWRBTN_N         
R1745            Q_RES_0402LF-0,5%,1/16W,EMPTY,A 1        FM_COMP_P3V3_AUX_ENIN   
                                  2        FM_PFR_DSW_PWROK_N      
R1747            Q_RES_0805LF-0,5%,1/8W,CHIP,CSA 1        P1V8_PCH_AUX            
                                  2        PGPPA_AUX               
R1748            Q_RES_0402LF-0,5%,1/16W,CHIP,CA 1        FM_ESPI_PLD_EN          
                                  2        FM_ESPI_PLD_R_EN        
R1749            Q_RES_0402LF-10K,1%,1/16W,EMPTA 1        FM_ESPI_PLD_R_EN        
                                  2        GND                     
R1750            Q_RES_0402LF-1K,1%,1/16W,CHIP,A 1        PGPPA_AUX               
                                  2        FM_ESPI_PLD_R_EN        
R1751            Q_RES_0402LF-33.2,1%,1/16W,CHIA 1        SGPIO_DO_0              
                                  2        SGPIO_BMC_DOUT          
R1752            Q_RES_0402LF-33.2,1%,1/16W,CHIA 1        SGPIO_CLK_0             
                                  2        SGPIO_BMC_CLK           
R1753            Q_RES_0402LF-33.2,1%,1/16W,CHIA 1        SGPIO_DI_0              
                                  2        SGPIO_BMC_DIN_R         
R1754            Q_RES_0402LF-33.2,1%,1/16W,CHIA 1        SGPIO_LD_0              
                                  2        SGPIO_BMC_LD_N          
R1755            Q_RES_0402LF-33.2,1%,1/16W,CHIA 1        SGPIO_DO_1              
                                  2        SGPIO_DEBUG_PLD_DOUT    
R1756            Q_RES_0402LF-33.2,1%,1/16W,CHIA 1        SGPIO_CLK_1             
                                  2        SGPIO_DEBUG_PLD_CLK     
R1757            Q_RES_0402LF-33.2,1%,1/16W,CHIA 1        SGPIO_DI_1              
                                  2        SGPIO_DEBUG_PLD_DIN     
R1758            Q_RES_0402LF-33.2,1%,1/16W,CHIA 1        SGPIO_LD_1              
                                  2        SGPIO_DEBUG_PLD_LD_N    
R1759            Q_RES_0402LF-0,5%,1/16W,EMPTY,A 1        SMB_S3M_CPU0_3V3AUX_SCL 
                                  2        SMB_S3M_CPU0_LVC1_SCL   
R1760            Q_RES_0402LF-0,5%,1/16W,EMPTY,A 1        SMB_S3M_CPU0_3V3AUX_SDA 
                                  2        SMB_S3M_CPU0_LVC1_SDA   
R1761            Q_RES_0402LF-33,5%,1/16W,CHIP,A 1        SMB_PLD_3V3AUX_SCL      
                                  2        SMB_PLD_3V3AUX_SCL_R    
R1762            Q_RES_0402LF-33,5%,1/16W,CHIP,A 1        SMB_PLD_3V3AUX_SDA      
                                  2        SMB_PLD_3V3AUX_SDA_R    
R1763            Q_RES_0402LF-10K,1%,1/16W,EMPTA 1        PGPPA_AUX               
                                  2        FM_LPC_ESPI_SEL         
R1764            Q_RES_0402LF-1K,1%,1/16W,EMPTYA 1        FM_LPC_ESPI_SEL         
                                  2        GND                     
R1765            Q_RES_0805LF-0,5%,1/8W,EMPTY,CA 1        PGPPA_AUX               
                                  2        P3V3_AUX                
R1778            Q_RES_0402LF-0,5%,1/16W,EMPTY,A 1        M2_SSD0_CLKREQ_EN_N     
                                  2        M2_SSD0_CLKREQ_LV_EN_N  
R1784            Q_RES_0402LF-4.7K,1%,1/16W,EMPA 1        P3V3_AUX                
                                  2        VOL_SEN_ADDR            
R1785            Q_RES_0402LF-4.7K,1%,1/16W,CHIA 1        VOL_SEN_ADDR            
                                  2        GND                     
R1786            Q_RES_0402LF-0,1%,1/16W,CHIP,TA 1        P3V3_AUX                
                                  2        P3V3_AUX_SENSE          
R1787            Q_RES_0402LF-1K,0.1%,1/16W,CHIA 1        P3V3_AUX_SENSE          
                                  2        GND                     
R1788            Q_RES_0402LF-0,1%,1/16W,CHIP,TA 1        P3V3                    
                                  2        P3V3_SENSE              
R1789            Q_RES_0402LF-1K,0.1%,1/16W,CHIA 1        P3V3_SENSE              
                                  2        GND                     
R1790            Q_RES_0402LF-1K,1%,1/16W,EMPTYA 1        P3V_BAT                 
                                  2        P3V3_RTC_AUX_SENSE      
R1791            Q_RES_0402LF-200K,1%,1/16W,CHIA 1        P3V3_RTC_AUX_SENSE      
                                  2        GND                     
R1792            Q_RES_0402LF-0,5%,1/16W,CHIP,CA 2        SMB_SEN_3V3AUX_SDA      
R1793            Q_RES_0402LF-0,5%,1/16W,CHIP,CA 2        SMB_SEN_3V3AUX_SCL      
R1794            Q_RES_0402LF-4.7K,1%,1/16W,EMPA 1        P3V3_AUX                
                                  2        VOL_SEN_ALERT           
R1798            Q_RES_0402LF-0,5%,1/16W,CHIP,CA 1        ROT_P1_RST_IND_N_R      
                                  2        ROT_P1_RST_IND_N        
R1799            Q_RES_0402LF-33K    ,1%  ,1/16A 1        P12V_AUX                
                                  2        P12V_AUX_SENSE          
R1800            Q_RES_0402LF-120K,1%,1/16W,CHIA 1        P12V_AUX_SENSE          
                                  2        GND                     
R1801            Q_RES_0402LF-0,5%,1/16W,CHIP,CA 1        PRSNT0_N                
                                  2        GND                     
R1809            Q_RES_0402LF-20K,1%,1/16W,CHIPA 1        P3V3_AUX                
                                  2        FM_ADR_MODE0            
R1810            Q_RES_0402LF-1K,5%,1/16W,EMPTYA 1        FM_ADR_MODE0            
                                  2        GND                     
R1811            Q_RES_0402LF-33.2,1%,1/16W,CHIA 1        RST_SGPIO_RESET_N       
                                  2        RST_SGPIO_RESET_N_R     
R1812            Q_RES_0402LF-33.2,1%,1/16W,CHIA 1        IRQ_SGPIO_INTR_N        
                                  2        IRQ_SGPIO_INTR_N_R      
R1813            Q_RES_0402LF-10K,1%,1/16W,EMPTA 1        P3V3_AUX                
                                  2        FM_JTAG_BMC_MUX_SEL     
R1814            Q_RES_0402LF-1K,1%,1/16W,CHIP,A 1        FM_JTAG_BMC_MUX_SEL     
                                  2        GND                     
R1815            Q_RES_0402LF-0,5%,1/16W,CHIP,CA 1        FM_BMC_PWRBTN_OUT_N     
                                  2        FM_BMC_PWRBTN_OUT_R_N   
R1816            Q_RES_0402LF-0,5%,1/16W,CHIP,CA 1        PWRGD_PS_PWROK          
                                  2        PWRGD_PS_PWROK_R        
R1820            Q_RES_0402LF-10K,1%,1/16W,CHIPA 1        P3V3_AUX                
                                  2        FM_PLT_BMC_THERMTRIP_R_N
R1821            Q_RES_0402LF-0,5%,1/16W,EMPTY,A 1        FM_SPD_REMOTE_EN_R      
                                  2        FM_SPD_REMOTE_EN        
R1822            Q_RES_0402LF-10K,1%,1/16W,CHIPA 1        P3V3_AUX                
                                  2        PU_RST_SMB_PCIE3_N      
R1823            Q_RES_0402LF-1K,1%,1/16W,CHIP,A 1        P3V3_AUX                
                                  2        RST_MB_STBY_R_N         
R1824            Q_RES_0402LF-10K,1%,1/16W,CHIPA 1        P3V3_OCP_SFF            
                                  2        IRQ_LVC3_OCP_SFF_WAKE_N 
R1827            Q_RES_0402LF-33,5%,1/16W,CHIP,A 1        USB_OC1_REAR_R_N        
                                  2        USB_OC1_REAR_N          
R1828            Q_RES_0402LF-10K,1%,1/16W,CHIPA 1        USB_OC1_REAR_R_N        
                                  2        P3V3_AUX                
R1829            Q_RES_0402LF-0,5%,1/16W,EMPTY,A 1        SMB_S3M_CPU1_3V3AUX_SCL 
                                  2        SMB_S3M_CPU1_LVC1_SCL   
R1830            Q_RES_0402LF-0,5%,1/16W,EMPTY,A 1        SMB_S3M_CPU1_3V3AUX_SDA 
                                  2        SMB_S3M_CPU1_LVC1_SDA   
R1831            Q_RES_0402LF-0,5%,1/16W,EMPTY,A 1        JTAG_DBP_BMC_PRDY_N     
                                  2        JTAG_DBP_BMC_PRDY_R_N   
R1832            Q_RES_0402LF-0,5%,1/16W,EMPTY,A 1        JTAG_BMC_DBP_PREQ_N     
                                  2        JTAG_DBP_BMC_PREQ_R_N   
R1833            Q_RES_0402LF-0,5%,1/16W,CHIP,CA 1        FM_JTAG_BMC_MUX_SEL     
R1836            Q_RES_0402LF-0,5%,1/16W,CHIP,CA 1        IRQ_PSU_ALERT_N         
                                  2        IRQ_P12V_HSC_FAULT_N    
R1837            Q_RES_4P_12-0.001,1%,3W,SMLF,CA 1        P12V_S3_AUX_CPU1_NVDIMM 
                                  2        P12V_AUX                
                                  3        P12V_S3_AUX_CPU1_NVDIMM_ISENSE_
                                  4        P12V_S3_AUX_CPU1_NVDIMM_ISENS_1
R1838            Q_RES_4P_12-0.001,1%,3W,SMLF,CA 1        P12V_S3_AUX_CPU0_NVDIMM 
                                  2        P12V_AUX                
                                  3        P12V_S3_AUX_CPU0_NVDIMM_ISENSE_
                                  4        P12V_S3_AUX_CPU0_NVDIMM_ISENS_1
R1839            Q_RES_0402LF-0,5%,1/16W,EMPTY,A 1        RST_PFR_OVR_RTC         
                                  2        RST_RTCRST_N            
R1840            Q_RES_0402LF-0,5%,1/16W,EMPTY,A 1        RST_PFR_OVR_SRTC        
                                  2        RST_SRTCRST_N           
R1841            Q_RES_0402LF-10K,1%,1/16W,EMPTA 1        P3V3_AUX                
                                  2        FM_CPU_RMCA_CATERR_LVT3_R_N
R1842            Q_RES_0402LF-33.2,1%,1/16W,CHIA 1        FM_JTAG_BMC_PLD_MUX_SEL 
                                  2        FM_JTAG_BMC_MUX_SEL     
R1843            Q_RES_0402LF-33.2,1%,1/16W,CHIA 1        RST_PFR_OVR_RTC_R       
                                  2        RST_PFR_OVR_RTC         
R1844            Q_RES_0402LF-33.2,1%,1/16W,CHIA 1        RST_PFR_OVR_SRTC_R      
                                  2        RST_PFR_OVR_SRTC        
R1845            Q_RES_0402LF-0,5%,1/16W,CHIP,CA 1        FM_BMC_CPU_FBRK_OUT_N   
                                  2        FM_BMC_CPU_FBRK_OUT_R_N 
R1850            Q_RES_0402LF-1K,5%,1/16W,EMPTYA 1        GND                     
                                  2        FM_PCH_P1V8_AUX_EN_R    
R1853            Q_RES_0402LF-0,5%,1/16W,CHIP,CA 1        VIRTUAL_RESEAT_FPGA_R_N 
                                  2        VIRTUAL_RESEAT_FPGA_N   
R1854            Q_RES_0402LF-10K,1%,1/16W,CHIPA 1        P3V3_AUX                
                                  2        FM_SCM_PRSNT1_N         
R1856            Q_RES_0402LF-100,1%,1/16W,CHIPA 1        FM_SCM_PRSNT1_N         
                                  2        FM_SCM_PRSNT1_R_N       
R1857            Q_RES_0402LF-10K,1%,1/16W,CHIPA 1        P3V3_AUX                
                                  2        P12V_SCM_EN_N           
R1868            Q_RES_0402LF-0,5%,1/16W,CHIP,CA 1        ESPI_LAD0_DATA_IO3      
                                  2        ESPI_LPC_LAD0_IO3       
R1869            Q_RES_0402LF-0,5%,1/16W,CHIP,CA 1        ESPI_LAD0_DATA_IO2      
                                  2        ESPI_LPC_LAD0_IO2       
R1870            Q_RES_0402LF-0,5%,1/16W,CHIP,CA 1        ESPI_LAD0_DATA_IO1      
                                  2        ESPI_LPC_LAD0_IO1       
R1871            Q_RES_0402LF-0,5%,1/16W,CHIP,CA 1        ESPI_LAD0_DATA_IO0      
                                  2        ESPI_LPC_LAD0_IO0       
R1872            Q_RES_0402LF-0,5%,1/16W,CHIP,CA 1        CLK_24M_66M_LPC0_ESPI   
                                  2        ESPI_HOST_LPC_BMC_CLK   
R1895            Q_RES_0402LF-100,1%,1/16W,CHIPA 1        OCP_SFF_PRSNTA_R_N      
                                  2        GND                     
R1896            Q_RES_0402LF-100,1%,1/16W,CHIPA 1        OCP_SFF_ISO_BIF0_EN     
                                  2        GND                     
R1897            Q_RES_0402LF-100,1%,1/16W,CHIPA 1        OCP_SFF_ISO_BIF1_EN     
                                  2        GND                     
R1898            Q_RES_0402LF-100,1%,1/16W,CHIPA 1        OCP_SFF_ISO_BIF2_EN     
                                  2        GND                     
R1905            Q_RES_0402LF-10K,1%,1/16W,CHIPA 1        P3V3_AUX                
                                  2        OCP_SFF_PRSNT0_R_N      
R1906            Q_RES_0402LF-10K,1%,1/16W,CHIPA 1        P3V3_AUX                
                                  2        OCP_SFF_PRSNT2_R_N      
R1907            Q_RES_0402LF-10K,1%,1/16W,CHIPA 1        P3V3_AUX                
                                  2        OCP_SFF_PRSNT1_R_N      
R1908            Q_RES_0402LF-10K,1%,1/16W,CHIPA 1        P3V3_AUX                
                                  2        OCP_SFF_PRSNT3_R_N      
R1919            Q_RES_0402LF-33.2,1%,1/16W,CHIA 1        PWRGD_P3V3_AUX          
                                  2        PWRGD_P3V3_AUX_PLD      
R1921            Q_RES_0402LF-33,5%,1/16W,CHIP,A 1        FM_SMB_CPU0_ALERT       
                                  2        FM_SMB_PEHPCPU0_PCIE_ALERT_N
R1925            Q_RES_0402LF-0,5%,1/16W,CHIP,CA 1        IRQ0_A57_R              
                                  2        IRQ0_A57                
R1929            Q_RES_0402LF-10K,5%,1/16W,CHIPA 1        GND                     
                                  2        OCP_SFF_AUX_PWR_EN      
R1930            Q_RES_0402LF-10K,5%,1/16W,CHIPA 1        GND                     
                                  2        OCP_SFF_MAIN_PWR_EN     
R1932            Q_RES_0402LF-33.2,1%,1/16W,CHIA 1        SMB_CPU_PIROM_3V3AUX_SCL
                                  2        SMB_CPU0_PIROM_3V3AUX_SCL_R
R1933            Q_RES_0402LF-33.2,1%,1/16W,CHIA 1        SMB_CPU_PIROM_3V3AUX_SDA
                                  2        SMB_CPU0_PIROM_3V3AUX_SDA_R
R1934            Q_RES_0402LF-33.2,1%,1/16W,CHIA 1        SMB_CPU_PIROM_3V3AUX_SCL
                                  2        SMB_CPU1_PIROM_3V3AUX_SCL_R
R1935            Q_RES_0402LF-33.2,1%,1/16W,CHIA 1        SMB_CPU_PIROM_3V3AUX_SDA
                                  2        SMB_CPU1_PIROM_3V3AUX_SDA_R
R1940            Q_RES_0402LF-33.2,1%,1/16W,CHIA 1        SMB_PMBUS_PSU1_SCL_R2   
                                  2        SMB_PMBUS_PSU1_SCL      
R1941            Q_RES_0402LF-33.2,1%,1/16W,CHIA 1        SMB_PMBUS_PSU1_SDA_R2   
                                  2        SMB_PMBUS_PSU1_SDA      
R1944            Q_RES_0402LF-0,5%,1/16W,CHIP,CA 1        IRQ_PCH_SCI_WHEA_R_N    
                                  2        IRQ_PCH_SCI_WHEA_N      
R1950            Q_RES_0402LF-0,5%,1/16W,CHIP,CA 1        FM_COMP_P3V3_AUX_VIN    
                                  2        PWRGD_P3V3_AUX          
R1955            Q_RES_0402LF-10K,1%,1/16W,CHIPA 1        P3V3_AUX                
                                  2        FM_PCHHOT_N             
R1956            Q_RES_0402LF-100,1%,1/16W,CHIPA 1        H_CPU0_MON_FAIL_LVC1_R_N
                                  2        PVNN_TERM_CPU0          
R1957            Q_RES_0402LF-100,1%,1/16W,CHIPA 1        H_CPU1_MON_FAIL_LVC1_R_N
                                  2        PVNN_TERM_CPU1          
R1958            Q_RES_0402LF-10K,1%,1/16W,CHIPA 1        P3V3_AUX                
                                  2        PU_CLK_PFT_LOST_N       
R1959            Q_RES_0402LF-0,5%,1/16W,CHIP,CA 1        H_CPU0_PMDOWN_PCH_R2    
                                  2        H_CPU0_PMDOWN_PCH_R     
R1960            Q_RES_0402LF-0,5%,1/16W,CHIP,CA 1        H_CPU0_PMSYNC_PCH_R2    
                                  2        H_CPU0_PMSYNC_PCH_R     
R1961            Q_RES_0402LF-10K,1%,1/16W,CHIPA 1        PGPPA_AUX               
                                  2        ESPI_LFRAME_N_BMC_CS0_N 
R1962            Q_RES_0402LF-20K,5%,1/16W,CHIPA 1        FM_PCH_CONSENT_STRAP_N  
                                  2        GND                     
R1963            Q_RES_0402LF-10K,1%,1/16W,CHIPA 1        P3V3_AUX                
                                  2        FM_EDSFF1A_TYPE_ID      
R1964            Q_RES_0402LF-10K,5%,1/16W,EMPTA 1        P3V3_AUX                
                                  2        FM_SYS_THROTTLE_R_N     
R1965            Q_RES_0402LF-0,5%,1/16W,CHIP,CA 1        FM_SYS_THROTTLE_R_N     
                                  2        FM_EDSFF1A_PWRBRK_N     
R1966            Q_RES_0402LF-33.2,1%,1/16W,CHIA 1        SMB_PEHPCPU0_LVC3_SDA   
                                  2        SMB_PEHPCPU0_EDSFF1ALVC3_R_SDA
R1967            Q_RES_0402LF-4.7K,5%,1/16W,CHIA 1        RST_SMB_EDSFF1A_N       
                                  2        P3V3_AUX                
R1968            Q_RES_0402LF-4.7K,5%,1/16W,CHIA 1        FM_PCIE_EDSFF1A_PRSNT_1_N
                                  2        P3V3_AUX                
R1969            Q_RES_0402LF-10K,1%,1/16W,EMPTA 1        EDSFF1A_PERST1_CLKREQ_N 
                                  2        GND                     
R1970            Q_RES_0402LF-10K,1%,1/16W,CHIPA 1        PD_EDSFF1A_PWRDIS       
                                  2        GND                     
R1971            Q_RES_0402LF-33.2,1%,1/16W,CHIA 1        SMB_PEHPCPU0_EDSFF1A_LVC3_R_SCL
                                  2        SMB_PEHPCPU0_LVC3_SCL   
R1972            Q_RES_0402LF-100,1%,1/16W,CHIPA 1        PD_PCIE_EDSFF1A_PRSNT_0_N
                                  2        GND                     
R1973            Q_RES_0402LF-10K,1%,1/16W,CHIPA 1        P3V3_AUX                
                                  2        FM_EDSFF1B_TYPE_ID      
R1974            Q_RES_0402LF-10K,5%,1/16W,EMPTA 1        P3V3_AUX                
                                  2        FM_SYS_THROTTLE_R_N     
R1975            Q_RES_0402LF-0,5%,1/16W,CHIP,CA 1        FM_SYS_THROTTLE_R_N     
                                  2        FM_EDSFF1B_PWRBRK_N     
R1976            Q_RES_0402LF-33.2,1%,1/16W,CHIA 1        SMB_PEHPCPU0_LVC3_SDA   
                                  2        SMB_PEHPCPU0_EDSFF1B_LVC3_R_SDA
R1977            Q_RES_0402LF-4.7K,5%,1/16W,CHIA 1        RST_SMB_EDSFF1B_N       
                                  2        P3V3_AUX                
R1978            Q_RES_0402LF-4.7K,5%,1/16W,CHIA 1        FM_PCIE_EDSFF1B_PRSNT_1_N
                                  2        P3V3_AUX                
R1979            Q_RES_0402LF-10K,1%,1/16W,CHIPA 1        PU_EDSFF1B_PERST1_CLKREQ_N
                                  2        P3V3_AUX                
R1980            Q_RES_0402LF-10K,1%,1/16W,CHIPA 1        PD_EDSFF1B_PWRDIS       
                                  2        GND                     
R1981            Q_RES_0402LF-33.2,1%,1/16W,CHIA 1        SMB_PEHPCPU0_EDSFF1B_LVC3_R_SCL
                                  2        SMB_PEHPCPU0_LVC3_SCL   
R1982            Q_RES_0402LF-100,1%,1/16W,CHIPA 1        PD_PCIE_EDSFF1B_PRSNT_0_N
                                  2        GND                     
R1983            Q_RES_0402LF-10K,1%,1/16W,CHIPA 1        P3V3_AUX                
                                  2        FM_EDSFF4A_TYPE_ID      
R1984            Q_RES_0402LF-10K,5%,1/16W,EMPTA 1        P3V3_AUX                
                                  2        FM_SYS_THROTTLE_R_N     
R1985            Q_RES_0402LF-0,5%,1/16W,CHIP,CA 1        FM_SYS_THROTTLE_R_N     
                                  2        FM_EDSFF4A_PWRBRK_N     
R1986            Q_RES_0402LF-33.2,1%,1/16W,CHIA 1        SMB_PEHPCPU1_LVC3_SDA   
                                  2        SMB_PEHPCPU1_EDSFF4A_LVC3_R_SDA
R1987            Q_RES_0402LF-4.7K,5%,1/16W,CHIA 1        RST_SMB_EDSFF4A_N       
                                  2        P3V3_AUX                
R1988            Q_RES_0402LF-4.7K,5%,1/16W,CHIA 1        FM_PCIE_EDSFF4A_PRSNT_1_N
                                  2        P3V3_AUX                
R1989            Q_RES_0402LF-10K,1%,1/16W,CHIPA 1        EDSFF4A_PERST1_CLKREQ_N 
                                  2        P3V3_AUX                
R1990            Q_RES_0402LF-10K,1%,1/16W,CHIPA 1        PD_EDSFF4A_PWRDIS       
                                  2        GND                     
R1991            Q_RES_0402LF-33.2,1%,1/16W,CHIA 1        SMB_PEHPCPU1_EDSFF4A_LVC3_R_SCL
                                  2        SMB_PEHPCPU1_LVC3_SCL   
R1992            Q_RES_0402LF-100,1%,1/16W,CHIPA 1        PD_PCIE_EDSFF4A_PRSNT_0_N
                                  2        GND                     
R1993            Q_RES_0402LF-10K,1%,1/16W,CHIPA 1        P3V3_AUX                
                                  2        FM_EDSFF4B_TYPE_ID      
R1995            Q_RES_0402LF-33,5%,1/16W,CHIP,A 1        FM_PCH_SLP_S3_N         
                                  2        FM_SLPS3_PLD_N          
R1996            Q_RES_0402LF-33,5%,1/16W,CHIP,A 1        FM_PCH_SLP_S4_N         
                                  2        FM_SLPS4_PLD_N          
R2000            Q_RES_0402LF-4.7K,5%,1/16W,CHIA 1        FM_PCIE_EDSFF4B_PRSNT_1_N
                                  2        P3V3_AUX                
R2001            Q_RES_0402LF-10K,1%,1/16W,CHIPA 1        EDSFF4B_PERST1_CLKREQ_N 
                                  2        P3V3_AUX                
R2002            Q_RES_0402LF-10K,1%,1/16W,CHIPA 1        PD_EDSFF4B_PWRDIS       
                                  2        GND                     
R2004            Q_RES_0402LF-100,1%,1/16W,CHIPA 1        PD_PCIE_EDSFF4B_PRSNT_0_N
                                  2        GND                     
R2005            Q_RES_0402LF-10K,1%,1/16W,EMPTA 1        P3V3_E1S_1              
                                  2        RST_SMB_E1S_1_N         
R2006            Q_RES_0402LF-10K,1%,1/16W,EMPTA 1        P3V3_E1S_2              
                                  2        RST_SMB_E1S_2_N         
R2007            Q_RES_0402LF-10K,1%,1/16W,EMPTA 1        P3V3_E1S_3              
                                  2        RST_SMB_E1S_3_N         
R2014            Q_RES_0402LF-100K,1%,1/16W,EMPA 1        P3V3_AUX                
                                  2        FM_P3V3_E1S_0_EN        
R2015            Q_RES_0402LF-100K,1%,1/16W,EMPA 1        P3V3_AUX                
                                  2        FM_P3V3_E1S_2_EN        
R2016            Q_RES_0402LF-1.33K,1%,1/16W,CHA 1        P3V3_E1S_2_ILM          
                                  2        GND                     
R2017            Q_RES_0402LF-10K,1%,1/16W,CHIPA 1        P3V3_AUX                
                                  2        P3V3_E1S_2_FLT_N        
R2018            Q_RES_0402LF-100K,1%,1/16W,EMPA 1        P3V3_AUX                
                                  2        FM_P3V3_E1S_1_EN        
R2019            Q_RES_0402LF-100K,1%,1/16W,EMPA 1        P3V3_AUX                
                                  2        FM_P3V3_E1S_3_EN        
R2020            Q_RES_0402LF-1.33K,1%,1/16W,CHA 1        P3V3_E1S_1_ILM          
                                  2        GND                     
R2021            Q_RES_0402LF-1.33K,1%,1/16W,CHA 1        P3V3_E1S_3_ILM          
                                  2        GND                     
R2022            Q_RES_0402LF-10K,1%,1/16W,CHIPA 1        P3V3_AUX                
                                  2        P3V3_E1S_1_FLT_N        
R2023            Q_RES_0402LF-10K,1%,1/16W,CHIPA 1        P3V3_AUX                
                                  2        P3V3_E1S_3_FLT_N        
R2036            Q_RES_0402LF-100K,1%,1/16W,EMPA 1        P3V3_AUX                
                                  2        FM_P12V_E1S_0_EN        
R2037            Q_RES_0402LF-100K,1%,1/16W,EMPA 1        P3V3_AUX                
                                  2        FM_P12V_E1S_2_EN        
R2038            Q_RES_0402LF-576,1%,1/16W,CHIPA 1        P12V_E1S_0_ILM          
                                  2        GND                     
R2039            Q_RES_0402LF-576,1%,1/16W,CHIPA 1        P12V_E1S_2_ILM          
                                  2        GND                     
R2040            Q_RES_0402LF-10K,1%,1/16W,CHIPA 1        P3V3_AUX                
                                  2        P12V_E1S_0_FLT_N        
R2041            Q_RES_0402LF-10K,1%,1/16W,CHIPA 1        P3V3_AUX                
                                  2        P12V_E1S_2_FLT_N        
R2042            Q_RES_0402LF-100K,1%,1/16W,EMPA 1        P3V3_AUX                
                                  2        FM_P12V_E1S_1_EN        
R2043            Q_RES_0402LF-100K,1%,1/16W,EMPA 1        P3V3_AUX                
                                  2        FM_P12V_E1S_3_EN        
R2044            Q_RES_0402LF-576,1%,1/16W,CHIPA 1        P12V_E1S_1_ILM          
                                  2        GND                     
R2045            Q_RES_0402LF-576,1%,1/16W,CHIPA 1        P12V_E1S_3_ILM          
                                  2        GND                     
R2046            Q_RES_0402LF-10K,1%,1/16W,CHIPA 1        P3V3_AUX                
                                  2        P12V_E1S_1_FLT_N        
R2047            Q_RES_0402LF-10K,1%,1/16W,CHIPA 1        P3V3_AUX                
                                  2        P12V_E1S_3_FLT_N        
R2048            Q_RES_0402LF-0,5%,1/16W,CHIP,CA 1        CLK_100M_EDSFF4B_R_DP   
                                  2        CLK_100M_EDSFF4B_DP     
R2049            Q_RES_0402LF-0,5%,1/16W,CHIP,CA 1        CLK_100M_EDSFF4B_R_DN   
                                  2        CLK_100M_EDSFF4B_DN     
R2050            Q_RES_0402LF-33.2,1%,1/16W,CHIA 1        RST_PCIE_CPU0_DEV_PERST_N
                                  2        RST_PCIE_EDSFF2B_PERST_N
R2051            Q_RES_0402LF-2.2K ,5%,1/16W,CHA 1        P3V3_AUX                
                                  2        SMB_EDSFF1B_3V3AUX_SCL_R
R2052            Q_RES_0402LF-2.2K ,5%,1/16W,CHA 1        P3V3_AUX                
                                  2        SMB_EDSFF1B_3V3AUX_SDA_R
R2053            Q_RES_0402LF-2.2K ,5%,1/16W,CHA 1        P3V3_AUX                
                                  2        SMB_EDSFF2B_3V3AUX_SCL_R
R2054            Q_RES_0402LF-2.2K ,5%,1/16W,CHA 1        P3V3_AUX                
                                  2        SMB_EDSFF2B_3V3AUX_SDA_R
R2055            Q_RES_0402LF-2.2K ,5%,1/16W,CHA 1        P3V3_AUX                
                                  2        SMB_EDSFF4B_3V3AUX_SCL_R
R2056            Q_RES_0402LF-2.2K ,5%,1/16W,CHA 1        P3V3_AUX                
                                  2        SMB_EDSFF4B_3V3AUX_SDA_R
R2057            Q_RES_0402LF-2.2K ,5%,1/16W,CHA 1        P3V3_AUX                
                                  2        PU_SMB_EDSFF_3V3AUX_SCL7
R2058            Q_RES_0402LF-2.2K ,5%,1/16W,CHA 1        P3V3_AUX                
                                  2        PU_SMB_EDSFF_3V3AUX_SDA7
R2059            Q_RES_0402LF-0,5%,1/16W,CHIP,CA 1        SMB_EDSFF1B_3V3AUX_SCL_R1
                                  2        SMB_EDSFF1B_3V3AUX_SCL_R
R2060            Q_RES_0402LF-0,5%,1/16W,CHIP,CA 1        SMB_EDSFF1B_3V3AUX_SDA_R1
                                  2        SMB_EDSFF1B_3V3AUX_SDA_R
R2061            Q_RES_0402LF-0,5%,1/16W,CHIP,CA 1        SMB_EDSFF2B_3V3AUX_SCL_R1
                                  2        SMB_EDSFF2B_3V3AUX_SCL_R
R2062            Q_RES_0402LF-0,5%,1/16W,CHIP,CA 1        SMB_EDSFF2B_3V3AUX_SDA_R1
                                  2        SMB_EDSFF2B_3V3AUX_SDA_R
R2063            Q_RES_0402LF-0,5%,1/16W,CHIP,CA 1        SMB_EDSFF4B_3V3AUX_SCL_R1
                                  2        SMB_EDSFF4B_3V3AUX_SCL_R
R2064            Q_RES_0402LF-0,5%,1/16W,CHIP,CA 1        SMB_EDSFF4B_3V3AUX_SDA_R1
                                  2        SMB_EDSFF4B_3V3AUX_SDA_R
R2065            Q_RES_0402LF-0,5%,1/16W,CHIP,CA 1        SMB_EDSFF_3V3AUX_SCL_R8 
                                  2        PU_SMB_EDSFF_3V3AUX_SCL7
R2066            Q_RES_0402LF-0,5%,1/16W,CHIP,CA 1        SMB_EDSFF_3V3AUX_SDA_R8 
                                  2        PU_SMB_EDSFF_3V3AUX_SDA7
R2070            Q_RES_0402LF-0,5%,1/16W,CHIP,CA 1        VOL_SEN_ALERT           
                                  2        VOL_SEN_ALERT_R         
R2071            Q_RES_0402LF-0,5%,1/16W,EMPTY,A 1        FM_BMC_SUSACK_R_N       
                                  2        FM_SUSACK_N             
R2072            Q_RES_0402LF-100K,1%,1/16W,CHIA 1        VDD3                    
                                  2        PU_MP5981_0_D_OC        
R2073            Q_RES_0402LF-100K,1%,1/16W,CHIA 1        VDD3                    
                                  2        PU_MP5981_0_GOK         
R2074            Q_RES_0402LF-0,5%,1/16W,CHIP,CA 1        PD_MP5981_0_MODE        
                                  2        GND                     
R2075            Q_RES_0402LF-120K,1%,1/16W,CHIA 1        MP5981_0_CLREF          
                                  2        GND                     
R2076            Q_RES_0402LF-2.4K,1%,1/16W,CHIA 1        MP5981_0_CS             
                                  2        GND                     
R2077            Q_RES_0402LF-33.2,1%,1/16W,CHIA 1        IRQ_LVC3_WAKE_EDSFF4_N  
                                  2        IRQ_LVC3_WAKE_N         
R2078            Q_RES_0402LF-33.2,1%,1/16W,CHIA 1        IRQ_LVC3_WAKE_EDSFF3_N  
                                  2        IRQ_LVC3_WAKE_N         
R2079            Q_RES_0402LF-4.7K,5%,1/16W,EMPA 1        JTAG_EDSFF4_TDI         
                                  2        P3V3_AUX                
R2080            Q_RES_0402LF-4.7K,5%,1/16W,EMPA 1        JTAG_EDSFF4_TDO         
                                  2        P3V3_AUX                
R2081            Q_RES_0402LF-4.7K,5%,1/16W,EMPA 1        JTAG_EDSFF4_TMS         
                                  2        P3V3_AUX                
R2082            Q_RES_0402LF-4.7K,5%,1/16W,EMPA 1        JTAG_EDSFF4_TCK         
                                  2        GND                     
R2083            Q_RES_0402LF-4.7K,5%,1/16W,EMPA 1        JTAG_EDSFF4_TRST_N      
                                  2        GND                     
R2084            Q_RES_0402LF-100K,1%,1/16W,CHIA 1        VDD3                    
                                  2        PU_MP5981_1_GOK         
R2085            Q_RES_0402LF-100K,1%,1/16W,CHIA 1        VDD3                    
                                  2        PU_MP5981_1_D_OC        
R2086            Q_RES_0402LF-0,5%,1/16W,CHIP,CA 1        PD_MP5981_1_MODE        
                                  2        GND                     
R2087            Q_RES_0402LF-120K,1%,1/16W,CHIA 1        MP5981_1_CLREF          
                                  2        GND                     
R2088            Q_RES_0402LF-2.4K,1%,1/16W,CHIA 1        MP5981_1_CS             
                                  2        GND                     
R2089            Q_RES_0402LF-1K,5%,1/16W,EMPTYA 1        P3V3_AUX                
                                  2        PCA9555_1_ADD2          
R2090            Q_RES_0402LF-1K,5%,1/16W,CHIP,A 1        PCA9555_1_ADD2          
                                  2        GND                     
R2091            Q_RES_0402LF-1K,5%,1/16W,EMPTYA 1        P3V3_AUX                
                                  2        PCA9555_2_ADD2          
R2092            Q_RES_0402LF-1K,5%,1/16W,CHIP,A 1        PCA9555_2_ADD2          
                                  2        GND                     
R2093            Q_RES_0402LF-1K,5%,1/16W,EMPTYA 1        P3V3_AUX                
                                  2        PCA9555_1_ADD1          
R2094            Q_RES_0402LF-1K,5%,1/16W,CHIP,A 1        PCA9555_1_ADD1          
                                  2        GND                     
R2095            Q_RES_0402LF-1K,5%,1/16W,EMPTYA 1        P3V3_AUX                
                                  2        PCA9555_2_ADD1          
R2096            Q_RES_0402LF-1K,5%,1/16W,CHIP,A 1        PCA9555_2_ADD1          
                                  2        GND                     
R2097            Q_RES_0402LF-1K,5%,1/16W,EMPTYA 1        P3V3_AUX                
                                  2        PCA9555_1_ADD0          
R2098            Q_RES_0402LF-1K,5%,1/16W,CHIP,A 1        PCA9555_1_ADD0          
                                  2        GND                     
R2099            Q_RES_0402LF-1K,5%,1/16W,EMPTYA 1        P3V3_AUX                
                                  2        PCA9555_2_ADD0          
R2100            Q_RES_0402LF-1K,5%,1/16W,CHIP,A 1        PCA9555_2_ADD0          
                                  2        GND                     
R2101            Q_RES_0402LF-33,5%,1/16W,CHIP,A 1        SMB_PEHPCPU0_LVC3_SCL   
                                  2        SMB_PEHPCPU0_LVC3_R1_SCL
R2102            Q_RES_0402LF-33,5%,1/16W,CHIP,A 1        SMB_PEHPCPU0_LVC3_SDA   
                                  2        SMB_PEHPCPU0_LVC3_R1_SDA
R2103            Q_RES_0402LF-33,5%,1/16W,CHIP,A 1        SMB_PEHPCPU0_LVC3_SCL   
                                  2        SMB_PEHPCPU0_LVC3_R2_SCL
R2104            Q_RES_0402LF-33,5%,1/16W,CHIP,A 1        SMB_PEHPCPU0_LVC3_SDA   
                                  2        SMB_PEHPCPU0_LVC3_R2_SDA
R2105            Q_RES_0402LF-0,5%,1/16W,CHIP,CA 1        E1S_1_BUF_EN            
                                  2        E1S_0_EN                
R2106            Q_RES_0402LF-0,5%,1/16W,CHIP,CA 1        E1S_0_BUF_PRSNT_N       
                                  2        E1S_0_BUF_PRSNT_R_N     
R2107            Q_RES_0402LF-0,5%,1/16W,CHIP,CA 1        E1S_1_BUF_EN            
                                  2        E1S_1_EN                
R2108            Q_RES_0402LF-0,5%,1/16W,CHIP,CA 1        E1S_1_BUF_PRSNT_N       
                                  2        E1S_1_BUF_PRSNT_R_N     
R2109            Q_RES_0402LF-0,5%,1/16W,CHIP,CA 1        E1S_2_BUF_EN            
                                  2        E1S_2_EN                
R2110            Q_RES_0402LF-0,5%,1/16W,CHIP,CA 1        E1S_2_BUF_PRSNT_N       
                                  2        E1S_2_BUF_PRSNT_R_N     
R2111            Q_RES_0402LF-0,5%,1/16W,CHIP,CA 1        E1S_3_BUF_EN            
                                  2        E1S_3_EN                
R2112            Q_RES_0402LF-0,5%,1/16W,CHIP,CA 1        E1S_3_BUF_PRSNT_N       
                                  2        E1S_3_BUF_PRSNT_R_N     
R2113            Q_RES_0402LF-0,5%,1/16W,CHIP,CA 1        RST_PCIE_BUF_E1S_0_PERST_N
                                  2        RST_PCIE_E1S_0_PERST_N  
R2114            Q_RES_0402LF-0,5%,1/16W,CHIP,CA 1        RST_PCIE_BUF_E1S_1_PERST_N
                                  2        RST_PCIE_E1S_1_PERST_N  
R2115            Q_RES_0402LF-0,5%,1/16W,CHIP,CA 1        RST_PCIE_BUF_E1S_2_PERST_N
                                  2        RST_PCIE_E1S_2_PERST_N  
R2116            Q_RES_0402LF-0,5%,1/16W,CHIP,CA 1        RST_PCIE_BUF_E1S_3_PERST_N
                                  2        RST_PCIE_E1S_3_PERST_N  
R2117            Q_RES_0402LF-0,5%,1/16W,CHIP,CA 1        RST_SMB_BUF_E1S_0_N     
                                  2        RST_SMB_E1S_0_N         
R2118            Q_RES_0402LF-0,5%,1/16W,CHIP,CA 1        RST_SMB_BUF_E1S_1_N     
                                  2        RST_SMB_E1S_1_N         
R2119            Q_RES_0402LF-0,5%,1/16W,CHIP,CA 1        RST_SMB_BUF_E1S_2_N     
                                  2        RST_SMB_E1S_2_N         
R2120            Q_RES_0402LF-0,5%,1/16W,CHIP,CA 1        RST_SMB_BUF_E1S_3_N     
                                  2        RST_SMB_E1S_3_N         
R2121            Q_RES_0402LF-4.7K,5%,1/16W,CHIA 1        P3V3_AUX                
                                  2        RST_PCIE_E1S_0_PERST_N  
R2122            Q_RES_0402LF-4.7K,5%,1/16W,CHIA 1        P3V3_AUX                
                                  2        RST_PCIE_E1S_2_PERST_N  
R2123            Q_RES_0402LF-4.7K,5%,1/16W,CHIA 1        P3V3_AUX                
                                  2        RST_SMB_E1S_0_N         
R2124            Q_RES_0402LF-4.7K,5%,1/16W,CHIA 1        P3V3_AUX                
                                  2        RST_SMB_E1S_2_N         
R2125            Q_RES_0402LF-4.7K,5%,1/16W,CHIA 1        P3V3_AUX                
                                  2        RST_PCIE_E1S_1_PERST_N  
R2126            Q_RES_0402LF-4.7K,5%,1/16W,CHIA 1        P3V3_AUX                
                                  2        RST_PCIE_E1S_3_PERST_N  
R2127            Q_RES_0402LF-4.7K,5%,1/16W,CHIA 1        P3V3_AUX                
                                  2        RST_SMB_E1S_1_N         
R2128            Q_RES_0402LF-4.7K,5%,1/16W,CHIA 1        P3V3_AUX                
                                  2        RST_SMB_E1S_3_N         
R2129            Q_RES_0402LF-33.2,1%,1/16W,CHIA 1        RST_PCIE_CPU0_DEV_PERST_N
                                  2        RST_PCIE_E1S_PERST_N    
R2130            Q_RES_0402LF-0,5%,1/16W,CHIP,CA 1        USB2_4_DN               
                                  2        RISER2_USB2_4_DN        
R2131            Q_RES_0402LF-0,5%,1/16W,CHIP,CA 1        USB2_4_DP               
                                  2        RISER2_USB2_4_DP        
R2132            Q_RES_0402LF-0,5%,1/16W,EMPTY,A 1        JTAG_TRC_PCH_PTI<6>     
                                  2        FM_ESPI_PLD_R_EN        
R2133            Q_RES_0402LF-1K,1%,1/16W,CHIP,A 1        P3V3_AUX                
                                  2        PU_ESPI_ENABLE_STRAP    
R2134            Q_RES_0402LF-10K,1%,1/16W,CHIPA 1        JTAG_TRC_PCH_PTI<6>     
                                  2        GND                     
R2135            Q_RES_0402LF-0,5%,1/16W,CHIP,CA 1        VIRTUAL_RESEAT_FPGA_N   
                                  2        P12V_SCM_EN_N           
R2137            Q_RES_0402LF-576,1%,1/16W,CHIPA 1        P12V_SCM_ILM            
                                  2        GND                     
R2138            Q_RES_0402LF-10K,1%,1/16W,CHIPA 1        P3V3_AUX                
                                  2        P12V_SCM_FLT_N          
R2139            Q_RES_0402LF-0,5%,1/16W,CHIP,CA 1        FM_RISER2_JTAG_SEL_PLD_N
                                  2        FM_RISER2_JTAG_SEL_N    
R2140            Q_RES_0402LF-10K,5%,1/16W,CHIPA 1        P3V3_AUX                
                                  2        FM_RISER2_JTAG_SEL_N    
R2141            Q_RES_0402LF-2.4K,1%,1/16W,CHIA 1        TP_MP5981_0_IMON        
                                  2        GND                     
R2142            Q_RES_0402LF-2.4K,1%,1/16W,CHIA 1        TP_MP5981_1_IMON        
                                  2        GND                     
R2143            Q_RES_0402LF-0,5%,1/16W,CHIP,CA 1        CLK_100M_EDSFF1A_1_R_DP 
                                  2        CLK_100M_EDSFF1A_1_DP   
R2144            Q_RES_0402LF-0,5%,1/16W,CHIP,CA 1        CLK_100M_EDSFF1A_1_R_DN 
                                  2        CLK_100M_EDSFF1A_1_DN   
R2145            Q_RES_0402LF-0,5%,1/16W,CHIP,CA 1        CLK_100M_EDSFF1B_1_R_DP 
                                  2        CLK_100M_EDSFF1B_1_DP   
R2146            Q_RES_0402LF-0,5%,1/16W,CHIP,CA 1        CLK_100M_EDSFF1B_1_R_DN 
                                  2        CLK_100M_EDSFF1B_1_DN   
R2147            Q_RES_0402LF-0,5%,1/16W,CHIP,CA 1        FM_BIOS_DEBUG_EN_N      
                                  2        FM_BIOS_DEBUG_EN_R_N    
R2148            Q_RES_0402LF-0,5%,1/16W,CHIP,CA 1        FM_PCIE_EDSFF3_PRSNT_1_N
                                  2        EDSFF3_CLK_EN_N         
R2149            Q_RES_0402LF-0,5%,1/16W,CHIP,CA 1        EDSFF3_USB2_5_DN        
                                  2        USB2_5_DN               
R2150            Q_RES_0402LF-0,5%,1/16W,CHIP,CA 1        EDSFF3_USB2_5_DP        
                                  2        USB2_5_DP               
R2151            Q_RES_0402LF-0,5%,1/16W,CHIP,CA 1        E1S_0_PWR_FAIL_N        
                                  2        E1S_0_LED_ACT_N         
R2152            Q_RES_0402LF-0,5%,1/16W,CHIP,CA 1        E1S_1_PWR_FAIL_N        
                                  2        E1S_1_LED_ACT_N         
R2153            Q_RES_0402LF-0,5%,1/16W,CHIP,CA 1        E1S_2_PWR_FAIL_N        
                                  2        E1S_2_LED_ACT_N         
R2154            Q_RES_0402LF-0,5%,1/16W,CHIP,CA 1        E1S_3_PWR_FAIL_N        
                                  2        E1S_3_LED_ACT_N         
R2155            Q_RES_0402LF-0,5%,1/16W,CHIP,CA 1        FM_BMC_READY_R_PLD_N    
                                  2        FM_BMC_READY_R_N        
R2156            Q_RES_0402LF-0,5%,1/16W,CHIP,CA 1        PD_MB_PRSNT             
                                  2        GND                     
R2157            Q_RES_0402LF-4.7K,1%,1/16W,CHIA 1        P3V3_AUX                
                                  2        FAN_PDB_PRSNT_N         
R2158            Q_RES_0402LF-10K,5%,1/16W,CHIPA 1        P3V3_AUX                
                                  2        PCIE_RISER2_PRSNT_N     
R2159            Q_RES_0402LF-0,5%,1/16W,CHIP,CA 1        E1S_2_EN                
                                  2        FM_P12V_E1S_2_EN        
R2160            Q_RES_0402LF-0,5%,1/16W,CHIP,CA 1        E1S_0_EN                
                                  2        FM_P12V_E1S_0_EN        
R2161            Q_RES_0402LF-0,5%,1/16W,CHIP,CA 1        E1S_1_EN                
                                  2        FM_P12V_E1S_1_EN        
R2162            Q_RES_0402LF-0,5%,1/16W,CHIP,CA 1        E1S_3_EN                
                                  2        FM_P12V_E1S_3_EN        
R2163            Q_RES_0402LF-0,5%,1/16W,CHIP,CA 1        E1S_2_EN                
                                  2        FM_P3V3_E1S_2_EN        
R2164            Q_RES_0402LF-0,5%,1/16W,CHIP,CA 1        E1S_0_EN                
                                  2        FM_P3V3_E1S_0_EN        
R2165            Q_RES_0402LF-0,5%,1/16W,CHIP,CA 1        E1S_1_EN                
                                  2        FM_P3V3_E1S_1_EN        
R2166            Q_RES_0402LF-0,5%,1/16W,CHIP,CA 1        E1S_3_EN                
                                  2        FM_P3V3_E1S_3_EN        
R2167            Q_RES_0402LF-10K,1%,1/16W,CHIPA 1        P3V3_AUX                
                                  2        RISER1_TYPE_ID          
R2168            Q_RES_0402LF-10K,5%,1/16W,EMPTA 1        P3V3_AUX                
                                  2        FM_SYS_THROTTLE_R_N     
R2169            Q_RES_0402LF-0,5%,1/16W,CHIP,CA 1        FM_SYS_THROTTLE_R_N     
                                  2        FM_RISER1_PWRBRK_N      
R2170            Q_RES_0402LF-10K,5%,1/16W,CHIPA 1        P3V3_AUX                
                                  2        PCIE_RISER1_PRSNT2_N    
R2171            Q_RES_0402LF-33.2,1%,1/16W,CHIA 1        IRQ_LVC3_WAKE_R1_N      
                                  2        IRQ_LVC3_WAKE_N         
R2172            Q_RES_0402LF-100,1%,1/16W,CHIPA 1        PD_RISER1_PRSNT1        
                                  2        GND                     
R2173            Q_RES_0402LF-10K,5%,1/16W,CHIPA 1        P3V3_AUX                
                                  2        RISER1_CLK0_EN_N        
R2174            Q_RES_0402LF-10K,5%,1/16W,CHIPA 1        P3V3_AUX                
                                  2        RISER1_CLK1_EN_N        
R2175            Q_RES_0402LF-4.7K,5%,1/16W,EMPA 1        JTAG_RISER1_TDI         
                                  2        P3V3_AUX                
R2176            Q_RES_0402LF-4.7K,5%,1/16W,EMPA 1        JTAG_RISER1_TDO         
                                  2        P3V3_AUX                
R2177            Q_RES_0402LF-4.7K,5%,1/16W,EMPA 1        JTAG_RISER1_TMS         
                                  2        P3V3_AUX                
R2178            Q_RES_0402LF-4.7K,5%,1/16W,EMPA 1        JTAG_RISER1_TCK         
                                  2        GND                     
R2179            Q_RES_0402LF-4.7K,5%,1/16W,EMPA 1        JTAG_RISER1_TRST_N      
                                  2        GND                     
R2180            Q_RES_0402LF-10K,1%,1/16W,CHIPA 1        P3V3_AUX                
                                  2        FM_EDSFF3_TYPE_ID       
R2181            Q_RES_0402LF-0,5%,1/16W,CHIP,CA 1        CLK_100M_PE_0_R_DP      
                                  2        CLK_100M_PE_0_DP        
R2182            Q_RES_0402LF-0,5%,1/16W,CHIP,CA 1        CLK_100M_PE_0_R_DN      
                                  2        CLK_100M_PE_0_DN        
R2183            Q_RES_0402LF-0,5%,1/16W,CHIP,CA 1        CLK_100M_PE_1_R_DP      
                                  2        CLK_100M_PE_1_DP        
R2184            Q_RES_0402LF-0,5%,1/16W,CHIP,CA 1        CLK_100M_PE_1_R_DN      
                                  2        CLK_100M_PE_1_DN        
R2185            Q_RES_0402LF-0,5%,1/16W,CHIP,CA 1        FM_JTAG_EDSFF4_SEL      
                                  2        FM_RISER1_JTAG_SEL_PLD_N
R2186            Q_RES_0402LF-33,5%,1/16W,CHIP,A 1        PWRGD_HSC_P12V_PWROK    
                                  2        PWRGD_PS_PWROK          
R2187            Q_RES_0402LF-0,5%,1/16W,CHIP,CA 1        SMB_RISER1_3V3AUX_SDA   
                                  2        SMB_PCIE0_3V3AUX_SDA_R0 
R2188            Q_RES_0402LF-0,5%,1/16W,CHIP,CA 1        SMB_RISER1_3V3AUX_SCL   
                                  2        SMB_PCIE0_3V3AUX_SCL_R0 
R2189            Q_RES_0402LF-0,5%,1/16W,CHIP,CA 1        SMB_PCIE0_3V3AUX_SCL_R3 
                                  2        SMB_SENSOR_M2_P0_3V3AUX_SCL
R2190            Q_RES_0402LF-0,5%,1/16W,CHIP,CA 1        SMB_PCIE0_3V3AUX_SDA_R3 
                                  2        SMB_SENSOR_M2_P0_3V3AUX_SDA
R2191            Q_RES_0402LF-10K,1%,1/16W,EMPTA 1        P3V3_AUX                
                                  2        PCA9546_PCIE3_ADDR2     
R2192            Q_RES_0402LF-1K,1%,1/16W,CHIP,A 1        PCA9546_PCIE3_ADDR2     
                                  2        GND                     
R2193            Q_RES_0402LF-10K,1%,1/16W,CHIPA 1        P3V3_AUX                
                                  2        PCA9546_PCIE3_ADDR1     
R2194            Q_RES_0402LF-1K,1%,1/16W,EMPTYA 1        PCA9546_PCIE3_ADDR1     
                                  2        GND                     
R2195            Q_RES_0402LF-10K,1%,1/16W,EMPTA 1        P3V3_AUX                
                                  2        PCA9546_PCIE3_ADDR0     
R2196            Q_RES_0402LF-1K,1%,1/16W,CHIP,A 1        PCA9546_PCIE3_ADDR0     
                                  2        GND                     
R2197            Q_RES_0402LF-10K,1%,1/16W,CHIPA 1        P3V3_AUX                
                                  2        PU_RST_SMB_PCIE3_N      
R2198            Q_RES_0402LF-2.2K ,5%,1/16W,CHA 1        P3V3_AUX                
                                  2        SMB_PCIE3_3V3AUX_SCL    
R2199            Q_RES_0402LF-2.2K ,5%,1/16W,CHA 1        P3V3_AUX                
                                  2        SMB_PCIE3_3V3AUX_SDA    
R2200            Q_RES_0402LF-2.2K ,5%,1/16W,CHA 1        P3V3_AUX                
                                  2        SMB_OCP_SFF_3V3AUX_SCL  
R2201            Q_RES_0402LF-2.2K ,5%,1/16W,CHA 1        P3V3_AUX                
                                  2        SMB_OCP_SFF_3V3AUX_SDA  
R2202            Q_RES_0402LF-2.2K ,5%,1/16W,CHA 1        P3V3_AUX                
                                  2        SMB_RISER3_3V3AUX_SCL   
R2203            Q_RES_0402LF-2.2K ,5%,1/16W,CHA 1        P3V3_AUX                
                                  2        SMB_RISER3_3V3AUX_SDA   
R2204            Q_RES_0402LF-2.2K ,5%,1/16W,CHA 1        P3V3_AUX                
                                  2        SMB_PCIE0_3V3AUX_SCL    
R2205            Q_RES_0402LF-2.2K ,5%,1/16W,CHA 1        P3V3_AUX                
                                  2        SMB_PCIE0_3V3AUX_SDA    
R2206            Q_RES_0402LF-2.2K ,5%,1/16W,CHA 1        P3V3_AUX                
                                  2        SMB_PCIE2_3V3AUX_SCL    
R2207            Q_RES_0402LF-2.2K ,5%,1/16W,CHA 1        P3V3_AUX                
                                  2        SMB_PCIE2_3V3AUX_SDA    
R2208            Q_RES_0402LF-0,5%,1/16W,CHIP,CA 1        SMB_S3M_CPU_3V3AUX_SCL  
                                  2        SMB_S3M_CPU0_3V3AUX_SCL 
R2209            Q_RES_0402LF-0,5%,1/16W,CHIP,CA 1        SMB_S3M_CPU_3V3AUX_SDA  
                                  2        SMB_S3M_CPU0_3V3AUX_SDA 
R2210            Q_RES_0402LF-0,5%,1/16W,CHIP,CA 1        SMB_S3M_CPU_3V3AUX_SCL  
                                  2        SMB_S3M_CPU1_3V3AUX_SCL 
R2211            Q_RES_0402LF-0,5%,1/16W,CHIP,CA 1        SMB_S3M_CPU_3V3AUX_SDA  
                                  2        SMB_S3M_CPU1_3V3AUX_SDA 
R2212            Q_RES_0402LF-2.2K ,5%,1/16W,CHA 1        SMB_S3M_CPU_3V3AUX_SCL  
                                  2        P3V3_AUX                
R2213            Q_RES_0402LF-2.2K ,5%,1/16W,CHA 1        SMB_S3M_CPU_3V3AUX_SDA  
                                  2        P3V3_AUX                
R2322            Q_RES_0402LF-49.9     ,1%  ,1/B 1        PVNN_TERM_CPU0          
                                  2        SVID_CLK0_CPU0_R        
R2330            Q_RES_0402LF-10K,1%,1/16W,EMPTA 1        P3V3_AUX                
                                  2        FM_PVPP_HBM_CPU0_EN     
R2332            Q_RES_0402LF-2K,1%,1/16W,EMPTYA 1        FM_PVPP_HBM_CPU0_EN     
                                  2        GND                     
R2334            Q_RES_0402LF-0,5%,1/16W,EMPTY,A 1        PWRGD_PVPP_HBM_CPU0_R   
                                  2        PWRGD_PVPP_HBM_CPU0     
R2336            Q_RES_0402LF-26.1K,1%,1/16W,EMA 1        PVPP_HBM_CPU0_FB        
                                  2        FM_HBM_VPP_SEL_CPU0_D   
R2338            Q_RES_0402LF-10K,1%,1/16W,EMPTA 1        P3V3_AUX                
                                  2        FM_PVNN_MAIN_CPU0_EN    
R2345            Q_RES_0402LF-49.9     ,1%  ,1/B 1        PVNN_TERM_CPU1          
                                  2        SVID_CLK0_CPU1_R        
R2354            Q_RES_0402LF-100,1%,1/16W,EMPTA 1        PVNN_TERM_CPU1          
                                  2        SVID_DIO0_CPU1_R        
R2367            Q_RES_0402LF-10K,1%,1/16W,EMPTA 1        P3V3_AUX                
                                  2        FM_PVPP_HBM_CPU1_EN     
R2374            Q_RES_0402LF-2K,1%,1/16W,CHIP,A 1        FM_PVPP_HBM_CPU1_EN     
                                  2        GND                     
R2380            Q_RES_0402LF-0,5%,1/16W,CHIP,CA 1        PWRGD_PVPP_HBM_CPU1_R   
                                  2        PWRGD_PVPP_HBM_CPU1     
R2381            Q_RES_0402LF-26.1K,1%,1/16W,CHA 1        PVPP_HBM_CPU1_FB        
                                  2        FM_HBM_VPP_SEL_CPU1_D   
R2384            Q_RES_0402LF-10K,1%,1/16W,EMPTA 1        P3V3_AUX                
                                  2        FM_PVNN_MAIN_CPU1_EN    
R2385            Q_RES_0402LF-2K,1%,1/16W,CHIP,A 1        FM_PVNN_MAIN_CPU1_EN    
                                  2        GND                     
R2387            Q_RES_0402LF-0,5%,1/16W,CHIP,CA 1        PWRGD_PVNN_MAIN_CPU1_R  
                                  2        PWRGD_PVNN_MAIN_CPU1    
S1               SW8S_DHNF04FTVTR-SW8S_DHNF04FTA 1        PU_ESPI_ENABLE_STRAP    
                                  2        PU_BIOS_RCVR_BOOT       
                                  3        PU_SWAP_OVERRIDE_N      
                                  4        PD_BIOS_IMAGE_SWAP_N    
                                  5        FM_BIOS_IMAGE_SWAP_N    
                                  6        FM_ADR_COMPLETE         
                                  7        FM_PCH_BIOS_RCVR_MODE   
                                  8        JTAG_TRC_PCH_PTI<6>     
S2               SW8S_DHNF04FTVTR-SW8S_DHNF04FTA 1        PU_FLASH_SECURITY_STRAP 
                                  2        PD_RST_RTCRST_N         
                                  3        PD_ME_RCVR_N            
                                  4        PD_PASSWORD_CLEAR       
                                  5        FM_PASSWORD_CLEAR_N     
                                  6        FM_ME_RCVR_N            
                                  7        RST_RTCRST_N            
                                  8        FM_FLASH_SECURITY_STRAP 
U1               SOCKET4677_AZIFS054P001C01-SOCA A9       M_A_CPU1_SB_DQS_DN<3>   
                                  A11      GND                     
                                  A13      GND                     
                                  A15      M_B_CPU1_SB_DQS_DN<3>   
                                  A17      GND                     
                                  A19      GND                     
                                  A21      M_A_CPU1_SB_DQS_DN<2>   
                                  A23      GND                     
                                  A25      GND                     
                                  A27      M_A_CPU1_SB_DQS_DN<1>   
                                  A29      GND                     
                                  A31      GND                     
                                  A33      M_A_CPU1_SB_DQS_DN<9>   
                                  A35      GND                     
                                  A37      GND                     
                                  A39      M_A_CPU1_SB_CA<6>       
                                  A41      GND                     
                                  A43      PWRGD_DRAMPWRGD_CPU1_AB_LVC1_R
                                  A50      GND                     
                                  A52      M_A_CPU1_SA_CA<0>       
                                  A54      GND                     
                                  A56      GND                     
                                  A58      M_A_CPU1_SA_DQS_DN<4>   
                                  A60      GND                     
                                  A62      GND                     
                                  A64      M_A_CPU1_SA_DQS_DN<3>   
                                  AA1      UPI_CPU1_CPU0_P0P1_DN<6>
                                  AA3      PVCCFA_EHV_CPU1         
                                  AA5      UPI_CPU0_CPU1_P1P0_DN<5>
                                  AA7      PVCCFA_EHV_FIVRA_CPU1   
                                  AA9      P5E_CPU1_PE0_RX_DN<10>  
                                  AA11     PVCCFA_EHV_FIVRA_CPU1   
                                  AA13     P5E_CPU1_PE0_TX_DN<11>  
                                  AA15     PVCCFA_EHV_FIVRA_CPU1   
                                  AA17     M_C_CPU1_SB_DQ<28>      
                                  AA19     GND                     
                                  AA21     M_C_CPU1_SB_DQS_DP<7>   
                                  AA23     GND                     
                                  AA25     GND                     
                                  AA27     M_B_CPU1_SB_DQS_DP<5>   
                                  AA29     GND                     
                                  AA31     GND                     
                                  AA33     M_C_CPU1_SB_DQS_DP<4>   
                                  AA35     GND                     
                                  AA37     GND                     
                                  AA39     M_C_CPU1_SB_PAR         
                                  AA41     GND                     
                                  AA43     GND                     
                                  AA45     M_B_CPU1_CLK_DP<1>      
                                  AA48     GND                     
                                  AA50     GND                     
                                  AA52     M_C_CPU1_SA_CA<1>       
                                  AA54     GND                     
                                  AA56     GND                     
                                  AA58     M_B_CPU1_SA_DQS_DN<8>   
                                  AA60     GND                     
                                  AA62     GND                     
                                  AA64     M_C_CPU1_SA_DQS_DN<7>   
                                  AA66     GND                     
                                  AA68     GND                     
                                  AA70     M_B_CPU1_SA_DQS_DN<6>   
                                  AA72     GND                     
                                  AA74     GND                     
                                  AA76     M_C_CPU1_SA_DQS_DP<5>   
                                  AA78     GND                     
                                  AA80     GND                     
                                  AA82     GND                     
                                  AA84     GND                     
                                  AA86     P5E_CPU1_PE4_TX_DN<10>  
                                  AA88     GND                     
                                  AA90     P5E_CPU1_PE4_RX_DP<10>  
                                  AB2      UPI_CPU1_CPU0_P0P1_DP<6>
                                  AB4      GND                     
                                  AB6      UPI_CPU0_CPU1_P1P0_DN<6>
                                  AB8      GND                     
                                  AB10     P5E_CPU1_PE0_RX_DN<9>   
                                  AB12     GND                     
                                  AB14     P5E_CPU1_PE0_TX_DN<10>  
                                  AB16     GND                     
                                  AB18     M_C_CPU1_SB_DQS_DN<3>   
                                  AB20     GND                     
                                  AB22     GND                     
                                  AB24     M_D_CPU1_SB_DQS_DN<2>   
                                  AB26     GND                     
                                  AB28     GND                     
                                  AB30     M_C_CPU1_SB_DQS_DN<1>   
                                  AB32     GND                     
                                  AB34     GND                     
                                  AB36     M_C_CPU1_SB_DQS_DN<0>   
                                  AB38     GND                     
                                  AB40     GND                     
                                  AB42     M_D_CPU1_SB_CA<6>       
                                  AB44     GND                     
                                  AB47     GND                     
                                  AB49     M_C_CPU1_CLK_DN<0>      
                                  AB51     GND                     
                                  AB53     GND                     
                                  AB55     M_C_CPU1_SA_DQS_DP<4>   
                                  AB57     GND                     
                                  AB59     GND                     
                                  AB61     M_C_CPU1_SA_DQS_DN<3>   
                                  AB63     GND                     
                                  AB65     GND                     
                                  AB67     M_C_CPU1_SA_DQS_DN<1>   
                                  AB69     GND                     
                                  AB71     GND                     
                                  AB73     M_D_CPU1_SA_DQS_DN<0>   
                                  AB75     GND                     
                                  AB77     GND                     
                                  AB79     GND                     
                                  AB81     GND                     
                                  AB83     GND                     
                                  AB85     P5E_CPU1_PE4_TX_DP<10>  
                                  AB87     GND                     
                                  AB89     P5E_CPU1_PE4_RX_DN<10>  
                                  AB91     GND                     
                                  AC1      GND                     
                                  AC3      UPI_CPU1_CPU0_P0P1_DP<7>
                                  AC5      GND                     
                                  AC7      UPI_CPU0_CPU1_P1P0_DP<6>
                                  AC9      GND                     
                                  AC11     P5E_CPU1_PE0_RX_DP<9>   
                                  AC13     GND                     
                                  AC15     P5E_CPU1_PE0_TX_DP<10>  
                                  AC17     M_C_CPU1_SB_DQ<30>      
                                  AC19     M_C_CPU1_SB_DQ<25>      
                                  AC21     GND                     
                                  AC23     M_D_CPU1_SB_DQ<20>      
                                  AC25     M_D_CPU1_SB_DQ<17>      
                                  AC27     GND                     
                                  AC29     M_C_CPU1_SB_DQ<12>      
                                  AC31     M_C_CPU1_SB_DQ<9>       
                                  AC33     GND                     
                                  AC35     M_C_CPU1_SB_DQ<4>       
                                  AC37     M_C_CPU1_SB_DQ<1>       
                                  AC39     GND                     
                                  AC41     M_D_CPU1_SB_CS_N<0>     
                                  AC43     M_D_CPU1_SB_CA<4>       
                                  AC45     GND                     
                                  AC48     M_C_CPU1_SA_RSP<0>      
                                  AC50     M_D_CPU1_SA_RSP<1>      
                                  AC52     GND                     
                                  AC54     M_C_CPU1_SA_CB<4>       
                                  AC56     M_C_CPU1_SA_CB<1>       
                                  AC58     GND                     
                                  AC60     M_C_CPU1_SA_DQ<28>      
                                  AC62     M_C_CPU1_SA_DQ<25>      
                                  AC64     GND                     
                                  AC66     M_C_CPU1_SA_DQ<12>      
                                  AC68     M_C_CPU1_SA_DQ<9>       
                                  AC70     GND                     
                                  AC72     M_D_CPU1_SA_DQ<4>       
                                  AC74     M_D_CPU1_SA_DQ<1>       
                                  AC76     GND                     
                                  AC80     UPI_CPU0_CPU1_P2P2_DN<6>
                                  AC82     UPI_CPU0_CPU1_P2P2_DP<7>
                                  AC84     GND                     
                                  AC86     P5E_CPU1_PE4_TX_DN<9>   
                                  AC88     GND                     
                                  AC90     P5E_CPU1_PE4_RX_DP<9>   
                                  AD2      UPI_CPU1_CPU0_P0P1_DN<7>
                                  AD4      GND                     
                                  AD6      UPI_CPU0_CPU1_P1P0_DP<7>
                                  AD8      GND                     
                                  AD10     P5E_CPU1_PE0_RX_DP<8>   
                                  AD12     GND                     
                                  AD14     P5E_CPU1_PE0_TX_DP<9>   
                                  AD16     GND                     
                                  AD18     M_C_CPU1_SB_DQS_DP<3>   
                                  AD20     M_C_CPU1_SB_DQ<24>      
                                  AD22     M_D_CPU1_SB_DQ<21>      
                                  AD24     M_D_CPU1_SB_DQS_DP<2>   
                                  AD26     M_D_CPU1_SB_DQ<16>      
                                  AD28     M_C_CPU1_SB_DQ<13>      
                                  AD30     M_C_CPU1_SB_DQS_DP<1>   
                                  AD32     M_C_CPU1_SB_DQ<8>       
                                  AD34     M_C_CPU1_SB_DQ<5>       
                                  AD36     M_C_CPU1_SB_DQS_DP<0>   
                                  AD38     M_C_CPU1_SB_DQ<0>       
                                  AD40     M_D_CPU1_SB_CS_N<3>     
                                  AD42     GND                     
                                  AD44     M_D_CPU1_SB_CA<2>       
                                  AD47     M_C_CPU1_SA_RSP<1>      
                                  AD49     M_C_CPU1_CLK_DP<0>      
                                  AD51     M_D_CPU1_SA_RSP<0>      
                                  AD53     M_C_CPU1_SA_CB<5>       
                                  AD55     M_C_CPU1_SA_DQS_DN<4>   
                                  AD57     M_C_CPU1_SA_CB<0>       
                                  AD59     M_C_CPU1_SA_DQ<29>      
                                  AD61     M_C_CPU1_SA_DQS_DP<3>   
                                  AD63     M_C_CPU1_SA_DQ<24>      
                                  AD65     M_C_CPU1_SA_DQ<13>      
                                  AD67     M_C_CPU1_SA_DQS_DP<1>   
                                  AD69     M_C_CPU1_SA_DQ<8>       
                                  AD71     M_D_CPU1_SA_DQ<5>       
                                  AD73     M_D_CPU1_SA_DQS_DP<0>   
                                  AD75     M_D_CPU1_SA_DQ<0>       
                                  AD79     GND                     
                                  AD81     UPI_CPU0_CPU1_P2P2_DN<7>
                                  AD83     GND                     
                                  AD85     PVCCFA_EHV_FIVRA_CPU1   
                                  AD87     P5E_CPU1_PE4_TX_DP<9>   
                                  AD89     PVCCFA_EHV_FIVRA_CPU1   
                                  AD91     P5E_CPU1_PE4_RX_DN<9>   
                                  AE1      UPI_CPU1_CPU0_P0P1_DP<8>
                                  AE3      PVCCFA_EHV_CPU1         
                                  AE5      UPI_CPU0_CPU1_P1P0_DN<7>
                                  AE7      PVCCFA_EHV_FIVRA_CPU1   
                                  AE9      P5E_CPU1_PE0_RX_DN<8>   
                                  AE11     PVCCFA_EHV_FIVRA_CPU1   
                                  AE13     P5E_CPU1_PE0_TX_DN<9>   
                                  AE15     PVCCFA_EHV_FIVRA_CPU1   
                                  AE17     GND                     
                                  AE19     GND                     
                                  AE21     GND                     
                                  AE23     GND                     
                                  AE25     GND                     
                                  AE27     GND                     
                                  AE29     GND                     
                                  AE31     GND                     
                                  AE33     GND                     
                                  AE35     GND                     
                                  AE37     GND                     
                                  AE39     GND                     
                                  AE41     GND                     
                                  AE43     GND                     
                                  AE45     GND                     
                                  AE48     GND                     
                                  AE50     GND                     
                                  AE52     GND                     
                                  AE54     GND                     
                                  AE56     GND                     
                                  AE58     GND                     
                                  AE60     GND                     
                                  AE62     GND                     
                                  AE64     GND                     
                                  AE66     GND                     
                                  AE68     GND                     
                                  AE70     GND                     
                                  AE72     GND                     
                                  AE74     GND                     
                                  AE76     GND                     
                                  AE78     GND                     
                                  AE80     UPI_CPU0_CPU1_P2P2_DP<6>
                                  AE82     UPI_CPU0_CPU1_P2P2_DN<9>
                                  AE84     GND                     
                                  AE86     P5E_CPU1_PE4_TX_DN<8>   
                                  AE88     GND                     
                                  AE90     P5E_CPU1_PE4_RX_DP<8>   
                                  AF2      UPI_CPU1_CPU0_P0P1_DN<8>
                                  AF4      GND                     
                                  AF6      UPI_CPU0_CPU1_P1P0_DN<8>
                                  AF8      GND                     
                                  AF10     P5E_CPU1_PE0_RX_DN<7>   
                                  AF12     GND                     
                                  AF14     P5E_CPU1_PE0_TX_DN<8>   
                                  AF16     GND                     
                                  AF18     M_C_CPU1_SB_DQS_DN<8>   
                                  AF20     M_C_CPU1_SB_DQ<26>      
                                  AF22     M_D_CPU1_SB_DQ<23>      
                                  AF24     M_D_CPU1_SB_DQS_DN<7>   
                                  AF26     M_D_CPU1_SB_DQ<18>      
                                  AF28     M_C_CPU1_SB_DQ<15>      
                                  AF30     M_C_CPU1_SB_DQS_DN<6>   
                                  AF32     M_C_CPU1_SB_DQ<10>      
                                  AF34     M_C_CPU1_SB_DQ<7>       
                                  AF36     M_C_CPU1_SB_DQS_DN<5>   
                                  AF38     M_C_CPU1_SB_DQ<2>       
                                  AF40     M_D_CPU1_SB_CS_N<2>     
                                  AF42     GND                     
                                  AF44     M_D_CPU1_SB_CA<3>       
                                  AF47     M_C_CPU1_SB_RSP<1>      
                                  AF49     M_C_CPU1_CLK_DN<1>      
                                  AF51     M_D_CPU1_SB_RSP<0>      
                                  AF53     M_C_CPU1_SA_CB<7>       
                                  AF55     M_C_CPU1_SA_DQS_DP<9>   
                                  AF57     M_C_CPU1_SA_CB<2>       
                                  AF59     M_C_CPU1_SA_DQ<31>      
                                  AF61     M_C_CPU1_SA_DQS_DN<8>   
                                  AF63     M_C_CPU1_SA_DQ<26>      
                                  AF65     M_C_CPU1_SA_DQ<15>      
                                  AF67     M_C_CPU1_SA_DQS_DP<6>   
                                  AF69     M_C_CPU1_SA_DQ<10>      
                                  AF71     M_D_CPU1_SA_DQ<7>       
                                  AF73     M_D_CPU1_SA_DQS_DP<5>   
                                  AF75     M_D_CPU1_SA_DQ<2>       
                                  AF77     PVCCFA_EHV_FIVRA_CPU1   
                                  AF79     UPI_CPU0_CPU1_P2P2_DN<8>
                                  AF81     GND                     
                                  AF83     UPI_CPU0_CPU1_P2P2_DP<9>
                                  AF85     P5E_CPU1_PE4_TX_DP<8>   
                                  AF87     GND                     
                                  AF89     P5E_CPU1_PE4_RX_DN<8>   
                                  AF91     GND                     
                                  AG1      GND                     
                                  AG3      UPI_CPU1_CPU0_P0P1_DP<9>
                                  AG5      GND                     
                                  AG7      UPI_CPU0_CPU1_P1P0_DP<8>
                                  AG9      GND                     
                                  AG11     P5E_CPU1_PE0_RX_DP<7>   
                                  AG13     GND                     
                                  AG15     P5E_CPU1_PE0_TX_DP<8>   
                                  AG17     M_C_CPU1_SB_DQ<29>      
                                  AG19     M_C_CPU1_SB_DQ<27>      
                                  AG21     GND                     
                                  AG23     M_D_CPU1_SB_DQ<22>      
                                  AG25     M_D_CPU1_SB_DQ<19>      
                                  AG27     GND                     
                                  AG29     M_C_CPU1_SB_DQ<14>      
                                  AG31     M_C_CPU1_SB_DQ<11>      
                                  AG33     GND                     
                                  AG35     M_C_CPU1_SB_DQ<6>       
                                  AG37     M_C_CPU1_SB_DQ<3>       
                                  AG39     GND                     
                                  AG41     M_D_CPU1_SB_CS_N<1>     
                                  AG43     M_D_CPU1_SB_CA<5>       
                                  AG45     GND                     
                                  AG48     M_C_CPU1_SB_RSP<0>      
                                  AG50     M_D_CPU1_SB_RSP<1>      
                                  AG52     GND                     
                                  AG54     M_C_CPU1_SA_CB<6>       
                                  AG56     M_C_CPU1_SA_CB<3>       
                                  AG58     GND                     
                                  AG60     M_C_CPU1_SA_DQ<30>      
                                  AG62     M_C_CPU1_SA_DQ<27>      
                                  AG64     GND                     
                                  AG66     M_C_CPU1_SA_DQ<14>      
                                  AG68     M_C_CPU1_SA_DQ<11>      
                                  AG70     GND                     
                                  AG72     M_D_CPU1_SA_DQ<6>       
                                  AG74     M_D_CPU1_SA_DQ<3>       
                                  AG76     GND                     
                                  AG78     PVCCFA_EHV_FIVRA_CPU1   
                                  AG80     UPI_CPU0_CPU1_P2P2_DP<8>
                                  AG82     UPI_CPU0_CPU1_P2P2_DN<11>
                                  AG84     GND                     
                                  AG86     P5E_CPU1_PE4_TX_DN<7>   
                                  AG88     GND                     
                                  AG90     P5E_CPU1_PE4_RX_DP<7>   
                                  AH2      UPI_CPU1_CPU0_P0P1_DN<9>
                                  AH4      GND                     
                                  AH6      UPI_CPU0_CPU1_P1P0_DN<9>
                                  AH8      GND                     
                                  AH10     P5E_CPU1_PE0_RX_DP<6>   
                                  AH12     GND                     
                                  AH14     P5E_CPU1_PE0_TX_DP<7>   
                                  AH16     GND                     
                                  AH18     M_C_CPU1_SB_DQS_DP<8>   
                                  AH20     GND                     
                                  AH22     GND                     
                                  AH24     M_D_CPU1_SB_DQS_DP<7>   
                                  AH26     GND                     
                                  AH28     GND                     
                                  AH30     M_C_CPU1_SB_DQS_DP<6>   
                                  AH32     GND                     
                                  AH34     GND                     
                                  AH36     M_C_CPU1_SB_DQS_DP<5>   
                                  AH38     GND                     
                                  AH40     GND                     
                                  AH42     M_D_CPU1_SB_PAR         
                                  AH44     GND                     
                                  AH47     GND                     
                                  AH49     M_C_CPU1_CLK_DP<1>      
                                  AH51     GND                     
                                  AH53     GND                     
                                  AH55     M_C_CPU1_SA_DQS_DN<9>   
                                  AH57     GND                     
                                  AH59     GND                     
                                  AH61     M_C_CPU1_SA_DQS_DP<8>   
                                  AH63     GND                     
                                  AH65     GND                     
                                  AH67     M_C_CPU1_SA_DQS_DN<6>   
                                  AH69     GND                     
                                  AH71     GND                     
                                  AH73     M_D_CPU1_SA_DQS_DN<5>   
                                  AH75     GND                     
                                  AH77     GND                     
                                  AH79     GND                     
                                  AH81     UPI_CPU0_CPU1_P2P2_DP<10>
                                  AH83     GND                     
                                  AH85     PVCCFA_EHV_FIVRA_CPU1   
                                  AH87     P5E_CPU1_PE4_TX_DP<7>   
                                  AH89     PVCCFA_EHV_FIVRA_CPU1   
                                  AH91     P5E_CPU1_PE4_RX_DN<7>   
                                  AJ1      UPI_CPU1_CPU0_P0P1_DP<10>
                                  AJ3      PVCCFA_EHV_CPU1         
                                  AJ5      UPI_CPU0_CPU1_P1P0_DP<9>
                                  AJ7      PVCCFA_EHV_FIVRA_CPU1   
                                  AJ9      P5E_CPU1_PE0_RX_DN<6>   
                                  AJ11     PVCCFA_EHV_FIVRA_CPU1   
                                  AJ13     P5E_CPU1_PE0_TX_DN<7>   
                                  AJ15     PVCCFA_EHV_FIVRA_CPU1   
                                  AJ17     M_C_CPU1_SB_DQ<31>      
                                  AJ19     GND                     
                                  AJ21     M_D_CPU1_SB_DQS_DN<3>   
                                  AJ23     GND                     
                                  AJ25     GND                     
                                  AJ27     M_D_CPU1_SB_DQS_DN<1>   
                                  AJ29     GND                     
                                  AJ31     GND                     
                                  AJ33     M_D_CPU1_SB_DQS_DN<0>   
                                  AJ35     GND                     
                                  AJ37     GND                     
                                  AJ39     M_D_CPU1_SB_DQS_DN<9>   
                                  AJ41     GND                     
                                  AJ43     GND                     
                                  AJ45     M_D_CPU1_CLK_DN<0>      
                                  AJ48     GND                     
                                  AJ50     GND                     
                                  AJ52     M_D_CPU1_SA_CA<0>       
                                  AJ54     GND                     
                                  AJ56     GND                     
                                  AJ58     M_D_CPU1_SA_DQS_DN<4>   
                                  AJ60     GND                     
                                  AJ62     GND                     
                                  AJ64     M_D_CPU1_SA_DQS_DN<3>   
                                  AJ66     GND                     
                                  AJ68     GND                     
                                  AJ70     M_D_CPU1_SA_DQS_DN<2>   
                                  AJ72     GND                     
                                  AJ74     GND                     
                                  AJ76     M_D_CPU1_SA_DQS_DN<1>   
                                  AJ78     GND                     
                                  AJ80     UPI_CPU0_CPU1_P2P2_DN<10>
                                  AJ82     UPI_CPU0_CPU1_P2P2_DP<11>
                                  AJ84     GND                     
                                  AJ86     P5E_CPU1_PE4_TX_DN<6>   
                                  AJ88     GND                     
                                  AJ90     P5E_CPU1_PE4_RX_DP<6>   
                                  AK2      UPI_CPU1_CPU0_P0P1_DN<10>
                                  AK4      GND                     
                                  AK6      UPI_CPU0_CPU1_P1P0_DN<10>
                                  AK8      GND                     
                                  AK10     P5E_CPU1_PE0_RX_DN<5>   
                                  AK12     GND                     
                                  AK14     P5E_CPU1_PE0_TX_DN<6>   
                                  AK16     GND                     
                                  AK18     GND                     
                                  AK20     M_D_CPU1_SB_DQ<28>      
                                  AK22     M_D_CPU1_SB_DQ<25>      
                                  AK24     GND                     
                                  AK26     M_D_CPU1_SB_DQ<12>      
                                  AK28     M_D_CPU1_SB_DQ<9>       
                                  AK30     GND                     
                                  AK32     M_D_CPU1_SB_DQ<4>       
                                  AK34     M_D_CPU1_SB_DQ<1>       
                                  AK36     GND                     
                                  AK38     M_D_CPU1_SB_CB<0>       
                                  AK40     M_D_CPU1_SB_CB<5>       
                                  AK42     GND                     
                                  AK44     M_D_CPU1_SB_CA<0>       
                                  AK47     M_B_CPU1_SA_RSP<1>      
                                  AK49     GND                     
                                  AK51     M_D_CPU1_SA_CA<2>       
                                  AK53     M_D_CPU1_SA_CS_N<1>     
                                  AK55     GND                     
                                  AK57     M_D_CPU1_SA_CB<4>       
                                  AK59     M_D_CPU1_SA_CB<1>       
                                  AK61     GND                     
                                  AK63     M_D_CPU1_SA_DQ<28>      
                                  AK65     M_D_CPU1_SA_DQ<25>      
                                  AK67     GND                     
                                  AK69     M_D_CPU1_SA_DQ<20>      
                                  AK71     M_D_CPU1_SA_DQ<17>      
                                  AK73     GND                     
                                  AK75     M_D_CPU1_SA_DQ<12>      
                                  AK77     M_D_CPU1_SA_DQ<9>       
                                  AK79     GND                     
                                  AK81     GND                     
                                  AK83     GND                     
                                  AK85     P5E_CPU1_PE4_TX_DP<6>   
                                  AK87     GND                     
                                  AK89     P5E_CPU1_PE4_RX_DN<6>   
                                  AK91     GND                     
                                  AL1      GND                     
                                  AL3      UPI_CPU1_CPU0_P0P1_DP<11>
                                  AL5      GND                     
                                  AL7      UPI_CPU0_CPU1_P1P0_DP<10>
                                  AL9      GND                     
                                  AL11     P5E_CPU1_PE0_RX_DP<5>   
                                  AL13     GND                     
                                  AL15     P5E_CPU1_PE0_TX_DP<6>   
                                  AL17     GND                     
                                  AL19     M_D_CPU1_SB_DQ<29>      
                                  AL21     M_D_CPU1_SB_DQS_DP<3>   
                                  AL23     M_D_CPU1_SB_DQ<24>      
                                  AL25     M_D_CPU1_SB_DQ<13>      
                                  AL27     M_D_CPU1_SB_DQS_DP<1>   
                                  AL29     M_D_CPU1_SB_DQ<8>       
                                  AL31     M_D_CPU1_SB_DQ<5>       
                                  AL33     M_D_CPU1_SB_DQS_DP<0>   
                                  AL35     M_D_CPU1_SB_DQ<0>       
                                  AL37     M_D_CPU1_SB_CB<1>       
                                  AL39     M_D_CPU1_SB_DQS_DP<9>   
                                  AL41     M_D_CPU1_SB_CB<4>       
                                  AL43     M_D_CPU1_SB_CA<1>       
                                  AL45     M_D_CPU1_CLK_DP<0>      
                                  AL48     M_B_CPU1_SA_RSP<0>      
                                  AL50     M_D_CPU1_SA_CA<4>       
                                  AL52     GND                     
                                  AL54     M_D_CPU1_SA_CS_N<0>     
                                  AL56     M_D_CPU1_SA_CB<5>       
                                  AL58     M_D_CPU1_SA_DQS_DP<4>   
                                  AL60     M_D_CPU1_SA_CB<0>       
                                  AL62     M_D_CPU1_SA_DQ<29>      
                                  AL64     M_D_CPU1_SA_DQS_DP<3>   
                                  AL66     M_D_CPU1_SA_DQ<24>      
                                  AL68     M_D_CPU1_SA_DQ<21>      
                                  AL70     M_D_CPU1_SA_DQS_DP<2>   
                                  AL72     M_D_CPU1_SA_DQ<16>      
                                  AL74     M_D_CPU1_SA_DQ<13>      
                                  AL76     M_D_CPU1_SA_DQS_DP<1>   
                                  AL78     M_D_CPU1_SA_DQ<8>       
                                  AL80     GND                     
                                  AL82     GND                     
                                  AL84     GND                     
                                  AL86     P5E_CPU1_PE4_TX_DN<5>   
                                  AL88     GND                     
                                  AL90     P5E_CPU1_PE4_RX_DP<5>   
                                  AM2      UPI_CPU1_CPU0_P0P1_DN<11>
                                  AM4      GND                     
                                  AM6      UPI_CPU0_CPU1_P1P0_DP<11>
                                  AM8      GND                     
                                  AM10     P5E_CPU1_PE0_RX_DN<4>   
                                  AM12     GND                     
                                  AM14     P5E_CPU1_PE0_TX_DP<5>   
                                  AM16     GND                     
                                  AM18     GND                     
                                  AM20     GND                     
                                  AM22     GND                     
                                  AM24     GND                     
                                  AM26     GND                     
                                  AM28     GND                     
                                  AM30     GND                     
                                  AM32     GND                     
                                  AM34     GND                     
                                  AM36     GND                     
                                  AM38     GND                     
                                  AM40     GND                     
                                  AM42     GND                     
                                  AM44     GND                     
                                  AM47     GND                     
                                  AM49     GND                     
                                  AM51     GND                     
                                  AM53     GND                     
                                  AM55     GND                     
                                  AM57     GND                     
                                  AM59     GND                     
                                  AM61     GND                     
                                  AM63     GND                     
                                  AM65     GND                     
                                  AM67     GND                     
                                  AM69     GND                     
                                  AM71     GND                     
                                  AM73     GND                     
                                  AM75     GND                     
                                  AM77     GND                     
                                  AM79     PVCCFA_EHV_FIVRA_CPU1   
                                  AM81     UPI_CPU1_CPU0_P2P2_DN<12>
                                  AM83     UPI_CPU1_CPU0_P2P2_DP<13>
                                  AM85     PVCCFA_EHV_FIVRA_CPU1   
                                  AM87     P5E_CPU1_PE4_TX_DP<5>   
                                  AM89     PVCCFA_EHV_FIVRA_CPU1   
                                  AM91     P5E_CPU1_PE4_RX_DN<5>   
                                  AN1      UPI_CPU1_CPU0_P0P1_DP<12>
                                  AN3      PVCCFA_EHV_CPU1         
                                  AN5      UPI_CPU0_CPU1_P1P0_DN<11>
                                  AN7      PVCCFA_EHV_FIVRA_CPU1   
                                  AN9      P5E_CPU1_PE0_RX_DP<4>   
                                  AN11     PVCCFA_EHV_FIVRA_CPU1   
                                  AN13     P5E_CPU1_PE0_TX_DN<5>   
                                  AN15     PVCCFA_EHV_FIVRA_CPU1   
                                  AN19     M_D_CPU1_SB_DQ<31>      
                                  AN21     M_D_CPU1_SB_DQS_DN<8>   
                                  AN23     M_D_CPU1_SB_DQ<26>      
                                  AN25     M_D_CPU1_SB_DQ<15>      
                                  AN27     M_D_CPU1_SB_DQS_DN<6>   
                                  AN29     M_D_CPU1_SB_DQ<10>      
                                  AN31     M_D_CPU1_SB_DQ<7>       
                                  AN33     M_D_CPU1_SB_DQS_DN<5>   
                                  AN35     M_D_CPU1_SB_DQ<2>       
                                  AN37     M_D_CPU1_SB_CB<3>       
                                  AN39     M_D_CPU1_SB_DQS_DP<4>   
                                  AN41     M_D_CPU1_SB_CB<6>       
                                  AN43     M_D_CPU1_SA_CA<6>       
                                  AN45     M_D_CPU1_CLK_DN<1>      
                                  AN48     M_B_CPU1_SB_RSP<0>      
                                  AN50     M_D_CPU1_SA_CA<5>       
                                  AN52     GND                     
                                  AN54     M_D_CPU1_SA_CS_N<2>     
                                  AN56     M_D_CPU1_SA_CB<7>       
                                  AN58     M_D_CPU1_SA_DQS_DN<9>   
                                  AN60     M_D_CPU1_SA_CB<2>       
                                  AN62     M_D_CPU1_SA_DQ<31>      
                                  AN64     M_D_CPU1_SA_DQS_DN<8>   
                                  AN66     M_D_CPU1_SA_DQ<26>      
                                  AN68     M_D_CPU1_SA_DQ<23>      
                                  AN70     M_D_CPU1_SA_DQS_DN<7>   
                                  AN72     M_D_CPU1_SA_DQ<18>      
                                  AN74     M_D_CPU1_SA_DQ<15>      
                                  AN76     M_D_CPU1_SA_DQS_DN<6>   
                                  AN78     M_D_CPU1_SA_DQ<10>      
                                  AN80     PVCCFA_EHV_FIVRA_CPU1   
                                  AN82     UPI_CPU1_CPU0_P2P2_DN<13>
                                  AN84     GND                     
                                  AN86     P5E_CPU1_PE4_TX_DP<4>   
                                  AN88     GND                     
                                  AN90     P5E_CPU1_PE4_RX_DP<4>   
                                  AP2      UPI_CPU1_CPU0_P0P1_DN<12>
                                  AP4      GND                     
                                  AP6      UPI_CPU0_CPU1_P1P0_DN<12>
                                  AP8      GND                     
                                  AP10     P5E_CPU1_PE0_RX_DN<3>   
                                  AP12     GND                     
                                  AP14     P5E_CPU1_PE0_TX_DN<4>   
                                  AP16     GND                     
                                  AP18     GND                     
                                  AP20     M_D_CPU1_SB_DQ<30>      
                                  AP22     M_D_CPU1_SB_DQ<27>      
                                  AP24     GND                     
                                  AP26     M_D_CPU1_SB_DQ<14>      
                                  AP28     M_D_CPU1_SB_DQ<11>      
                                  AP30     GND                     
                                  AP32     M_D_CPU1_SB_DQ<6>       
                                  AP34     M_D_CPU1_SB_DQ<3>       
                                  AP36     GND                     
                                  AP38     M_D_CPU1_SB_CB<2>       
                                  AP40     M_D_CPU1_SB_CB<7>       
                                  AP42     GND                     
                                  AP44     M_D_CPU1_SA_PAR         
                                  AP47     M_B_CPU1_SB_RSP<1>      
                                  AP49     GND                     
                                  AP51     M_D_CPU1_SA_CA<3>       
                                  AP53     M_D_CPU1_SA_CS_N<3>     
                                  AP55     GND                     
                                  AP57     M_D_CPU1_SA_CB<6>       
                                  AP59     M_D_CPU1_SA_CB<3>       
                                  AP61     GND                     
                                  AP63     M_D_CPU1_SA_DQ<30>      
                                  AP65     M_D_CPU1_SA_DQ<27>      
                                  AP67     GND                     
                                  AP69     M_D_CPU1_SA_DQ<22>      
                                  AP71     M_D_CPU1_SA_DQ<19>      
                                  AP73     GND                     
                                  AP75     M_D_CPU1_SA_DQ<14>      
                                  AP77     M_D_CPU1_SA_DQ<11>      
                                  AP79     GND                     
                                  AP81     UPI_CPU1_CPU0_P2P2_DP<12>
                                  AP83     GND                     
                                  AP85     P5E_CPU1_PE4_TX_DN<4>   
                                  AP87     GND                     
                                  AP89     P5E_CPU1_PE4_RX_DN<4>   
                                  AP91     GND                     
                                  AR1      GND                     
                                  AR3      UPI_CPU1_CPU0_P0P1_DP<13>
                                  AR5      GND                     
                                  AR7      UPI_CPU0_CPU1_P1P0_DP<12>
                                  AR9      GND                     
                                  AR11     P5E_CPU1_PE0_RX_DP<3>   
                                  AR13     GND                     
                                  AR15     P5E_CPU1_PE0_TX_DP<4>   
                                  AR19     GND                     
                                  AR21     M_D_CPU1_SB_DQS_DP<8>   
                                  AR23     GND                     
                                  AR25     GND                     
                                  AR27     M_D_CPU1_SB_DQS_DP<6>   
                                  AR29     GND                     
                                  AR31     GND                     
                                  AR33     M_D_CPU1_SB_DQS_DP<5>   
                                  AR35     GND                     
                                  AR37     GND                     
                                  AR39     M_D_CPU1_SB_DQS_DN<4>   
                                  AR41     GND                     
                                  AR43     GND                     
                                  AR45     M_D_CPU1_CLK_DP<1>      
                                  AR48     GND                     
                                  AR50     GND                     
                                  AR52     M_D_CPU1_SA_CA<1>       
                                  AR54     GND                     
                                  AR56     GND                     
                                  AR58     M_D_CPU1_SA_DQS_DP<9>   
                                  AR60     GND                     
                                  AR62     GND                     
                                  AR64     M_D_CPU1_SA_DQS_DP<8>   
                                  AR66     GND                     
                                  AR68     GND                     
                                  AR70     M_D_CPU1_SA_DQS_DP<7>   
                                  AR72     GND                     
                                  AR74     GND                     
                                  AR76     M_D_CPU1_SA_DQS_DP<6>   
                                  AR78     GND                     
                                  AR80     UPI_CPU1_CPU0_P2P2_DN<14>
                                  AR82     GND                     
                                  AR84     GND                     
                                  AR86     P5E_CPU1_PE4_TX_DN<3>   
                                  AR88     GND                     
                                  AR90     P5E_CPU1_PE4_RX_DP<3>   
                                  AT2      UPI_CPU1_CPU0_P0P1_DN<13>
                                  AT4      GND                     
                                  AT6      UPI_CPU0_CPU1_P1P0_DP<13>
                                  AT8      GND                     
                                  AT10     P5E_CPU1_PE0_RX_DP<2>   
                                  AT12     GND                     
                                  AT14     P5E_CPU1_PE0_TX_DP<3>   
                                  AT16     GND                     
                                  AT18     PD_CPU1_BIST_ENABLE     
                                  AT20     GND                     
                                  AT22     GND                     
                                  AT26     GND                     
                                  AT28     GND                     
                                  AT30     CLK_100M_DB2000_CPU1_BCLK0_DN
                                  AT32     GND                     
                                  AT34     GND                     
                                  AT36     PVCCD_HV_CPU1           
                                  AT38     GND                     
                                  AT40     GND                     
                                  AT42     M_A_CPU1_SA_RSP<0>      
                                  AT44     GND                     
                                  AT47     M_C_CPU1_ALERT_N        
                                  AT49     M_A_CPU1_ALERT_N        
                                  AT51     GND                     
                                  AT53     GND                     
                                  AT55     PVCCD_HV_CPU1           
                                  AT57     GND                     
                                  AT59     GND                     
                                  AT61     PVCCFA_EHV_CPU1         
                                  AT63     GND                     
                                  AT65     GND                     
                                  AT69     GND                     
                                  AT71     GND                     
                                  AT73     PVCCFA_EHV_FIVRA_CPU1   
                                  AT75     GND                     
                                  AT77     GND                     
                                  AT79     GND                     
                                  AT81     UPI_CPU1_CPU0_P2P2_DP<14>
                                  AT83     UPI_CPU1_CPU0_P2P2_DN<15>
                                  AT85     VSENSE_PVCCFA_EHV_FIVRA_CPU1_DN
                                  AT87     P5E_CPU1_PE4_TX_DP<3>   
                                  AT89     PVCCFA_EHV_FIVRA_CPU1   
                                  AT91     P5E_CPU1_PE4_RX_DN<3>   
                                  AU1      UPI_CPU1_CPU0_P0P1_DN<14>
                                  AU3      PVCCD_HV_CPU1           
                                  AU5      UPI_CPU0_CPU1_P1P0_DN<13>
                                  AU7      PVCCD_HV_CPU1           
                                  AU9      P5E_CPU1_PE0_RX_DN<2>   
                                  AU11     VSENSE_PVCCFA_EHV_CPU1_DP
                                  AU13     P5E_CPU1_PE0_TX_DN<3>   
                                  AU15     PVCCFA_EHV_FIVRA_CPU1   
                                  AU17     PU_CPU1_FRMAGENT        
                                  AU19     H_CPU1_PROCHOT_LVC1_N   
                                  AU21     H_CPU1_MEMHOT_IN_LVC1_N 
                                  AU23     PU_CPU1_SAFE_MODE_BOOT  
                                  AU27     GND                     
                                  AU29     CLK_100M_DB2000_CPU1_BCLK2_DN
                                  AU31     GND                     
                                  AU35     PVCCD_HV_CPU1           
                                  AU37     GND                     
                                  AU39     GND                     
                                  AU41     GND                     
                                  AU43     M_A_CPU1_SA_RSP<1>      
                                  AU45     GND                     
                                  AU48     GND                     
                                  AU50     RST_CPU1_DRAM_AB_N      
                                  AU54     PVCCD_HV_CPU1           
                                  AU60     PVCCFA_EHV_CPU1         
                                  AU70     GND                     
                                  AU72     GND                     
                                  AU74     GND                     
                                  AU76     GND                     
                                  AU78     UPI_CPU1_CPU0_P2P2_DN<11>
                                  AU80     GND                     
                                  AU82     UPI_CPU1_CPU0_P2P2_DP<16>
                                  AU84     GND                     
                                  AU86     P5E_CPU1_PE4_TX_DN<2>   
                                  AU88     GND                     
                                  AU90     P5E_CPU1_PE4_RX_DP<2>   
                                  AV2      UPI_CPU1_CPU0_P0P1_DP<14>
                                  AV4      GND                     
                                  AV6      UPI_CPU0_CPU1_P1P0_DN<14>
                                  AV8      GND                     
                                  AV10     P5E_CPU1_PE0_RX_DN<1>   
                                  AV12     GND                     
                                  AV14     P5E_CPU1_PE0_TX_DN<2>   
                                  AV16     GND                     
                                  AV18     H_CPU1_NMI_LVC1_N       
                                  AV20     PWRGD_CPU1_LVC1         
                                  AV22     H_CPU1_PREQ_QS_GTL_R_N  
                                  AV24     H_CPU1_MEMTRIP_LVC1_R_N 
                                  AV28     CLK_100M_DB2000_CPU1_BCLK2_DP
                                  AV30     CLK_100M_DB2000_CPU1_BCLK0_DP
                                  AV34     PVCCD_HV_CPU1           
                                  AV36     PVCCD_HV_CPU1           
                                  AV42     M_A_CPU1_SB_RSP<1>      
                                  AV44     M_A_CPU1_SB_RSP<0>      
                                  AV47     M_D_CPU1_ALERT_N        
                                  AV49     M_B_CPU1_ALERT_N        
                                  AV51     RST_CPU1_DRAM_CD_N      
                                  AV53     PVCCD_HV_CPU1           
                                  AV55     PVCCD_HV_CPU1           
                                  AV57     FM_CPU_FBRK_DEBUG_R_N   
                                  AV61     PVCCFA_EHV_CPU1         
                                  AV69     FM_S3M_CPU1_LVC1_GPIO_2 
                                  AV71     FM_S3M_CPU1_LVC1_GPIO_1 
                                  AV73     UPI_CPU0_CPU1_P2P2_DN<13>
                                  AV75     UPI_CPU0_CPU1_P2P2_DP<16>
                                  AV77     GND                     
                                  AV79     UPI_CPU1_CPU0_P2P2_DP<11>
                                  AV81     UPI_CPU1_CPU0_P2P2_DN<16>
                                  AV83     UPI_CPU1_CPU0_P2P2_DP<15>
                                  AV85     P5E_CPU1_PE4_TX_DP<2>   
                                  AV87     GND                     
                                  AV89     P5E_CPU1_PE4_RX_DN<2>   
                                  AV91     GND                     
                                  AW1      GND                     
                                  AW3      UPI_CPU1_CPU0_P0P1_DP<15>
                                  AW5      GND                     
                                  AW7      UPI_CPU0_CPU1_P1P0_DP<14>
                                  AW9      GND                     
                                  AW11     P5E_CPU1_PE0_RX_DP<1>   
                                  AW13     GND                     
                                  AW15     P5E_CPU1_PE0_TX_DP<2>   
                                  AW17     PD_CPU1_DMIMODE_OVERRIDE
                                  AW21     GND                     
                                  AW23     GND                     
                                  AW25     GND                     
                                  AW60     PVCCFA_EHV_CPU1         
                                  AW62     GND                     
                                  AW66     GND                     
                                  AW68     GND                     
                                  AW70     FM_S3M_CPU1_LVC1_GPIO_4 
                                  AW72     GND                     
                                  AW74     UPI_CPU0_CPU1_P2P2_DN<16>
                                  AW76     PVCCFA_EHV_FIVRA_CPU1   
                                  AW78     UPI_CPU1_CPU0_P2P2_DN<10>
                                  AW80     GND                     
                                  AW82     GND                     
                                  AW84     GND                     
                                  AW86     P5E_CPU1_PE4_TX_DN<1>   
                                  AW88     GND                     
                                  AW90     P5E_CPU1_PE4_RX_DP<1>   
                                  AY2      UPI_CPU1_CPU0_P0P1_DN<15>
                                  AY4      GND                     
                                  AY6      UPI_CPU0_CPU1_P1P0_DP<15>
                                  AY8      GND                     
                                  AY10     P5E_CPU1_PE0_RX_DP<0>   
                                  AY12     GND                     
                                  AY14     P5E_CPU1_PE0_TX_DP<1>   
                                  AY16     GND                     
                                  AY18     PVCCINFAON_CPU1         
                                  AY20     PU_TAP_ODT_CPU1_EN      
                                  AY22     H_CPU1_ERR1_LVC1_R_N    
                                  AY63     FM_CPU1_PKGID1          
                                  AY69     FM_S3M_CPU1_LVC1_GPIO_3 
                                  AY71     GND                     
                                  AY73     UPI_CPU0_CPU1_P2P2_DP<13>
                                  AY75     UPI_CPU0_CPU1_P2P2_DN<14>
                                  AY77     GND                     
                                  AY79     GND                     
                                  AY81     GND                     
                                  AY83     GND                     
                                  AY85     VSENSE_PVCCFA_EHV_FIVRA_CPU1_DP
                                  AY87     P5E_CPU1_PE4_TX_DP<1>   
                                  AY89     PVCCFA_EHV_FIVRA_CPU1   
                                  AY91     P5E_CPU1_PE4_RX_DN<1>   
                                  B6       GND                     
                                  B8       M_A_CPU1_SB_DQ<28>      
                                  B10      M_A_CPU1_SB_DQ<25>      
                                  B12      GND                     
                                  B14      M_B_CPU1_SB_DQ<30>      
                                  B16      M_B_CPU1_SB_DQ<25>      
                                  B18      GND                     
                                  B20      M_A_CPU1_SB_DQ<20>      
                                  B22      M_A_CPU1_SB_DQ<17>      
                                  B24      GND                     
                                  B26      M_A_CPU1_SB_DQ<12>      
                                  B28      M_A_CPU1_SB_DQ<9>       
                                  B30      GND                     
                                  B32      M_A_CPU1_SB_CB<0>       
                                  B34      M_A_CPU1_SB_CB<5>       
                                  B36      GND                     
                                  B38      M_A_CPU1_SB_CS_N<0>     
                                  B40      M_A_CPU1_SB_CA<4>       
                                  B42      GND                     
                                  B44      M_A_CPU1_CLK_DN<0>      
                                  B49      GND                     
                                  B51      M_A_CPU1_SA_CA<2>       
                                  B53      M_A_CPU1_SA_CS_N<1>     
                                  B55      GND                     
                                  B57      M_A_CPU1_SA_CB<4>       
                                  B59      M_A_CPU1_SA_CB<1>       
                                  B61      GND                     
                                  B63      M_A_CPU1_SA_DQ<28>      
                                  B65      M_A_CPU1_SA_DQ<25>      
                                  B67      GND                     
                                  B69      M_A_CPU1_SA_DQ<20>      
                                  B71      M_A_CPU1_SA_DQS_DN<2>   
                                  B73      M_A_CPU1_SA_DQ<16>      
                                  B75      GND                     
                                  B77      M_A_CPU1_SA_DQS_DN<0>   
                                  B79      M_A_CPU1_SA_DQ<1>       
                                  B81      M_A_CPU1_SA_DQ<0>       
                                  B83      GND                     
                                  B85      UPI_CPU1_CPU0_P2P2_DN<0>
                                  B87      GND                     
                                  BA1      UPI_CPU1_CPU0_P0P1_DP<16>
                                  BA3      PVCCD_HV_CPU1           
                                  BA5      UPI_CPU0_CPU1_P1P0_DN<15>
                                  BA7      PVCCD_HV_CPU1           
                                  BA9      P5E_CPU1_PE0_RX_DN<0>   
                                  BA11     VSENSE_PVCCFA_EHV_CPU1_DN
                                  BA13     P5E_CPU1_PE0_TX_DN<1>   
                                  BA15     PVCCINFAON_CPU1         
                                  BA17     GND                     
                                  BA19     PVNN_MAIN_CPU1          
                                  BA21     P3V3_AUX                
                                  BA23     PU_CPU1_UPI0_AC_COUPLING
                                  BA60     GND                     
                                  BA64     GND                     
                                  BA70     FM_S3M_CPU1_LVC1_GPIO_0 
                                  BA72     UPI_CPU0_CPU1_P2P2_DN<12>
                                  BA74     GND                     
                                  BA76     UPI_CPU0_CPU1_P2P2_DP<14>
                                  BA78     UPI_CPU1_CPU0_P2P2_DP<10>
                                  BA80     UPI_CPU1_CPU0_P2P2_DN<17>
                                  BA82     UPI_CPU1_CPU0_P2P2_DP<18>
                                  BA84     GND                     
                                  BA86     P5E_CPU1_PE4_TX_DN<0>   
                                  BA88     GND                     
                                  BA90     P5E_CPU1_PE4_RX_DP<0>   
                                  BB2      UPI_CPU1_CPU0_P0P1_DN<16>
                                  BB4      GND                     
                                  BB6      UPI_CPU0_CPU1_P1P0_DN<16>
                                  BB8      GND                     
                                  BB10     GND                     
                                  BB12     GND                     
                                  BB14     P5E_CPU1_PE0_TX_DN<0>   
                                  BB16     GND                     
                                  BB20     GND                     
                                  BB22     GND                     
                                  BB24     GND                     
                                  BB26     GND                     
                                  BB63     GND                     
                                  BB65     PU_CPU1_UPI2_AC_COUPLING
                                  BB69     GND                     
                                  BB71     GND                     
                                  BB73     UPI_CPU0_CPU1_P2P2_DP<12>
                                  BB75     UPI_CPU0_CPU1_P2P2_DN<15>
                                  BB77     GND                     
                                  BB79     GND                     
                                  BB81     UPI_CPU1_CPU0_P2P2_DP<17>
                                  BB83     GND                     
                                  BB85     P5E_CPU1_PE4_TX_DP<0>   
                                  BB87     GND                     
                                  BB89     P5E_CPU1_PE4_RX_DN<0>   
                                  BB91     GND                     
                                  BC1      GND                     
                                  BC3      UPI_CPU1_CPU0_P0P1_DP<17>
                                  BC5      GND                     
                                  BC7      UPI_CPU0_CPU1_P1P0_DP<16>
                                  BC9      GND                     
                                  BC11     P5E_CPU1_PE1_RX_DN<0>   
                                  BC13     GND                     
                                  BC15     P5E_CPU1_PE0_TX_DP<0>   
                                  BC17     GND                     
                                  BC21     P3V3_AUX                
                                  BC60     PVCCINFAON_CPU1         
                                  BC62     GND                     
                                  BC66     GND                     
                                  BC72     GND                     
                                  BC74     UPI_CPU0_CPU1_P2P2_DP<23>
                                  BC76     GND                     
                                  BC78     GND                     
                                  BC80     UPI_CPU1_CPU0_P2P2_DP<20>
                                  BC82     UPI_CPU1_CPU0_P2P2_DN<18>
                                  BC84     GND                     
                                  BC86     GND                     
                                  BC88     GND                     
                                  BC90     VSENSE_PVCCIN_CPU1_DN   
                                  BD2      UPI_CPU1_CPU0_P0P1_DN<17>
                                  BD4      GND                     
                                  BD6      UPI_CPU0_CPU1_P1P0_DP<17>
                                  BD8      GND                     
                                  BD10     P5E_CPU1_PE1_RX_DP<0>   
                                  BD12     GND                     
                                  BD14     P5E_CPU1_PE1_TX_DP<0>   
                                  BD16     GND                     
                                  BD20     GND                     
                                  BD22     H_CPU1_ERR2_LVC1_R_N    
                                  BD24     H_PMAX_TRIGGER_IO_CPU1  
                                  BD26     SVID_DIO0_CPU1          
                                  BD73     UPI_CPU0_CPU1_P2P2_DN<23>
                                  BD75     UPI_CPU0_CPU1_P2P2_DP<15>
                                  BD79     UPI_CPU1_CPU0_P2P2_DN<20>
                                  BD81     GND                     
                                  BD83     UPI_CPU1_CPU0_P2P2_DP<19>
                                  BD85     GND                     
                                  BD87     VSENSE_PVCCIN_CPU1_DP   
                                  BD89     GND                     
                                  BD91     PVCCIN_CPU1             
                                  BE1      UPI_CPU1_CPU0_P0P1_DP<18>
                                  BE3      PVCCD_HV_CPU1           
                                  BE5      UPI_CPU0_CPU1_P1P0_DN<17>
                                  BE7      PVCCD_HV_CPU1           
                                  BE9      P5E_CPU1_PE1_RX_DP<1>   
                                  BE11     PVCCD_HV_CPU1           
                                  BE13     P5E_CPU1_PE1_TX_DN<0>   
                                  BE15     PVCCINFAON_CPU1         
                                  BE19     PVNN_MAIN_CPU1          
                                  BE60     PVCCINFAON_CPU1         
                                  BE64     GND                     
                                  BE66     GND                     
                                  BE68     GND                     
                                  BE72     PVCCFA_EHV_FIVRA_CPU1   
                                  BE74     GND                     
                                  BE76     GND                     
                                  BE78     GND                     
                                  BE80     UPI_CPU1_CPU0_P2P2_DP<22>
                                  BE82     UPI_CPU1_CPU0_P2P2_DN<19>
                                  BE84     GND                     
                                  BE86     PVCCIN_CPU1             
                                  BE88     PVCCIN_CPU1             
                                  BE90     PVCCIN_CPU1             
                                  BF2      UPI_CPU1_CPU0_P0P1_DN<18>
                                  BF4      GND                     
                                  BF6      UPI_CPU0_CPU1_P1P0_DN<18>
                                  BF8      GND                     
                                  BF10     P5E_CPU1_PE1_RX_DN<1>   
                                  BF12     GND                     
                                  BF14     P5E_CPU1_PE1_TX_DN<1>   
                                  BF16     GND                     
                                  BF20     GND                     
                                  BF22     H_CPU1_ERR0_LVC1_R_N    
                                  BF26     SVID_CLK1_CPU1          
                                  BF61     GND                     
                                  BF63     GND                     
                                  BF73     GND                     
                                  BF75     GND                     
                                  BF77     PVCCFA_EHV_FIVRA_CPU1   
                                  BF79     GND                     
                                  BF81     UPI_CPU1_CPU0_P2P2_DN<21>
                                  BF83     GND                     
                                  BF85     PVCCIN_CPU1             
                                  BF87     PVCCIN_CPU1             
                                  BF89     PVCCIN_CPU1             
                                  BF91     PVCCIN_CPU1             
                                  BG1      GND                     
                                  BG3      UPI_CPU1_CPU0_P0P1_DP<19>
                                  BG5      GND                     
                                  BG7      UPI_CPU0_CPU1_P1P0_DP<18>
                                  BG9      GND                     
                                  BG11     P5E_CPU1_PE1_RX_DN<2>   
                                  BG13     GND                     
                                  BG15     P5E_CPU1_PE1_TX_DP<1>   
                                  BG17     GND                     
                                  BG21     GND                     
                                  BG23     GND                     
                                  BG25     GND                     
                                  BG60     PVCCINFAON_CPU1         
                                  BG70     GND                     
                                  BG72     FM_CPU1_PROC_ID0        
                                  BG74     UPI_CPU0_CPU1_P2P2_DN<20>
                                  BG76     UPI_CPU0_CPU1_P2P2_DP<17>
                                  BG80     UPI_CPU1_CPU0_P2P2_DN<22>
                                  BG82     UPI_CPU1_CPU0_P2P2_DP<21>
                                  BG84     PVCCIN_CPU1             
                                  BG86     PVCCIN_CPU1             
                                  BG88     PVCCIN_CPU1             
                                  BG90     PVCCIN_CPU1             
                                  BH2      UPI_CPU1_CPU0_P0P1_DN<19>
                                  BH4      GND                     
                                  BH6      UPI_CPU0_CPU1_P1P0_DP<19>
                                  BH8      GND                     
                                  BH10     P5E_CPU1_PE1_RX_DP<2>   
                                  BH12     GND                     
                                  BH14     P5E_CPU1_PE1_TX_DP<2>   
                                  BH16     GND                     
                                  BH20     GND                     
                                  BH22     H_CPU1_RMCA_LVC1_R_N    
                                  BH24     PECI_CPU1_GTL_R         
                                  BH26     SVID_CLK0_CPU1          
                                  BH61     RST_CPU1_LVC1_N         
                                  BH67     GND                     
                                  BH71     FM_CPU1_PROC_ID1        
                                  BH73     GND                     
                                  BH75     UPI_CPU0_CPU1_P2P2_DN<17>
                                  BH77     GND                     
                                  BH79     PVCCFA_EHV_FIVRA_CPU1   
                                  BH81     GND                     
                                  BH83     GND                     
                                  BH85     PVCCIN_CPU1             
                                  BH87     PVCCIN_CPU1             
                                  BH89     PVCCIN_CPU1             
                                  BH91     PVCCIN_CPU1             
                                  BJ1      UPI_CPU1_CPU0_P0P1_DP<20>
                                  BJ3      PVCCD_HV_CPU1           
                                  BJ5      UPI_CPU0_CPU1_P1P0_DN<19>
                                  BJ7      PVCCD_HV_CPU1           
                                  BJ9      P5E_CPU1_PE1_RX_DP<3>   
                                  BJ11     PVCCD_HV_CPU1           
                                  BJ13     P5E_CPU1_PE1_TX_DN<2>   
                                  BJ15     PVCCINFAON_CPU1         
                                  BJ19     PVNN_MAIN_CPU1          
                                  BJ23     DBP_CPU1_HOOK8_MBP2_GTL_QS_R_N
                                  BJ25     SVID_ALERT1_CPU1_N      
                                  BJ60     PVCCINFAON_CPU1         
                                  BJ62     GND                     
                                  BJ68     GND                     
                                  BJ72     PVCCFA_EHV_FIVRA_CPU1   
                                  BJ74     UPI_CPU0_CPU1_P2P2_DP<20>
                                  BJ76     UPI_CPU0_CPU1_P2P2_DN<18>
                                  BJ78     PVCCFA_EHV_FIVRA_CPU1   
                                  BJ80     GND                     
                                  BJ82     GND                     
                                  BJ84     GND                     
                                  BJ86     GND                     
                                  BJ88     GND                     
                                  BJ90     GND                     
                                  BK2      UPI_CPU1_CPU0_P0P1_DN<20>
                                  BK4      GND                     
                                  BK6      UPI_CPU0_CPU1_P1P0_DN<20>
                                  BK8      GND                     
                                  BK10     P5E_CPU1_PE1_RX_DN<3>   
                                  BK12     GND                     
                                  BK14     P5E_CPU1_PE1_TX_DN<3>   
                                  BK16     GND                     
                                  BK20     GND                     
                                  BK24     DBP_CPU1_HOOK9_MBP3_GTL_QS_R_N
                                  BK26     SVID_ALERT0_CPU1_N      
                                  BK61     PVCCINFAON_CPU1         
                                  BK65     GND                     
                                  BK71     GND                     
                                  BK73     UPI_CPU0_CPU1_P2P2_DN<22>
                                  BK75     GND                     
                                  BK77     UPI_CPU0_CPU1_P2P2_DP<18>
                                  BK79     GND                     
                                  BK81     PVCCIN_CPU1             
                                  BK83     PVCCIN_CPU1             
                                  BK85     PVCCIN_CPU1             
                                  BK87     PVCCIN_CPU1             
                                  BK89     PVCCIN_CPU1             
                                  BK91     PVCCIN_CPU1             
                                  BL1      GND                     
                                  BL3      UPI_CPU1_CPU0_P0P1_DP<21>
                                  BL5      GND                     
                                  BL7      UPI_CPU0_CPU1_P1P0_DP<20>
                                  BL9      GND                     
                                  BL11     P5E_CPU1_PE1_RX_DN<4>   
                                  BL13     GND                     
                                  BL15     P5E_CPU1_PE1_TX_DP<3>   
                                  BL17     GND                     
                                  BL23     DBP_CPU1_MBP0_GTL_R_N   
                                  BL25     SVID_DIO1_CPU1          
                                  BL62     H_CPU1_THERMTRIP_LVC1_R_N
                                  BL64     FM_CPU1_PKGID0          
                                  BL68     GND                     
                                  BL70     GND                     
                                  BL72     GND                     
                                  BL74     UPI_CPU0_CPU1_P2P2_DP<22>
                                  BL76     UPI_CPU0_CPU1_P2P2_DN<19>
                                  BL78     GND                     
                                  BL80     PVCCIN_CPU1             
                                  BL82     PVCCIN_CPU1             
                                  BL84     PVCCIN_CPU1             
                                  BL86     PVCCIN_CPU1             
                                  BL88     PVCCIN_CPU1             
                                  BL90     PVCCIN_CPU1             
                                  BM2      UPI_CPU1_CPU0_P0P1_DN<21>
                                  BM4      GND                     
                                  BM6      UPI_CPU0_CPU1_P1P0_DP<21>
                                  BM8      GND                     
                                  BM10     P5E_CPU1_PE1_RX_DP<4>   
                                  BM12     GND                     
                                  BM14     P5E_CPU1_PE1_TX_DP<4>   
                                  BM16     GND                     
                                  BM20     GND                     
                                  BM22     GND                     
                                  BM24     GND                     
                                  BM26     GND                     
                                  BM61     GND                     
                                  BM71     UPI_CPU1_CPU0_P2P2_DN<23>
                                  BM73     GND                     
                                  BM75     UPI_CPU0_CPU1_P2P2_DP<21>
                                  BM77     GND                     
                                  BM79     PVCCIN_CPU1             
                                  BM81     PVCCIN_CPU1             
                                  BM83     PVCCIN_CPU1             
                                  BM85     PVCCIN_CPU1             
                                  BM87     PVCCIN_CPU1             
                                  BM89     PVCCIN_CPU1             
                                  BM91     PVCCIN_CPU1             
                                  BN3      UPI_CPU1_CPU0_P0P1_DP<22>
                                  BN5      UPI_CPU0_CPU1_P1P0_DN<21>
                                  BN7      PVCCD_HV_CPU1           
                                  BN9      P5E_CPU1_PE1_RX_DP<5>   
                                  BN11     VSENSE_PVCCD_HV_CPU1_DN 
                                  BN13     P5E_CPU1_PE1_TX_DN<4>   
                                  BN15     PVCCINFAON_CPU1         
                                  BN19     PVNN_MAIN_CPU1          
                                  BN23     H_CPU1_BMCINIT_LVC1     
                                  BN25     DBP_CPU1_MBP1_GTL_R_N   
                                  BN31     GND                     
                                  BN33     PVCCIN_CPU1             
                                  BN35     PVCCIN_CPU1             
                                  BN37     PVCCIN_CPU1             
                                  BN39     PVCCIN_CPU1             
                                  BN41     PVCCIN_CPU1             
                                  BN43     PVCCIN_CPU1             
                                  BN45     PVCCIN_CPU1             
                                  BN48     PVCCIN_CPU1             
                                  BN50     PVCCIN_CPU1             
                                  BN52     PVCCIN_CPU1             
                                  BN54     PVCCIN_CPU1             
                                  BN56     PVCCIN_CPU1             
                                  BN58     PVCCIN_CPU1             
                                  BN60     PVCCIN_CPU1             
                                  BN62     GND                     
                                  BN64     FM_CPU1_PKGID2          
                                  BN70     GND                     
                                  BN72     UPI_CPU1_CPU0_P2P2_DP<23>
                                  BN74     UPI_CPU0_CPU1_P2P2_DN<21>
                                  BN76     UPI_CPU0_CPU1_P2P2_DP<19>
                                  BN78     PVCCIN_CPU1             
                                  BN80     PVCCIN_CPU1             
                                  BN82     PVCCIN_CPU1             
                                  BN84     PVCCIN_CPU1             
                                  BN86     PVCCIN_CPU1             
                                  BN88     PVCCIN_CPU1             
                                  BN90     PVCCIN_CPU1             
                                  BP2      GND                     
                                  BP4      GND                     
                                  BP6      UPI_CPU0_CPU1_P1P0_DP<22>
                                  BP8      GND                     
                                  BP10     P5E_CPU1_PE1_RX_DN<5>   
                                  BP12     GND                     
                                  BP14     P5E_CPU1_PE1_TX_DN<5>   
                                  BP16     GND                     
                                  BP20     GND                     
                                  BP24     H_CPU1_CATERR_LVC1_R_N  
                                  BP26     H_CPU1_PRDY_QS_GTL_R_N  
                                  BP32     PVCCIN_CPU1             
                                  BP34     PVCCIN_CPU1             
                                  BP36     PVCCIN_CPU1             
                                  BP38     PVCCIN_CPU1             
                                  BP40     PVCCIN_CPU1             
                                  BP42     PVCCIN_CPU1             
                                  BP44     PVCCIN_CPU1             
                                  BP47     PVCCIN_CPU1             
                                  BP49     PVCCIN_CPU1             
                                  BP51     PVCCIN_CPU1             
                                  BP53     PVCCIN_CPU1             
                                  BP55     PVCCIN_CPU1             
                                  BP57     PVCCIN_CPU1             
                                  BP59     PVCCIN_CPU1             
                                  BP61     PVCCIN_CPU1             
                                  BP63     GND                     
                                  BP71     GND                     
                                  BP73     GND                     
                                  BP75     GND                     
                                  BP77     GND                     
                                  BP79     PVCCIN_CPU1             
                                  BP81     PVCCIN_CPU1             
                                  BP83     PVCCIN_CPU1             
                                  BP85     PVCCIN_CPU1             
                                  BP87     PVCCIN_CPU1             
                                  BP89     PVCCIN_CPU1             
                                  BR3      UPI_CPU1_CPU0_P0P1_DN<22>
                                  BR5      GND                     
                                  BR7      UPI_CPU0_CPU1_P1P0_DN<22>
                                  BR9      GND                     
                                  BR11     P5E_CPU1_PE1_RX_DN<6>   
                                  BR13     GND                     
                                  BR15     P5E_CPU1_PE1_TX_DP<5>   
                                  BR17     GND                     
                                  BR23     H_CPU1_MON_FAIL_LVC1_R_N
                                  BR25     JTAG_DBP_CPU1_QS_GTL_R_TMS
                                  BR27     GND                     
                                  BR29     GND                     
                                  BR31     GND                     
                                  BR33     GND                     
                                  BR35     GND                     
                                  BR37     GND                     
                                  BR39     GND                     
                                  BR41     GND                     
                                  BR43     GND                     
                                  BR45     GND                     
                                  BR48     GND                     
                                  BR50     GND                     
                                  BR52     GND                     
                                  BR54     GND                     
                                  BR56     GND                     
                                  BR58     GND                     
                                  BR60     PVCCIN_CPU1             
                                  BR62     PVCCIN_CPU1             
                                  BR64     GND                     
                                  BR66     GND                     
                                  BR68     GND                     
                                  BR70     GND                     
                                  BR72     GND                     
                                  BR74     GND                     
                                  BR76     GND                     
                                  BR78     PVCCIN_CPU1             
                                  BR80     GND                     
                                  BR82     GND                     
                                  BR84     GND                     
                                  BR86     GND                     
                                  BR88     GND                     
                                  BR90     GND                     
                                  BT2      UPI_CPU1_CPU0_P0P1_DN<23>
                                  BT4      GND                     
                                  BT6      UPI_CPU0_CPU1_P1P0_DP<23>
                                  BT8      GND                     
                                  BT10     P5E_CPU1_PE1_RX_DP<6>   
                                  BT12     GND                     
                                  BT14     P5E_CPU1_PE1_TX_DP<6>   
                                  BT16     GND                     
                                  BT20     GND                     
                                  BT22     I3C_SPD_DDRABCD_CPU1_SCL
                                  BT24     JTAG_DBP_CPU1_GTL_R_TCK 
                                  BT26     PU_CPU1_TXT_AGENT       
                                  BT32     PVCCIN_CPU1             
                                  BT34     PVCCIN_CPU1             
                                  BT36     PVCCIN_CPU1             
                                  BT38     PVCCIN_CPU1             
                                  BT40     PVCCIN_CPU1             
                                  BT42     PVCCIN_CPU1             
                                  BT44     PVCCIN_CPU1             
                                  BT47     PVCCIN_CPU1             
                                  BT49     PVCCIN_CPU1             
                                  BT51     PVCCIN_CPU1             
                                  BT53     PVCCIN_CPU1             
                                  BT55     PVCCIN_CPU1             
                                  BT57     PVCCIN_CPU1             
                                  BT59     PVCCIN_CPU1             
                                  BT61     PVCCIN_CPU1             
                                  BT63     PVCCIN_CPU1             
                                  BT65     PVCCIN_CPU1             
                                  BT67     PVCCIN_CPU1             
                                  BT69     PVCCIN_CPU1             
                                  BT71     PVCCIN_CPU1             
                                  BT73     PVCCIN_CPU1             
                                  BT75     PVCCIN_CPU1             
                                  BT77     PVCCIN_CPU1             
                                  BT79     PVCCIN_CPU1             
                                  BT81     PVCCIN_CPU1             
                                  BT83     PVCCIN_CPU1             
                                  BT85     PVCCIN_CPU1             
                                  BT87     PVCCIN_CPU1             
                                  BT89     PVCCIN_CPU1             
                                  BU3      UPI_CPU1_CPU0_P0P1_DP<23>
                                  BU5      UPI_CPU0_CPU1_P1P0_DN<23>
                                  BU7      GND                     
                                  BU9      P5E_CPU1_PE1_RX_DP<7>   
                                  BU11     VSENSE_PVCCD_HV_CPU1_DP 
                                  BU13     P5E_CPU1_PE1_TX_DN<6>   
                                  BU15     GND                     
                                  BU19     GND                     
                                  BU21     GND                     
                                  BU23     GND                     
                                  BU25     GND                     
                                  BU31     GND                     
                                  BU33     PVCCIN_CPU1             
                                  BU35     PVCCIN_CPU1             
                                  BU37     PVCCIN_CPU1             
                                  BU39     PVCCIN_CPU1             
                                  BU41     PVCCIN_CPU1             
                                  BU43     PVCCIN_CPU1             
                                  BU45     PVCCIN_CPU1             
                                  BU48     PVCCIN_CPU1             
                                  BU50     PVCCIN_CPU1             
                                  BU52     PVCCIN_CPU1             
                                  BU54     PVCCIN_CPU1             
                                  BU56     PVCCIN_CPU1             
                                  BU58     PVCCIN_CPU1             
                                  BU60     PVCCIN_CPU1             
                                  BU62     PVCCIN_CPU1             
                                  BU64     PVCCIN_CPU1             
                                  BU66     PVCCIN_CPU1             
                                  BU68     PVCCIN_CPU1             
                                  BU70     PVCCIN_CPU1             
                                  BU72     PVCCIN_CPU1             
                                  BU74     PVCCIN_CPU1             
                                  BU76     PVCCIN_CPU1             
                                  BU78     PVCCIN_CPU1             
                                  BU80     PVCCIN_CPU1             
                                  BU82     PVCCIN_CPU1             
                                  BU84     PVCCIN_CPU1             
                                  BU86     PVCCIN_CPU1             
                                  BU88     PVCCIN_CPU1             
                                  BU90     PVCCIN_CPU1             
                                  BV2      GND                     
                                  BV4      GND                     
                                  BV6      GND                     
                                  BV8      GND                     
                                  BV10     P5E_CPU1_PE1_RX_DN<7>   
                                  BV12     GND                     
                                  BV14     P5E_CPU1_PE1_TX_DN<7>   
                                  BV16     GND                     
                                  BV18     GND                     
                                  BV20     GND                     
                                  BV24     JTAG_DBP_CPU1_GTL_R_TDI 
                                  BV26     FM_PEHPCPU1_ALERT_N     
                                  BV32     PVCCIN_CPU1             
                                  BV34     PVCCIN_CPU1             
                                  BV36     PVCCIN_CPU1             
                                  BV38     PVCCIN_CPU1             
                                  BV40     PVCCIN_CPU1             
                                  BV42     PVCCIN_CPU1             
                                  BV44     PVCCIN_CPU1             
                                  BV47     PVCCIN_CPU1             
                                  BV49     PVCCIN_CPU1             
                                  BV51     PVCCIN_CPU1             
                                  BV53     PVCCIN_CPU1             
                                  BV55     PVCCIN_CPU1             
                                  BV57     PVCCIN_CPU1             
                                  BV59     PVCCIN_CPU1             
                                  BV61     PVCCIN_CPU1             
                                  BV63     PVCCIN_CPU1             
                                  BV65     PVCCIN_CPU1             
                                  BV67     PVCCIN_CPU1             
                                  BV69     PVCCIN_CPU1             
                                  BV71     PVCCIN_CPU1             
                                  BV73     PVCCIN_CPU1             
                                  BV75     PVCCIN_CPU1             
                                  BV77     PVCCIN_CPU1             
                                  BV79     PVCCIN_CPU1             
                                  BV81     PVCCIN_CPU1             
                                  BV83     PVCCIN_CPU1             
                                  BV85     PVCCIN_CPU1             
                                  BV87     PVCCIN_CPU1             
                                  BV89     PVCCIN_CPU1             
                                  BW3      GND                     
                                  BW5      GND                     
                                  BW7      UPI_CPU1_CPU0_P1P0_DP<23>
                                  BW9      GND                     
                                  BW11     P5E_CPU1_PE1_RX_DN<8>   
                                  BW13     GND                     
                                  BW15     P5E_CPU1_PE1_TX_DP<7>   
                                  BW17     GND                     
                                  BW25     JTAG_CPU1_MUX_GTL_TDO   
                                  BW27     GND                     
                                  BW29     GND                     
                                  BW31     GND                     
                                  BW33     PVCCIN_CPU1             
                                  BW35     PVCCIN_CPU1             
                                  BW37     PVCCIN_CPU1             
                                  BW39     PVCCIN_CPU1             
                                  BW41     PVCCIN_CPU1             
                                  BW43     PVCCIN_CPU1             
                                  BW45     PVCCIN_CPU1             
                                  BW48     PVCCIN_CPU1             
                                  BW50     PVCCIN_CPU1             
                                  BW52     PVCCIN_CPU1             
                                  BW54     PVCCIN_CPU1             
                                  BW56     PVCCIN_CPU1             
                                  BW58     PVCCIN_CPU1             
                                  BW60     PVCCIN_CPU1             
                                  BW62     PVCCIN_CPU1             
                                  BW64     PVCCIN_CPU1             
                                  BW66     PVCCIN_CPU1             
                                  BW68     PVCCIN_CPU1             
                                  BW70     PVCCIN_CPU1             
                                  BW72     PVCCIN_CPU1             
                                  BW74     PVCCIN_CPU1             
                                  BW76     PVCCIN_CPU1             
                                  BW78     PVCCIN_CPU1             
                                  BW80     PVCCIN_CPU1             
                                  BW82     PVCCIN_CPU1             
                                  BW84     PVCCIN_CPU1             
                                  BW86     PVCCIN_CPU1             
                                  BW88     PVCCIN_CPU1             
                                  BW90     PVCCIN_CPU1             
                                  BY2      UPI_CPU0_CPU1_P0P1_DP<23>
                                  BY4      GND                     
                                  BY6      UPI_CPU1_CPU0_P1P0_DN<23>
                                  BY8      GND                     
                                  BY10     P5E_CPU1_PE1_RX_DP<8>   
                                  BY12     GND                     
                                  BY14     P5E_CPU1_PE1_TX_DP<8>   
                                  BY16     GND                     
                                  BY20     GND                     
                                  BY22     I3C_SPD_DDRABCD_CPU1_SDA
                                  BY24     PD_EXT_CLK_SEL_CPU1     
                                  BY26     SMB_PEHPCPU1_GTL_SDA    
                                  BY32     PVCCIN_CPU1             
                                  BY34     PVCCIN_CPU1             
                                  BY36     PVCCIN_CPU1             
                                  BY38     PVCCIN_CPU1             
                                  BY40     PVCCIN_CPU1             
                                  BY42     PVCCIN_CPU1             
                                  BY44     PVCCIN_CPU1             
                                  BY47     PVCCIN_CPU1             
                                  BY49     PVCCIN_CPU1             
                                  BY51     PVCCIN_CPU1             
                                  BY53     PVCCIN_CPU1             
                                  BY55     PVCCIN_CPU1             
                                  BY57     PVCCIN_CPU1             
                                  BY59     PVCCIN_CPU1             
                                  BY61     PVCCIN_CPU1             
                                  BY63     PVCCIN_CPU1             
                                  BY65     PVCCIN_CPU1             
                                  BY67     PVCCIN_CPU1             
                                  BY69     PVCCIN_CPU1             
                                  BY71     PVCCIN_CPU1             
                                  BY73     PVCCIN_CPU1             
                                  BY75     PVCCIN_CPU1             
                                  BY77     PVCCIN_CPU1             
                                  BY79     PVCCIN_CPU1             
                                  BY81     PVCCIN_CPU1             
                                  BY83     PVCCIN_CPU1             
                                  BY85     PVCCIN_CPU1             
                                  BY87     PVCCIN_CPU1             
                                  BY89     PVCCIN_CPU1             
                                  C5       GND                     
                                  C7       M_A_CPU1_SB_DQ<29>      
                                  C9       M_A_CPU1_SB_DQS_DP<3>   
                                  C11      M_A_CPU1_SB_DQ<24>      
                                  C13      M_B_CPU1_SB_DQ<28>      
                                  C15      M_B_CPU1_SB_DQS_DP<3>   
                                  C17      M_B_CPU1_SB_DQ<24>      
                                  C19      M_A_CPU1_SB_DQ<21>      
                                  C21      M_A_CPU1_SB_DQS_DP<2>   
                                  C23      M_A_CPU1_SB_DQ<16>      
                                  C25      M_A_CPU1_SB_DQ<13>      
                                  C27      M_A_CPU1_SB_DQS_DP<1>   
                                  C29      M_A_CPU1_SB_DQ<8>       
                                  C31      M_A_CPU1_SB_CB<1>       
                                  C33      M_A_CPU1_SB_DQS_DP<9>   
                                  C35      M_A_CPU1_SB_CB<4>       
                                  C37      M_A_CPU1_SB_CS_N<1>     
                                  C39      GND                     
                                  C41      M_A_CPU1_SB_CA<2>       
                                  C43      M_A_CPU1_CLK_DP<0>      
                                  C45      GND                     
                                  C48      M_A_CPU1_SA_CA<6>       
                                  C50      M_A_CPU1_SA_CA<4>       
                                  C52      GND                     
                                  C54      M_A_CPU1_SA_CS_N<0>     
                                  C56      M_A_CPU1_SA_CB<5>       
                                  C58      M_A_CPU1_SA_DQS_DP<4>   
                                  C60      M_A_CPU1_SA_CB<0>       
                                  C62      M_A_CPU1_SA_DQ<29>      
                                  C64      M_A_CPU1_SA_DQS_DP<3>   
                                  C66      M_A_CPU1_SA_DQ<24>      
                                  C68      M_A_CPU1_SA_DQ<21>      
                                  C70      M_A_CPU1_SA_DQS_DP<2>   
                                  C72      GND                     
                                  C74      GND                     
                                  C76      M_A_CPU1_SA_DQ<4>       
                                  C78      GND                     
                                  C80      GND                     
                                  C82      GND                     
                                  C84      PVCCFA_EHV_FIVRA_CPU1   
                                  C86      GND                     
                                  C88      PVCCFA_EHV_FIVRA_CPU1   
                                  CA3      GND                     
                                  CA5      UPI_CPU1_CPU0_P1P0_DN<22>
                                  CA7      PVCCD_HV_CPU1           
                                  CA9      P5E_CPU1_PE1_RX_DP<9>   
                                  CA11     VSENSE_PVCCINFAON_CPU1_DP
                                  CA13     P5E_CPU1_PE1_TX_DN<8>   
                                  CA15     PVCCINFAON_CPU1         
                                  CA25     SMB_PEHPCPU1_GTL_SCL    
                                  CA31     GND                     
                                  CA33     PVCCIN_CPU1             
                                  CA35     PVCCIN_CPU1             
                                  CA37     PVCCIN_CPU1             
                                  CA39     PVCCIN_CPU1             
                                  CA41     PVCCIN_CPU1             
                                  CA43     PVCCIN_CPU1             
                                  CA45     PVCCIN_CPU1             
                                  CA48     PVCCIN_CPU1             
                                  CA50     PVCCIN_CPU1             
                                  CA52     PVCCIN_CPU1             
                                  CA54     PVCCIN_CPU1             
                                  CA56     PVCCIN_CPU1             
                                  CA58     PVCCIN_CPU1             
                                  CA60     PVCCIN_CPU1             
                                  CA62     PVCCIN_CPU1             
                                  CA64     PVCCIN_CPU1             
                                  CA66     PVCCIN_CPU1             
                                  CA68     PVCCIN_CPU1             
                                  CA70     PVCCIN_CPU1             
                                  CA72     PVCCIN_CPU1             
                                  CA74     PVCCIN_CPU1             
                                  CA76     PVCCIN_CPU1             
                                  CA78     PVCCIN_CPU1             
                                  CA80     PVCCIN_CPU1             
                                  CA82     PVCCIN_CPU1             
                                  CA84     PVCCIN_CPU1             
                                  CA86     PVCCIN_CPU1             
                                  CA88     PVCCIN_CPU1             
                                  CA90     PVCCIN_CPU1             
                                  CB2      UPI_CPU0_CPU1_P0P1_DN<23>
                                  CB4      GND                     
                                  CB6      UPI_CPU1_CPU0_P1P0_DP<22>
                                  CB8      GND                     
                                  CB10     P5E_CPU1_PE1_RX_DN<9>   
                                  CB12     GND                     
                                  CB14     P5E_CPU1_PE1_TX_DN<9>   
                                  CB16     GND                     
                                  CB20     GND                     
                                  CB22     GND                     
                                  CB24     GND                     
                                  CB26     GND                     
                                  CB28     GND                     
                                  CB32     GND                     
                                  CB34     GND                     
                                  CB36     GND                     
                                  CB38     GND                     
                                  CB40     GND                     
                                  CB42     GND                     
                                  CB44     GND                     
                                  CB47     GND                     
                                  CB49     GND                     
                                  CB51     GND                     
                                  CB53     GND                     
                                  CB55     GND                     
                                  CB57     GND                     
                                  CB59     GND                     
                                  CB61     PVCCIN_CPU1             
                                  CB63     GND                     
                                  CB65     GND                     
                                  CB67     GND                     
                                  CB69     GND                     
                                  CB71     GND                     
                                  CB73     GND                     
                                  CB75     PVCCIN_CPU1             
                                  CB77     PVCCIN_CPU1             
                                  CB79     GND                     
                                  CB81     GND                     
                                  CB83     GND                     
                                  CB85     GND                     
                                  CB87     GND                     
                                  CB89     GND                     
                                  CC3      UPI_CPU0_CPU1_P0P1_DP<22>
                                  CC5      GND                     
                                  CC7      UPI_CPU1_CPU0_P1P0_DP<21>
                                  CC9      GND                     
                                  CC11     P5E_CPU1_PE1_RX_DN<10>  
                                  CC13     GND                     
                                  CC15     P5E_CPU1_PE1_TX_DP<9>   
                                  CC17     GND                     
                                  CC31     GND                     
                                  CC33     PVCCIN_CPU1             
                                  CC35     PVCCIN_CPU1             
                                  CC37     PVCCIN_CPU1             
                                  CC39     PVCCIN_CPU1             
                                  CC41     PVCCIN_CPU1             
                                  CC43     PVCCIN_CPU1             
                                  CC45     PVCCIN_CPU1             
                                  CC48     PVCCIN_CPU1             
                                  CC50     PVCCIN_CPU1             
                                  CC52     PVCCIN_CPU1             
                                  CC54     PVCCIN_CPU1             
                                  CC56     PVCCIN_CPU1             
                                  CC58     PVCCIN_CPU1             
                                  CC60     PVCCIN_CPU1             
                                  CC62     GND                     
                                  CC68     PVPP_HBM_CPU1           
                                  CC70     GND                     
                                  CC72     GND                     
                                  CC74     GND                     
                                  CC76     PVCCIN_CPU1             
                                  CC78     PVCCIN_CPU1             
                                  CC80     PVCCIN_CPU1             
                                  CC82     PVCCIN_CPU1             
                                  CC84     PVCCIN_CPU1             
                                  CC86     PVCCIN_CPU1             
                                  CC88     PVCCIN_CPU1             
                                  CC90     PVCCIN_CPU1             
                                  CD2      UPI_CPU0_CPU1_P0P1_DN<22>
                                  CD4      GND                     
                                  CD6      UPI_CPU1_CPU0_P1P0_DN<21>
                                  CD8      GND                     
                                  CD10     P5E_CPU1_PE1_RX_DP<10>  
                                  CD12     GND                     
                                  CD14     P5E_CPU1_PE1_TX_DP<10>  
                                  CD16     GND                     
                                  CD20     GND                     
                                  CD32     PVCCIN_CPU1             
                                  CD34     PVCCIN_CPU1             
                                  CD36     PVCCIN_CPU1             
                                  CD38     PVCCIN_CPU1             
                                  CD40     PVCCIN_CPU1             
                                  CD42     PVCCIN_CPU1             
                                  CD44     PVCCIN_CPU1             
                                  CD47     PVCCIN_CPU1             
                                  CD49     PVCCIN_CPU1             
                                  CD51     PVCCIN_CPU1             
                                  CD53     PVCCIN_CPU1             
                                  CD55     PVCCIN_CPU1             
                                  CD57     PVCCIN_CPU1             
                                  CD59     PVCCIN_CPU1             
                                  CD61     GND                     
                                  CD63     SMB_S3M_CPU1_SDA        
                                  CD67     PVPP_HBM_CPU1           
                                  CD73     UPI_CPU1_CPU0_P3P3_DN<23>
                                  CD75     GND                     
                                  CD77     GND                     
                                  CD79     PVCCIN_CPU1             
                                  CD81     PVCCIN_CPU1             
                                  CD83     PVCCIN_CPU1             
                                  CD85     PVCCIN_CPU1             
                                  CD87     PVCCIN_CPU1             
                                  CD89     PVCCIN_CPU1             
                                  CE1      UPI_CPU0_CPU1_P0P1_DP<21>
                                  CE3      GND                     
                                  CE5      UPI_CPU1_CPU0_P1P0_DN<20>
                                  CE7      PVCCD_HV_CPU1           
                                  CE9      P5E_CPU1_PE1_RX_DP<11>  
                                  CE11     VSENSE_PVCCINFAON_CPU1_DN
                                  CE13     P5E_CPU1_PE1_TX_DN<10>  
                                  CE15     PVCCINFAON_CPU1         
                                  CE19     PVCCINFAON_CPU1         
                                  CE60     GND                     
                                  CE64     SMB_S3M_CPU1_SCL        
                                  CE66     GND                     
                                  CE68     PVPP_HBM_CPU1           
                                  CE72     GND                     
                                  CE74     PVCCFA_EHV_FIVRA_CPU1   
                                  CE76     GND                     
                                  CE78     GND                     
                                  CE80     PVCCIN_CPU1             
                                  CE82     PVCCIN_CPU1             
                                  CE84     PVCCIN_CPU1             
                                  CE86     PVCCIN_CPU1             
                                  CE88     PVCCIN_CPU1             
                                  CE90     PVCCIN_CPU1             
                                  CF2      UPI_CPU0_CPU1_P0P1_DN<21>
                                  CF4      GND                     
                                  CF6      UPI_CPU1_CPU0_P1P0_DP<20>
                                  CF8      GND                     
                                  CF10     P5E_CPU1_PE1_RX_DN<11>  
                                  CF12     GND                     
                                  CF14     P5E_CPU1_PE1_TX_DN<11>  
                                  CF16     GND                     
                                  CF20     GND                     
                                  CF26     H_CPU1_MEMHOT_OUT_LVC1_R_N
                                  CF61     PUD_PCH_BOOT_MODE_CPU1  
                                  CF67     PVPP_HBM_CPU1           
                                  CF69     GND                     
                                  CF71     GND                     
                                  CF73     UPI_CPU1_CPU0_P3P3_DP<23>
                                  CF75     UPI_CPU1_CPU0_P3P3_DN<20>
                                  CF77     UPI_CPU1_CPU0_P3P3_DP<19>
                                  CF79     PVCCIN_CPU1             
                                  CF81     PVCCIN_CPU1             
                                  CF83     PVCCIN_CPU1             
                                  CF85     PVCCIN_CPU1             
                                  CF87     PVCCIN_CPU1             
                                  CF89     PVCCIN_CPU1             
                                  CF91     PVCCIN_CPU1             
                                  CG1      GND                     
                                  CG3      UPI_CPU0_CPU1_P0P1_DP<20>
                                  CG5      GND                     
                                  CG7      UPI_CPU1_CPU0_P1P0_DP<19>
                                  CG9      GND                     
                                  CG11     P5E_CPU1_PE1_RX_DN<12>  
                                  CG13     GND                     
                                  CG15     P5E_CPU1_PE1_TX_DP<11>  
                                  CG17     GND                     
                                  CG21     GND                     
                                  CG23     GND                     
                                  CG25     GND                     
                                  CG62     GND                     
                                  CG64     GND                     
                                  CG66     FM_CPU1_SKTOCC_LVT3_N   
                                  CG68     PVPP_HBM_CPU1           
                                  CG70     GND                     
                                  CG72     GND                     
                                  CG74     GND                     
                                  CG76     UPI_CPU1_CPU0_P3P3_DN<19>
                                  CG78     GND                     
                                  CG80     PVCCIN_CPU1             
                                  CG82     PVCCIN_CPU1             
                                  CG84     PVCCIN_CPU1             
                                  CG86     PVCCIN_CPU1             
                                  CG88     PVCCIN_CPU1             
                                  CG90     PVCCIN_CPU1             
                                  CH2      UPI_CPU0_CPU1_P0P1_DN<20>
                                  CH4      GND                     
                                  CH6      UPI_CPU1_CPU0_P1P0_DN<19>
                                  CH8      GND                     
                                  CH10     P5E_CPU1_PE1_RX_DP<12>  
                                  CH12     GND                     
                                  CH14     P5E_CPU1_PE1_TX_DP<12>  
                                  CH16     GND                     
                                  CH20     GND                     
                                  CH22     PD_CPU1_ENH_MCECC_DIS   
                                  CH65     PU_S3M_CPU1_CPLD_STATUS 
                                  CH67     GND                     
                                  CH71     PWRGD_S0_PWROK_CPU1_LVC1
                                  CH73     GND                     
                                  CH75     UPI_CPU1_CPU0_P3P3_DP<20>
                                  CH77     UPI_CPU1_CPU0_P3P3_DN<17>
                                  CH79     GND                     
                                  CH81     PVCCIN_CPU1             
                                  CH83     GND                     
                                  CH85     GND                     
                                  CH87     GND                     
                                  CH89     GND                     
                                  CH91     PVCCIN_CPU1             
                                  CJ1      UPI_CPU0_CPU1_P0P1_DN<19>
                                  CJ3      PVCCINFAON_CPU1         
                                  CJ5      UPI_CPU1_CPU0_P1P0_DN<18>
                                  CJ7      PVCCINFAON_CPU1         
                                  CJ9      P5E_CPU1_PE1_RX_DP<13>  
                                  CJ11     PVCCINFAON_CPU1         
                                  CJ13     P5E_CPU1_PE1_TX_DN<12>  
                                  CJ15     PVCCINFAON_CPU1         
                                  CJ19     PVCCINFAON_CPU1         
                                  CJ60     GND                     
                                  CJ64     PU_S3M_CPU1_CPLD_CONFD  
                                  CJ72     PUD_XTAL_CPU1_MODE1     
                                  CJ74     UPI_CPU1_CPU0_P3P3_DP<21>
                                  CJ76     GND                     
                                  CJ78     UPI_CPU1_CPU0_P3P3_DP<17>
                                  CJ80     GND                     
                                  CJ82     PVCCIN_CPU1             
                                  CJ84     PVCCIN_CPU1             
                                  CJ86     PVCCIN_CPU1             
                                  CJ88     PVCCIN_CPU1             
                                  CJ90     PVCCIN_CPU1             
                                  CK2      UPI_CPU0_CPU1_P0P1_DP<19>
                                  CK4      GND                     
                                  CK6      UPI_CPU1_CPU0_P1P0_DP<18>
                                  CK8      GND                     
                                  CK10     P5E_CPU1_PE1_RX_DN<13>  
                                  CK12     GND                     
                                  CK14     P5E_CPU1_PE1_TX_DN<13>  
                                  CK16     GND                     
                                  CK20     GND                     
                                  CK26     GND                     
                                  CK63     GND                     
                                  CK65     FM_S3M_CPU1_CPLD_CONFIG_N
                                  CK69     GND                     
                                  CK71     PU_CPU1_UPI3_AC_COUPLING
                                  CK73     PVCCFA_EHV_FIVRA_CPU1   
                                  CK75     UPI_CPU1_CPU0_P3P3_DN<21>
                                  CK77     UPI_CPU1_CPU0_P3P3_DP<16>
                                  CK79     PVCCFA_EHV_FIVRA_CPU1   
                                  CK81     GND                     
                                  CK83     PVCCIN_CPU1             
                                  CK85     PVCCIN_CPU1             
                                  CK87     PVCCIN_CPU1             
                                  CK89     PVCCIN_CPU1             
                                  CK91     PVCCIN_CPU1             
                                  CL1      GND                     
                                  CL3      UPI_CPU0_CPU1_P0P1_DN<18>
                                  CL5      GND                     
                                  CL7      UPI_CPU1_CPU0_P1P0_DP<17>
                                  CL9      GND                     
                                  CL11     P5E_CPU1_PE1_RX_DN<14>  
                                  CL13     GND                     
                                  CL15     P5E_CPU1_PE1_TX_DP<13>  
                                  CL17     GND                     
                                  CL62     GND                     
                                  CL72     PUD_XTAL_CPU1_MODE0     
                                  CL74     GND                     
                                  CL76     UPI_CPU1_CPU0_P3P3_DN<18>
                                  CL78     GND                     
                                  CL80     GND                     
                                  CL82     GND                     
                                  CL84     PVCCIN_CPU1             
                                  CL86     PVCCIN_CPU1             
                                  CL88     PVCCIN_CPU1             
                                  CL90     PVCCIN_CPU1             
                                  CM2      UPI_CPU0_CPU1_P0P1_DP<18>
                                  CM4      GND                     
                                  CM6      UPI_CPU1_CPU0_P1P0_DN<17>
                                  CM8      GND                     
                                  CM10     P5E_CPU1_PE1_RX_DP<14>  
                                  CM12     GND                     
                                  CM14     P5E_CPU1_PE1_TX_DP<14>  
                                  CM16     GND                     
                                  CM20     GND                     
                                  CM22     GND                     
                                  CM24     GND                     
                                  CM61     GND                     
                                  CM65     GND                     
                                  CM67     GND                     
                                  CM71     SMB_CPU1_PIROM_3V3AUX_SDA_R
                                  CM73     PVCCFA_EHV_FIVRA_CPU1   
                                  CM75     UPI_CPU1_CPU0_P3P3_DP<18>
                                  CM77     UPI_CPU1_CPU0_P3P3_DN<16>
                                  CM79     GND                     
                                  CM81     GND                     
                                  CM83     GND                     
                                  CM85     GND                     
                                  CM87     PVCCIN_CPU1             
                                  CM89     PVCCIN_CPU1             
                                  CM91     PVCCIN_CPU1             
                                  CN1      UPI_CPU0_CPU1_P0P1_DN<17>
                                  CN3      PVCCINFAON_CPU1         
                                  CN5      UPI_CPU1_CPU0_P1P0_DN<16>
                                  CN7      PVCCINFAON_CPU1         
                                  CN9      P5E_CPU1_PE1_RX_DP<15>  
                                  CN11     PVCCINFAON_CPU1         
                                  CN13     P5E_CPU1_PE1_TX_DN<14>  
                                  CN15     PVCCINFAON_CPU1         
                                  CN19     PVCCINFAON_CPU1         
                                  CN25     H_CPU0_PMDOWN_CPU1      
                                  CN64     PVCCINFAON_CPU1         
                                  CN66     PVCCINFAON_CPU1         
                                  CN68     GND                     
                                  CN70     GND                     
                                  CN72     GND                     
                                  CN74     GND                     
                                  CN76     GND                     
                                  CN78     PVCCFA_EHV_FIVRA_CPU1   
                                  CN80     UPI_CPU0_CPU1_P3P3_DN<21>
                                  CN82     UPI_CPU0_CPU1_P3P3_DP<20>
                                  CN84     GND                     
                                  CN86     GND                     
                                  CN88     PVCCIN_CPU1             
                                  CN90     PVCCIN_CPU1             
                                  CP2      UPI_CPU0_CPU1_P0P1_DP<17>
                                  CP4      GND                     
                                  CP6      UPI_CPU1_CPU0_P1P0_DP<16>
                                  CP8      GND                     
                                  CP10     P5E_CPU1_PE1_RX_DN<15>  
                                  CP12     GND                     
                                  CP14     P5E_CPU1_PE1_TX_DN<15>  
                                  CP16     GND                     
                                  CP18     GND                     
                                  CP20     H_CPU1_PM_FAST_WAKE_N   
                                  CP63     PVCCINFAON_CPU1         
                                  CP65     PVCCINFAON_CPU1         
                                  CP67     PVCCINFAON_CPU1         
                                  CP71     PD_PIROM_CPU1_ADDR2     
                                  CP73     PVCCFA_EHV_FIVRA_CPU1   
                                  CP75     GND                     
                                  CP77     GND                     
                                  CP79     GND                     
                                  CP81     UPI_CPU0_CPU1_P3P3_DN<20>
                                  CP83     GND                     
                                  CP85     P5E_CPU1_PE3_TX_DN<15>  
                                  CP87     GND                     
                                  CP89     PVCCIN_CPU1             
                                  CP91     GND                     
                                  CR1      GND                     
                                  CR3      UPI_CPU0_CPU1_P0P1_DN<16>
                                  CR5      GND                     
                                  CR7      UPI_CPU1_CPU0_P1P0_DP<15>
                                  CR9      GND                     
                                  CR11     GND                     
                                  CR13     GND                     
                                  CR15     P5E_CPU1_PE1_TX_DP<15>  
                                  CR17     GND                     
                                  CR62     GND                     
                                  CR64     GND                     
                                  CR66     PVCCINFAON_CPU1         
                                  CR70     PU_PIROM_CPU1_ADDR0     
                                  CR72     PU_PIROM_CPU1_SM_WP     
                                  CR74     UPI_CPU1_CPU0_P3P3_DP<15>
                                  CR76     UPI_CPU1_CPU0_P3P3_DP<14>
                                  CR78     GND                     
                                  CR80     UPI_CPU0_CPU1_P3P3_DP<21>
                                  CR82     UPI_CPU0_CPU1_P3P3_DN<18>
                                  CR84     GND                     
                                  CR86     P5E_CPU1_PE3_TX_DP<15>  
                                  CR88     GND                     
                                  CR90     GND                     
                                  CT2      UPI_CPU0_CPU1_P0P1_DP<16>
                                  CT4      GND                     
                                  CT6      UPI_CPU1_CPU0_P1P0_DN<15>
                                  CT8      GND                     
                                  CT10     GND                     
                                  CT12     GND                     
                                  CT14     P5E_CPU1_PE2_TX_DP<0>   
                                  CT16     GND                     
                                  CT18     I3C_SPD_DDREFGH_CPU1_SDA
                                  CT20     PD_CPU1_TXT_PLTEN       
                                  CT61     PU_CPU1_SOCKET_ID2      
                                  CT63     PVCCINFAON_CPU1         
                                  CT65     PVCCINFAON_CPU1         
                                  CT67     PVCCINFAON_CPU1         
                                  CT69     GND                     
                                  CT71     PD_PIROM_CPU1_ADDR1     
                                  CT73     GND                     
                                  CT75     UPI_CPU1_CPU0_P3P3_DN<14>
                                  CT77     PVCCFA_EHV_FIVRA_CPU1   
                                  CT79     UPI_CPU0_CPU1_P3P3_DN<22>
                                  CT81     GND                     
                                  CT83     UPI_CPU0_CPU1_P3P3_DP<18>
                                  CT85     PVCCFA_EHV_FIVRA_CPU1   
                                  CT87     P5E_CPU1_PE3_TX_DN<14>  
                                  CT89     GND                     
                                  CT91     P5E_CPU1_PE3_RX_DP<15>  
                                  CU1      UPI_CPU0_CPU1_P0P1_DP<15>
                                  CU3      PVCCINFAON_CPU1         
                                  CU5      UPI_CPU1_CPU0_P1P0_DN<14>
                                  CU7      PVCCINFAON_CPU1         
                                  CU9      P5E_CPU1_PE2_RX_DN<0>   
                                  CU11     PVCCINFAON_CPU1         
                                  CU13     P5E_CPU1_PE2_TX_DN<0>   
                                  CU15     PVCCINFAON_CPU1         
                                  CU17     I3C_SPD_DDREFGH_CPU1_SCL
                                  CU19     GND                     
                                  CU21     GND                     
                                  CU23     GND                     
                                  CU25     GND                     
                                  CU60     GND                     
                                  CU64     PVCCINFAON_CPU1         
                                  CU66     GND                     
                                  CU68     GND                     
                                  CU70     SMB_CPU1_PIROM_3V3AUX_SCL_R
                                  CU72     GND                     
                                  CU74     UPI_CPU1_CPU0_P3P3_DN<15>
                                  CU76     UPI_CPU1_CPU0_P3P3_DN<13>
                                  CU78     GND                     
                                  CU80     UPI_CPU0_CPU1_P3P3_DP<22>
                                  CU82     UPI_CPU0_CPU1_P3P3_DN<17>
                                  CU84     GND                     
                                  CU86     P5E_CPU1_PE3_TX_DP<14>  
                                  CU88     GND                     
                                  CU90     P5E_CPU1_PE3_RX_DN<15>  
                                  CV2      UPI_CPU0_CPU1_P0P1_DN<15>
                                  CV4      GND                     
                                  CV6      UPI_CPU1_CPU0_P1P0_DP<14>
                                  CV8      GND                     
                                  CV10     P5E_CPU1_PE2_RX_DP<0>   
                                  CV12     GND                     
                                  CV14     P5E_CPU1_PE2_TX_DN<1>   
                                  CV16     GND                     
                                  CV20     PWRGD_PLT_AUX_CPU1_LVT3 
                                  CV26     GND                     
                                  CV61     PVCCINFAON_CPU1         
                                  CV63     PVCCINFAON_CPU1         
                                  CV65     PVCCINFAON_CPU1         
                                  CV67     PVCCINFAON_CPU1         
                                  CV73     UPI_CPU1_CPU0_P3P3_DP<22>
                                  CV75     GND                     
                                  CV77     UPI_CPU1_CPU0_P3P3_DP<13>
                                  CV79     GND                     
                                  CV81     UPI_CPU0_CPU1_P3P3_DP<19>
                                  CV83     GND                     
                                  CV85     P5E_CPU1_PE3_TX_DN<13>  
                                  CV87     GND                     
                                  CV89     P5E_CPU1_PE3_RX_DN<14>  
                                  CV91     GND                     
                                  CW1      GND                     
                                  CW3      UPI_CPU0_CPU1_P0P1_DP<14>
                                  CW5      GND                     
                                  CW7      UPI_CPU1_CPU0_P1P0_DP<13>
                                  CW9      GND                     
                                  CW11     P5E_CPU1_PE2_RX_DP<1>   
                                  CW13     GND                     
                                  CW15     P5E_CPU1_PE2_TX_DP<1>   
                                  CW17     GND                     
                                  CW19     PU_CPU1_UPI1_AC_COUPLING
                                  CW27     CLK_100M_DB2000_CPU1_BCLK3_DN
                                  CW29     CLK_100M_DB2000_CPU1_BCLK1_DP
                                  CW31     CLK_25M_NSSC_CPU1_DN    
                                  CW33     GND                     
                                  CW35     PVCCD_HV_CPU1           
                                  CW37     PVCCD_HV_CPU1           
                                  CW39     H_CPU0_PMSYNC_CPU1      
                                  CW45     PWRGD_DRAMPWRGD_CPU1_GH_LVC1_R
                                  CW48     M_F_CPU1_ALERT_N        
                                  CW50     M_G_CPU1_ALERT_N        
                                  CW52     PVCCD_HV_CPU1           
                                  CW54     PVCCD_HV_CPU1           
                                  CW56     PVCCD_HV_CPU1           
                                  CW60     PU_CPU1_SOCKET_ID0      
                                  CW62     PVCCINFAON_CPU1         
                                  CW64     PVCCINFAON_CPU1         
                                  CW66     PVCCINFAON_CPU1         
                                  CW70     GND                     
                                  CW72     GND                     
                                  CW74     UPI_CPU1_CPU0_P3P3_DN<22>
                                  CW76     UPI_CPU1_CPU0_P3P3_DN<12>
                                  CW78     GND                     
                                  CW80     UPI_CPU0_CPU1_P3P3_DN<19>
                                  CW82     UPI_CPU0_CPU1_P3P3_DP<17>
                                  CW84     GND                     
                                  CW86     P5E_CPU1_PE3_TX_DP<13>  
                                  CW88     GND                     
                                  CW90     P5E_CPU1_PE3_RX_DP<14>  
                                  CY2      UPI_CPU0_CPU1_P0P1_DN<14>
                                  CY4      GND                     
                                  CY6      UPI_CPU1_CPU0_P1P0_DN<13>
                                  CY8      GND                     
                                  CY10     P5E_CPU1_PE2_RX_DN<1>   
                                  CY12     GND                     
                                  CY14     P5E_CPU1_PE2_TX_DP<2>   
                                  CY16     GND                     
                                  CY18     GND                     
                                  CY20     FM_S3M_CPU1_CPLD_CRC_ERROR
                                  CY22     PD_JTAG_CPU1_PLD_TCK    
                                  CY26     GND                     
                                  CY28     CLK_100M_DB2000_CPU1_BCLK1_DN
                                  CY30     GND                     
                                  CY32     CLK_25M_NSSC_CPU1_DP    
                                  CY34     PVCCD_HV_CPU1           
                                  CY36     PVCCD_HV_CPU1           
                                  CY42     RST_CPU1_DRAM_EF_N      
                                  CY44     PWRGD_DRAMPWRGD_CPU1_EF_LVC1_R
                                  CY47     M_E_CPU1_ALERT_N        
                                  CY51     M_H_CPU1_ALERT_N        
                                  CY53     PVCCD_HV_CPU1           
                                  CY55     RST_CPU1_DRAM_GH_N      
                                  CY59     PU_CPU1_LEGACY_SKT      
                                  CY61     PU_CPU1_SOCKET_ID1      
                                  CY63     GND                     
                                  CY65     PVCCINFAON_CPU1         
                                  CY67     PVCCINFAON_CPU1         
                                  CY73     GND                     
                                  CY75     PVCCFA_EHV_FIVRA_CPU1   
                                  CY77     GND                     
                                  CY79     PVCCFA_EHV_FIVRA_CPU1   
                                  CY81     GND                     
                                  CY83     GND                     
                                  CY85     PVCCFA_EHV_FIVRA_CPU1   
                                  CY87     P5E_CPU1_PE3_TX_DN<12>  
                                  CY89     PVCCFA_EHV_FIVRA_CPU1   
                                  CY91     P5E_CPU1_PE3_RX_DP<13>  
                                  D6       GND                     
                                  D8       GND                     
                                  D10      GND                     
                                  D12      GND                     
                                  D14      GND                     
                                  D16      GND                     
                                  D18      GND                     
                                  D20      GND                     
                                  D22      GND                     
                                  D24      GND                     
                                  D26      GND                     
                                  D28      GND                     
                                  D30      GND                     
                                  D32      GND                     
                                  D34      GND                     
                                  D36      GND                     
                                  D38      GND                     
                                  D40      GND                     
                                  D42      GND                     
                                  D44      GND                     
                                  D47      GND                     
                                  D49      GND                     
                                  D51      GND                     
                                  D53      GND                     
                                  D55      GND                     
                                  D57      GND                     
                                  D59      GND                     
                                  D61      GND                     
                                  D63      GND                     
                                  D65      GND                     
                                  D67      GND                     
                                  D69      GND                     
                                  D71      GND                     
                                  D73      M_A_CPU1_SA_DQ<18>      
                                  D75      M_A_CPU1_SA_DQ<5>       
                                  D77      M_A_CPU1_SA_DQS_DP<0>   
                                  D79      GND                     
                                  D81      GND                     
                                  D83      GND                     
                                  D85      UPI_CPU1_CPU0_P2P2_DP<0>
                                  D87      UPI_CPU1_CPU0_P2P2_DN<2>
                                  DA1      UPI_CPU0_CPU1_P0P1_DP<13>
                                  DA3      PVCCINFAON_CPU1         
                                  DA5      UPI_CPU1_CPU0_P1P0_DN<12>
                                  DA7      PVCCINFAON_CPU1         
                                  DA9      P5E_CPU1_PE2_RX_DN<2>   
                                  DA11     PVCCINFAON_CPU1         
                                  DA13     P5E_CPU1_PE2_TX_DN<2>   
                                  DA15     PVCCINFAON_CPU1         
                                  DA17     M_H_CPU1_SB_DQ<29>      
                                  DA19     GND                     
                                  DA21     PVCCINFAON_CPU1         
                                  DA23     GND                     
                                  DA25     GND                     
                                  DA27     CLK_100M_DB2000_CPU1_BCLK3_DP
                                  DA29     GND                     
                                  DA31     GND                     
                                  DA33     GND                     
                                  DA35     GND                     
                                  DA37     GND                     
                                  DA41     GND                     
                                  DA43     GND                     
                                  DA48     GND                     
                                  DA50     GND                     
                                  DA52     PD_CPU1_PROCDIS_COD_GTL_N
                                  DA54     GND                     
                                  DA56     GND                     
                                  DA58     GND                     
                                  DA60     GND                     
                                  DA62     GND                     
                                  DA64     PVCCINFAON_CPU1         
                                  DA66     GND                     
                                  DA68     GND                     
                                  DA72     GND                     
                                  DA74     GND                     
                                  DA76     UPI_CPU1_CPU0_P3P3_DP<12>
                                  DA78     UPI_CPU0_CPU1_P3P3_DN<23>
                                  DA80     GND                     
                                  DA82     GND                     
                                  DA84     GND                     
                                  DA86     P5E_CPU1_PE3_TX_DP<12>  
                                  DA88     GND                     
                                  DA90     P5E_CPU1_PE3_RX_DN<13>  
                                  DB2      UPI_CPU0_CPU1_P0P1_DN<13>
                                  DB4      GND                     
                                  DB6      UPI_CPU1_CPU0_P1P0_DP<12>
                                  DB8      GND                     
                                  DB10     P5E_CPU1_PE2_RX_DP<2>   
                                  DB12     GND                     
                                  DB14     P5E_CPU1_PE2_TX_DN<3>   
                                  DB16     GND                     
                                  DB18     M_H_CPU1_SB_DQS_DN<3>   
                                  DB20     GND                     
                                  DB22     GND                     
                                  DB24     M_H_CPU1_SB_DQS_DP<1>   
                                  DB26     GND                     
                                  DB28     GND                     
                                  DB30     M_H_CPU1_SB_DQS_DP<0>   
                                  DB32     GND                     
                                  DB34     GND                     
                                  DB36     M_H_CPU1_SB_DQS_DP<9>   
                                  DB38     GND                     
                                  DB40     GND                     
                                  DB42     M_H_CPU1_CLK_DP<1>      
                                  DB44     GND                     
                                  DB47     GND                     
                                  DB49     M_H_CPU1_SA_CA<0>       
                                  DB51     GND                     
                                  DB53     GND                     
                                  DB55     M_H_CPU1_SA_DQS_DP<4>   
                                  DB57     GND                     
                                  DB59     GND                     
                                  DB61     M_H_CPU1_SA_DQS_DP<3>   
                                  DB63     GND                     
                                  DB65     GND                     
                                  DB67     M_H_CPU1_SA_DQS_DP<2>   
                                  DB69     GND                     
                                  DB71     GND                     
                                  DB73     M_H_CPU1_SA_DQS_DN<1>   
                                  DB75     GND                     
                                  DB77     GND                     
                                  DB79     UPI_CPU0_CPU1_P3P3_DP<23>
                                  DB81     UPI_CPU0_CPU1_P3P3_DN<15>
                                  DB83     UPI_CPU0_CPU1_P3P3_DP<14>
                                  DB85     P5E_CPU1_PE3_TX_DN<11>  
                                  DB87     GND                     
                                  DB89     P5E_CPU1_PE3_RX_DN<12>  
                                  DB91     GND                     
                                  DC1      GND                     
                                  DC3      UPI_CPU0_CPU1_P0P1_DP<12>
                                  DC5      GND                     
                                  DC7      UPI_CPU1_CPU0_P1P0_DP<11>
                                  DC9      GND                     
                                  DC11     P5E_CPU1_PE2_RX_DP<3>   
                                  DC13     GND                     
                                  DC15     P5E_CPU1_PE2_TX_DP<3>   
                                  DC17     M_H_CPU1_SB_DQ<31>      
                                  DC19     M_H_CPU1_SB_DQ<25>      
                                  DC21     GND                     
                                  DC23     M_H_CPU1_SB_DQ<12>      
                                  DC25     M_H_CPU1_SB_DQ<9>       
                                  DC27     GND                     
                                  DC29     M_H_CPU1_SB_DQ<4>       
                                  DC31     M_H_CPU1_SB_DQ<1>       
                                  DC33     GND                     
                                  DC35     M_H_CPU1_SB_CB<0>       
                                  DC37     M_H_CPU1_SB_CB<7>       
                                  DC39     GND                     
                                  DC41     M_H_CPU1_SA_CA<6>       
                                  DC43     M_E_CPU1_SA_RSP<1>      
                                  DC45     GND                     
                                  DC48     M_H_CPU1_SA_CA<2>       
                                  DC50     M_H_CPU1_SA_CS_N<3>     
                                  DC52     GND                     
                                  DC54     M_H_CPU1_SA_CB<4>       
                                  DC56     M_H_CPU1_SA_CB<1>       
                                  DC58     GND                     
                                  DC60     M_H_CPU1_SA_DQ<28>      
                                  DC62     M_H_CPU1_SA_DQ<25>      
                                  DC64     GND                     
                                  DC66     M_H_CPU1_SA_DQ<20>      
                                  DC68     M_H_CPU1_SA_DQ<17>      
                                  DC70     GND                     
                                  DC72     M_H_CPU1_SA_DQ<12>      
                                  DC74     M_H_CPU1_SA_DQ<9>       
                                  DC76     GND                     
                                  DC78     GND                     
                                  DC80     GND                     
                                  DC82     UPI_CPU0_CPU1_P3P3_DN<14>
                                  DC84     GND                     
                                  DC86     P5E_CPU1_PE3_TX_DP<11>  
                                  DC88     GND                     
                                  DC90     P5E_CPU1_PE3_RX_DP<12>  
                                  DD2      UPI_CPU0_CPU1_P0P1_DN<12>
                                  DD4      GND                     
                                  DD6      UPI_CPU1_CPU0_P1P0_DN<11>
                                  DD8      GND                     
                                  DD10     P5E_CPU1_PE2_RX_DN<3>   
                                  DD12     GND                     
                                  DD14     P5E_CPU1_PE2_TX_DP<4>   
                                  DD16     GND                     
                                  DD18     M_H_CPU1_SB_DQS_DP<3>   
                                  DD20     M_H_CPU1_SB_DQ<24>      
                                  DD22     M_H_CPU1_SB_DQ<13>      
                                  DD24     M_H_CPU1_SB_DQS_DN<1>   
                                  DD26     M_H_CPU1_SB_DQ<8>       
                                  DD28     M_H_CPU1_SB_DQ<7>       
                                  DD30     M_H_CPU1_SB_DQS_DN<0>   
                                  DD32     M_H_CPU1_SB_DQ<0>       
                                  DD34     M_H_CPU1_SB_CB<1>       
                                  DD36     M_H_CPU1_SB_DQS_DN<9>   
                                  DD38     M_H_CPU1_SB_CB<6>       
                                  DD40     M_H_CPU1_SA_PAR         
                                  DD42     M_H_CPU1_CLK_DN<1>      
                                  DD44     M_E_CPU1_SA_RSP<0>      
                                  DD47     M_H_CPU1_SA_CA<4>       
                                  DD49     GND                     
                                  DD51     M_H_CPU1_SA_CS_N<2>     
                                  DD53     M_H_CPU1_SA_CB<5>       
                                  DD55     M_H_CPU1_SA_DQS_DN<4>   
                                  DD57     M_H_CPU1_SA_CB<0>       
                                  DD59     M_H_CPU1_SA_DQ<29>      
                                  DD61     M_H_CPU1_SA_DQS_DN<3>   
                                  DD63     M_H_CPU1_SA_DQ<24>      
                                  DD65     M_H_CPU1_SA_DQ<21>      
                                  DD67     M_H_CPU1_SA_DQS_DN<2>   
                                  DD69     M_H_CPU1_SA_DQ<16>      
                                  DD71     M_H_CPU1_SA_DQ<13>      
                                  DD73     M_H_CPU1_SA_DQS_DP<1>   
                                  DD75     M_H_CPU1_SA_DQ<8>       
                                  DD77     PVCCFA_EHV_FIVRA_CPU1   
                                  DD79     GND                     
                                  DD81     UPI_CPU0_CPU1_P3P3_DP<15>
                                  DD83     PVCCFA_EHV_FIVRA_CPU1   
                                  DD85     PVCCFA_EHV_FIVRA_CPU1   
                                  DD87     P5E_CPU1_PE3_TX_DN<10>  
                                  DD89     PVCCFA_EHV_FIVRA_CPU1   
                                  DD91     P5E_CPU1_PE3_RX_DN<11>  
                                  DE1      UPI_CPU0_CPU1_P0P1_DN<11>
                                  DE3      PVCCINFAON_CPU1         
                                  DE5      UPI_CPU1_CPU0_P1P0_DN<10>
                                  DE7      PVCCINFAON_CPU1         
                                  DE9      P5E_CPU1_PE2_RX_DN<4>   
                                  DE11     PVCCINFAON_CPU1         
                                  DE13     P5E_CPU1_PE2_TX_DN<4>   
                                  DE15     PVCCINFAON_CPU1         
                                  DE17     GND                     
                                  DE19     GND                     
                                  DE21     GND                     
                                  DE23     GND                     
                                  DE25     GND                     
                                  DE27     GND                     
                                  DE29     GND                     
                                  DE31     GND                     
                                  DE33     GND                     
                                  DE35     GND                     
                                  DE37     GND                     
                                  DE39     GND                     
                                  DE41     GND                     
                                  DE43     GND                     
                                  DE45     GND                     
                                  DE48     GND                     
                                  DE50     GND                     
                                  DE52     GND                     
                                  DE54     GND                     
                                  DE56     GND                     
                                  DE58     GND                     
                                  DE60     GND                     
                                  DE62     GND                     
                                  DE64     GND                     
                                  DE66     GND                     
                                  DE68     GND                     
                                  DE70     GND                     
                                  DE72     GND                     
                                  DE74     GND                     
                                  DE76     GND                     
                                  DE78     UPI_CPU0_CPU1_P3P3_DP<16>
                                  DE80     UPI_CPU0_CPU1_P3P3_DN<13>
                                  DE82     GND                     
                                  DE84     GND                     
                                  DE86     P5E_CPU1_PE3_TX_DP<10>  
                                  DE88     GND                     
                                  DE90     P5E_CPU1_PE3_RX_DP<11>  
                                  DF2      UPI_CPU0_CPU1_P0P1_DP<11>
                                  DF4      GND                     
                                  DF6      UPI_CPU1_CPU0_P1P0_DP<10>
                                  DF8      GND                     
                                  DF10     P5E_CPU1_PE2_RX_DP<4>   
                                  DF12     GND                     
                                  DF14     P5E_CPU1_PE2_TX_DN<5>   
                                  DF16     GND                     
                                  DF18     M_H_CPU1_SB_DQS_DN<8>   
                                  DF20     M_H_CPU1_SB_DQ<26>      
                                  DF22     M_H_CPU1_SB_DQ<15>      
                                  DF24     M_H_CPU1_SB_DQS_DP<6>   
                                  DF26     M_H_CPU1_SB_DQ<10>      
                                  DF28     M_H_CPU1_SB_DQ<5>       
                                  DF30     M_H_CPU1_SB_DQS_DP<5>   
                                  DF32     M_H_CPU1_SB_DQ<2>       
                                  DF34     M_H_CPU1_SB_CB<3>       
                                  DF36     M_H_CPU1_SB_DQS_DP<4>   
                                  DF38     M_H_CPU1_SB_CB<4>       
                                  DF40     M_H_CPU1_SB_CA<0>       
                                  DF42     M_H_CPU1_CLK_DP<0>      
                                  DF44     M_E_CPU1_SB_RSP<0>      
                                  DF47     M_H_CPU1_SA_CA<5>       
                                  DF49     GND                     
                                  DF51     M_H_CPU1_SA_CS_N<0>     
                                  DF53     M_H_CPU1_SA_CB<7>       
                                  DF55     M_H_CPU1_SA_DQS_DP<9>   
                                  DF57     M_H_CPU1_SA_CB<2>       
                                  DF59     M_H_CPU1_SA_DQ<31>      
                                  DF61     M_H_CPU1_SA_DQS_DP<8>   
                                  DF63     M_H_CPU1_SA_DQ<26>      
                                  DF65     M_H_CPU1_SA_DQ<23>      
                                  DF67     M_H_CPU1_SA_DQS_DP<7>   
                                  DF69     M_H_CPU1_SA_DQ<18>      
                                  DF71     M_H_CPU1_SA_DQ<15>      
                                  DF73     M_H_CPU1_SA_DQS_DP<6>   
                                  DF75     M_H_CPU1_SA_DQ<10>      
                                  DF77     UPI_CPU0_CPU1_P3P3_DN<16>
                                  DF79     GND                     
                                  DF81     UPI_CPU0_CPU1_P3P3_DP<13>
                                  DF83     UPI_CPU0_CPU1_P3P3_DN<12>
                                  DF85     P5E_CPU1_PE3_TX_DN<9>   
                                  DF87     GND                     
                                  DF89     P5E_CPU1_PE3_RX_DP<10>  
                                  DF91     GND                     
                                  DG1      GND                     
                                  DG3      UPI_CPU0_CPU1_P0P1_DN<10>
                                  DG5      GND                     
                                  DG7      UPI_CPU1_CPU0_P1P0_DP<9>
                                  DG9      GND                     
                                  DG11     P5E_CPU1_PE2_RX_DP<5>   
                                  DG13     GND                     
                                  DG15     P5E_CPU1_PE2_TX_DP<5>   
                                  DG17     M_H_CPU1_SB_DQ<28>      
                                  DG19     M_H_CPU1_SB_DQ<27>      
                                  DG21     GND                     
                                  DG23     M_H_CPU1_SB_DQ<14>      
                                  DG25     M_H_CPU1_SB_DQ<11>      
                                  DG27     GND                     
                                  DG29     M_H_CPU1_SB_DQ<6>       
                                  DG31     M_H_CPU1_SB_DQ<3>       
                                  DG33     GND                     
                                  DG35     M_H_CPU1_SB_CB<2>       
                                  DG37     M_H_CPU1_SB_CB<5>       
                                  DG39     GND                     
                                  DG41     M_H_CPU1_SB_CA<1>       
                                  DG43     M_E_CPU1_SB_RSP<1>      
                                  DG45     GND                     
                                  DG48     M_H_CPU1_SA_CA<3>       
                                  DG50     M_H_CPU1_SA_CS_N<1>     
                                  DG52     GND                     
                                  DG54     M_H_CPU1_SA_CB<6>       
                                  DG56     M_H_CPU1_SA_CB<3>       
                                  DG58     GND                     
                                  DG60     M_H_CPU1_SA_DQ<30>      
                                  DG62     M_H_CPU1_SA_DQ<27>      
                                  DG64     GND                     
                                  DG66     M_H_CPU1_SA_DQ<22>      
                                  DG68     M_H_CPU1_SA_DQ<19>      
                                  DG70     GND                     
                                  DG72     M_H_CPU1_SA_DQ<14>      
                                  DG74     M_H_CPU1_SA_DQ<11>      
                                  DG76     GND                     
                                  DG78     UPI_CPU0_CPU1_P3P3_DN<10>
                                  DG80     GND                     
                                  DG82     UPI_CPU0_CPU1_P3P3_DP<11>
                                  DG84     GND                     
                                  DG86     P5E_CPU1_PE3_TX_DP<9>   
                                  DG88     GND                     
                                  DG90     P5E_CPU1_PE3_RX_DN<10>  
                                  DH2      UPI_CPU0_CPU1_P0P1_DP<10>
                                  DH4      GND                     
                                  DH6      UPI_CPU1_CPU0_P1P0_DN<9>
                                  DH8      GND                     
                                  DH10     P5E_CPU1_PE2_RX_DN<5>   
                                  DH12     GND                     
                                  DH14     P5E_CPU1_PE2_TX_DP<6>   
                                  DH16     GND                     
                                  DH18     M_H_CPU1_SB_DQS_DP<8>   
                                  DH20     GND                     
                                  DH22     GND                     
                                  DH24     M_H_CPU1_SB_DQS_DN<6>   
                                  DH26     GND                     
                                  DH28     GND                     
                                  DH30     M_H_CPU1_SB_DQS_DN<5>   
                                  DH32     GND                     
                                  DH34     GND                     
                                  DH36     M_H_CPU1_SB_DQS_DN<4>   
                                  DH38     GND                     
                                  DH40     GND                     
                                  DH42     M_H_CPU1_CLK_DN<0>      
                                  DH44     GND                     
                                  DH47     GND                     
                                  DH49     M_H_CPU1_SA_CA<1>       
                                  DH51     GND                     
                                  DH53     GND                     
                                  DH55     M_H_CPU1_SA_DQS_DN<9>   
                                  DH57     GND                     
                                  DH59     GND                     
                                  DH61     M_H_CPU1_SA_DQS_DN<8>   
                                  DH63     GND                     
                                  DH65     GND                     
                                  DH67     M_H_CPU1_SA_DQS_DN<7>   
                                  DH69     GND                     
                                  DH71     GND                     
                                  DH73     M_H_CPU1_SA_DQS_DN<6>   
                                  DH75     GND                     
                                  DH77     GND                     
                                  DH79     UPI_CPU0_CPU1_P3P3_DP<10>
                                  DH81     UPI_CPU0_CPU1_P3P3_DN<11>
                                  DH83     UPI_CPU0_CPU1_P3P3_DP<12>
                                  DH85     GND                     
                                  DH87     P5E_CPU1_PE3_TX_DN<8>   
                                  DH89     PVCCFA_EHV_FIVRA_CPU1   
                                  DH91     P5E_CPU1_PE3_RX_DN<9>   
                                  DJ1      UPI_CPU0_CPU1_P0P1_DN<9>
                                  DJ3      PVCCINFAON_CPU1         
                                  DJ5      UPI_CPU1_CPU0_P1P0_DP<8>
                                  DJ7      PVCCINFAON_CPU1         
                                  DJ9      P5E_CPU1_PE2_RX_DN<6>   
                                  DJ11     PVCCINFAON_CPU1         
                                  DJ13     P5E_CPU1_PE2_TX_DN<6>   
                                  DJ15     PVCCINFAON_CPU1         
                                  DJ17     M_H_CPU1_SB_DQ<30>      
                                  DJ19     GND                     
                                  DJ21     M_H_CPU1_SB_DQS_DP<2>   
                                  DJ23     GND                     
                                  DJ25     GND                     
                                  DJ27     M_G_CPU1_SB_DQS_DN<1>   
                                  DJ29     GND                     
                                  DJ31     GND                     
                                  DJ33     M_G_CPU1_SB_DQS_DN<0>   
                                  DJ35     GND                     
                                  DJ37     GND                     
                                  DJ39     M_H_CPU1_SB_CA<6>       
                                  DJ41     GND                     
                                  DJ43     GND                     
                                  DJ45     M_G_CPU1_CLK_DP<1>      
                                  DJ48     GND                     
                                  DJ50     GND                     
                                  DJ52     M_G_CPU1_SA_CA<0>       
                                  DJ54     GND                     
                                  DJ56     GND                     
                                  DJ58     M_G_CPU1_SA_DQS_DP<4>   
                                  DJ60     GND                     
                                  DJ62     GND                     
                                  DJ64     M_G_CPU1_SA_DQS_DP<3>   
                                  DJ66     GND                     
                                  DJ68     GND                     
                                  DJ70     M_G_CPU1_SA_DQS_DN<1>   
                                  DJ72     GND                     
                                  DJ74     GND                     
                                  DJ76     M_H_CPU1_SA_DQS_DN<0>   
                                  DJ78     UPI_CPU0_CPU1_P3P3_DN<9>
                                  DJ80     GND                     
                                  DJ82     GND                     
                                  DJ84     GND                     
                                  DJ86     P5E_CPU1_PE3_TX_DP<8>   
                                  DJ88     GND                     
                                  DJ90     P5E_CPU1_PE3_RX_DP<9>   
                                  DK2      UPI_CPU0_CPU1_P0P1_DP<9>
                                  DK4      GND                     
                                  DK6      UPI_CPU1_CPU0_P1P0_DN<8>
                                  DK8      GND                     
                                  DK10     P5E_CPU1_PE2_RX_DP<6>   
                                  DK12     GND                     
                                  DK14     P5E_CPU1_PE2_TX_DN<7>   
                                  DK16     GND                     
                                  DK18     GND                     
                                  DK20     M_H_CPU1_SB_DQ<20>      
                                  DK22     M_H_CPU1_SB_DQ<17>      
                                  DK24     GND                     
                                  DK26     M_G_CPU1_SB_DQ<12>      
                                  DK28     M_G_CPU1_SB_DQ<9>       
                                  DK30     GND                     
                                  DK32     M_G_CPU1_SB_DQ<4>       
                                  DK34     M_G_CPU1_SB_DQ<1>       
                                  DK36     GND                     
                                  DK38     M_H_CPU1_SB_CS_N<2>     
                                  DK40     M_H_CPU1_SB_CA<4>       
                                  DK42     GND                     
                                  DK44     M_G_CPU1_SA_CA<6>       
                                  DK47     M_F_CPU1_SB_RSP<1>      
                                  DK49     GND                     
                                  DK51     M_G_CPU1_SA_CA<2>       
                                  DK53     M_G_CPU1_SA_CS_N<3>     
                                  DK55     GND                     
                                  DK57     M_G_CPU1_SA_CB<4>       
                                  DK59     M_G_CPU1_SA_CB<1>       
                                  DK61     GND                     
                                  DK63     M_G_CPU1_SA_DQ<28>      
                                  DK65     M_G_CPU1_SA_DQ<25>      
                                  DK67     GND                     
                                  DK69     M_G_CPU1_SA_DQ<12>      
                                  DK71     M_G_CPU1_SA_DQ<9>       
                                  DK73     GND                     
                                  DK75     M_H_CPU1_SA_DQ<4>       
                                  DK77     GND                     
                                  DK79     GND                     
                                  DK81     GND                     
                                  DK83     GND                     
                                  DK85     P5E_CPU1_PE3_TX_DN<7>   
                                  DK87     GND                     
                                  DK89     P5E_CPU1_PE3_RX_DP<8>   
                                  DK91     GND                     
                                  DL1      GND                     
                                  DL3      UPI_CPU0_CPU1_P0P1_DN<8>
                                  DL5      GND                     
                                  DL7      UPI_CPU1_CPU0_P1P0_DN<7>
                                  DL9      GND                     
                                  DL11     P5E_CPU1_PE2_RX_DP<7>   
                                  DL13     GND                     
                                  DL15     P5E_CPU1_PE2_TX_DP<7>   
                                  DL17     GND                     
                                  DL19     M_H_CPU1_SB_DQ<21>      
                                  DL21     M_H_CPU1_SB_DQS_DN<2>   
                                  DL23     M_H_CPU1_SB_DQ<16>      
                                  DL25     M_G_CPU1_SB_DQ<13>      
                                  DL27     M_G_CPU1_SB_DQS_DP<1>   
                                  DL29     M_G_CPU1_SB_DQ<10>      
                                  DL31     M_G_CPU1_SB_DQ<5>       
                                  DL33     M_G_CPU1_SB_DQS_DP<0>   
                                  DL35     M_G_CPU1_SB_DQ<0>       
                                  DL37     M_H_CPU1_SB_CS_N<0>     
                                  DL39     GND                     
                                  DL41     M_H_CPU1_SB_CA<2>       
                                  DL43     M_G_CPU1_SA_PAR         
                                  DL45     M_G_CPU1_CLK_DN<1>      
                                  DL48     M_F_CPU1_SB_RSP<0>      
                                  DL50     M_G_CPU1_SA_CA<4>       
                                  DL52     GND                     
                                  DL54     M_G_CPU1_SA_CS_N<2>     
                                  DL56     M_G_CPU1_SA_CB<5>       
                                  DL58     M_G_CPU1_SA_DQS_DN<4>   
                                  DL60     M_G_CPU1_SA_CB<0>       
                                  DL62     M_G_CPU1_SA_DQ<29>      
                                  DL64     M_G_CPU1_SA_DQS_DN<3>   
                                  DL66     M_G_CPU1_SA_DQ<24>      
                                  DL68     M_G_CPU1_SA_DQ<13>      
                                  DL70     M_G_CPU1_SA_DQS_DP<1>   
                                  DL72     M_G_CPU1_SA_DQ<8>       
                                  DL74     M_H_CPU1_SA_DQ<5>       
                                  DL76     M_H_CPU1_SA_DQS_DP<0>   
                                  DL78     UPI_CPU0_CPU1_P3P3_DP<9>
                                  DL80     UPI_CPU1_CPU0_P3P3_DP<11>
                                  DL82     UPI_CPU1_CPU0_P3P3_DP<10>
                                  DL84     GND                     
                                  DL86     P5E_CPU1_PE3_TX_DP<7>   
                                  DL88     GND                     
                                  DL90     P5E_CPU1_PE3_RX_DN<8>   
                                  DM2      UPI_CPU0_CPU1_P0P1_DP<8>
                                  DM4      GND                     
                                  DM6      UPI_CPU1_CPU0_P1P0_DP<7>
                                  DM8      GND                     
                                  DM10     P5E_CPU1_PE2_RX_DN<7>   
                                  DM12     GND                     
                                  DM14     P5E_CPU1_PE2_TX_DP<8>   
                                  DM16     GND                     
                                  DM18     GND                     
                                  DM20     GND                     
                                  DM22     GND                     
                                  DM24     GND                     
                                  DM26     GND                     
                                  DM28     GND                     
                                  DM30     GND                     
                                  DM32     GND                     
                                  DM34     GND                     
                                  DM36     GND                     
                                  DM38     GND                     
                                  DM40     GND                     
                                  DM42     GND                     
                                  DM44     GND                     
                                  DM47     GND                     
                                  DM49     GND                     
                                  DM51     GND                     
                                  DM53     GND                     
                                  DM55     GND                     
                                  DM57     GND                     
                                  DM59     GND                     
                                  DM61     GND                     
                                  DM63     GND                     
                                  DM65     GND                     
                                  DM67     GND                     
                                  DM69     GND                     
                                  DM71     GND                     
                                  DM73     GND                     
                                  DM75     GND                     
                                  DM77     GND                     
                                  DM79     GND                     
                                  DM81     UPI_CPU1_CPU0_P3P3_DN<10>
                                  DM83     PVCCFA_EHV_FIVRA_CPU1   
                                  DM85     PVCCFA_EHV_FIVRA_CPU1   
                                  DM87     P5E_CPU1_PE3_TX_DN<6>   
                                  DM89     PVCCFA_EHV_FIVRA_CPU1   
                                  DM91     P5E_CPU1_PE3_RX_DP<7>   
                                  DN1      UPI_CPU0_CPU1_P0P1_DN<7>
                                  DN3      PVCCFA_EHV_FIVRA_CPU1   
                                  DN5      UPI_CPU1_CPU0_P1P0_DP<6>
                                  DN7      PVCCFA_EHV_FIVRA_CPU1   
                                  DN9      P5E_CPU1_PE2_RX_DN<8>   
                                  DN11     PVCCFA_EHV_FIVRA_CPU1   
                                  DN13     P5E_CPU1_PE2_TX_DN<8>   
                                  DN15     PVCCFA_EHV_FIVRA_CPU1   
                                  DN17     GND                     
                                  DN19     M_H_CPU1_SB_DQ<23>      
                                  DN21     M_H_CPU1_SB_DQS_DP<7>   
                                  DN23     M_H_CPU1_SB_DQ<18>      
                                  DN25     M_G_CPU1_SB_DQ<15>      
                                  DN27     M_G_CPU1_SB_DQS_DN<6>   
                                  DN29     M_G_CPU1_SB_DQ<8>       
                                  DN31     M_G_CPU1_SB_DQ<7>       
                                  DN33     M_G_CPU1_SB_DQS_DP<5>   
                                  DN35     M_G_CPU1_SB_DQ<2>       
                                  DN37     M_H_CPU1_SB_CS_N<1>     
                                  DN39     GND                     
                                  DN41     M_H_CPU1_SB_CA<3>       
                                  DN43     M_G_CPU1_SB_CA<0>       
                                  DN45     M_G_CPU1_CLK_DP<0>      
                                  DN48     M_F_CPU1_SA_RSP<0>      
                                  DN50     M_G_CPU1_SA_CA<5>       
                                  DN52     GND                     
                                  DN54     M_G_CPU1_SA_CS_N<0>     
                                  DN56     M_G_CPU1_SA_CB<7>       
                                  DN58     M_G_CPU1_SA_DQS_DP<9>   
                                  DN60     M_G_CPU1_SA_CB<2>       
                                  DN62     M_G_CPU1_SA_DQ<31>      
                                  DN64     M_G_CPU1_SA_DQS_DP<8>   
                                  DN66     M_G_CPU1_SA_DQ<26>      
                                  DN68     M_G_CPU1_SA_DQ<15>      
                                  DN70     M_G_CPU1_SA_DQS_DP<6>   
                                  DN72     M_G_CPU1_SA_DQ<10>      
                                  DN74     M_H_CPU1_SA_DQ<7>       
                                  DN76     M_H_CPU1_SA_DQS_DP<5>   
                                  DN78     GND                     
                                  DN80     UPI_CPU1_CPU0_P3P3_DN<11>
                                  DN82     UPI_CPU1_CPU0_P3P3_DN<9>
                                  DN84     GND                     
                                  DN86     P5E_CPU1_PE3_TX_DP<6>   
                                  DN88     GND                     
                                  DN90     P5E_CPU1_PE3_RX_DN<7>   
                                  DP2      UPI_CPU0_CPU1_P0P1_DP<7>
                                  DP4      GND                     
                                  DP6      UPI_CPU1_CPU0_P1P0_DN<6>
                                  DP8      GND                     
                                  DP10     P5E_CPU1_PE2_RX_DP<8>   
                                  DP12     GND                     
                                  DP14     P5E_CPU1_PE2_TX_DN<9>   
                                  DP16     GND                     
                                  DP18     GND                     
                                  DP20     M_H_CPU1_SB_DQ<22>      
                                  DP22     M_H_CPU1_SB_DQ<19>      
                                  DP24     GND                     
                                  DP26     M_G_CPU1_SB_DQ<14>      
                                  DP28     M_G_CPU1_SB_DQ<11>      
                                  DP30     GND                     
                                  DP32     M_G_CPU1_SB_DQ<6>       
                                  DP34     M_G_CPU1_SB_DQ<3>       
                                  DP36     GND                     
                                  DP38     M_H_CPU1_SB_CS_N<3>     
                                  DP40     M_H_CPU1_SB_CA<5>       
                                  DP42     GND                     
                                  DP44     M_G_CPU1_SB_CA<1>       
                                  DP47     M_F_CPU1_SA_RSP<1>      
                                  DP49     GND                     
                                  DP51     M_G_CPU1_SA_CA<3>       
                                  DP53     M_G_CPU1_SA_CS_N<1>     
                                  DP55     GND                     
                                  DP57     M_G_CPU1_SA_CB<6>       
                                  DP59     M_G_CPU1_SA_CB<3>       
                                  DP61     GND                     
                                  DP63     M_G_CPU1_SA_DQ<30>      
                                  DP65     M_G_CPU1_SA_DQ<27>      
                                  DP67     GND                     
                                  DP69     M_G_CPU1_SA_DQ<14>      
                                  DP71     M_G_CPU1_SA_DQ<11>      
                                  DP73     GND                     
                                  DP75     M_H_CPU1_SA_DQ<6>       
                                  DP77     M_H_CPU1_SA_DQ<3>       
                                  DP79     UPI_CPU1_CPU0_P3P3_DN<8>
                                  DP81     GND                     
                                  DP83     UPI_CPU1_CPU0_P3P3_DP<9>
                                  DP85     P5E_CPU1_PE3_TX_DN<5>   
                                  DP87     GND                     
                                  DP89     P5E_CPU1_PE3_RX_DN<6>   
                                  DP91     GND                     
                                  DR1      GND                     
                                  DR3      UPI_CPU0_CPU1_P0P1_DP<6>
                                  DR5      GND                     
                                  DR7      UPI_CPU1_CPU0_P1P0_DP<5>
                                  DR9      GND                     
                                  DR11     P5E_CPU1_PE2_RX_DP<9>   
                                  DR13     GND                     
                                  DR15     P5E_CPU1_PE2_TX_DP<9>   
                                  DR17     M_F_CPU1_SB_DQ<31>      
                                  DR19     GND                     
                                  DR21     M_H_CPU1_SB_DQS_DN<7>   
                                  DR23     GND                     
                                  DR25     GND                     
                                  DR27     M_G_CPU1_SB_DQS_DP<6>   
                                  DR29     GND                     
                                  DR31     GND                     
                                  DR33     M_G_CPU1_SB_DQS_DN<5>   
                                  DR35     GND                     
                                  DR37     GND                     
                                  DR39     M_H_CPU1_SB_PAR         
                                  DR41     GND                     
                                  DR43     GND                     
                                  DR45     M_G_CPU1_CLK_DN<0>      
                                  DR48     GND                     
                                  DR50     GND                     
                                  DR52     M_G_CPU1_SA_CA<1>       
                                  DR54     GND                     
                                  DR56     GND                     
                                  DR58     M_G_CPU1_SA_DQS_DN<9>   
                                  DR60     GND                     
                                  DR62     GND                     
                                  DR64     M_G_CPU1_SA_DQS_DN<8>   
                                  DR66     GND                     
                                  DR68     GND                     
                                  DR70     M_G_CPU1_SA_DQS_DN<6>   
                                  DR72     GND                     
                                  DR74     GND                     
                                  DR76     M_H_CPU1_SA_DQS_DN<5>   
                                  DR78     GND                     
                                  DR80     UPI_CPU1_CPU0_P3P3_DP<8>
                                  DR82     UPI_CPU1_CPU0_P3P3_DN<7>
                                  DR84     GND                     
                                  DR86     P5E_CPU1_PE3_TX_DP<5>   
                                  DR88     GND                     
                                  DR90     P5E_CPU1_PE3_RX_DP<6>   
                                  DT2      UPI_CPU0_CPU1_P0P1_DN<6>
                                  DT4      GND                     
                                  DT6      UPI_CPU1_CPU0_P1P0_DN<5>
                                  DT8      GND                     
                                  DT10     P5E_CPU1_PE2_RX_DN<9>   
                                  DT12     GND                     
                                  DT14     P5E_CPU1_PE2_TX_DP<10>  
                                  DT16     GND                     
                                  DT18     M_F_CPU1_SB_DQS_DN<3>   
                                  DT20     GND                     
                                  DT22     GND                     
                                  DT24     M_G_CPU1_SB_DQS_DP<2>   
                                  DT26     GND                     
                                  DT28     GND                     
                                  DT30     M_F_CPU1_SB_DQS_DP<0>   
                                  DT32     GND                     
                                  DT34     GND                     
                                  DT36     M_G_CPU1_SB_DQS_DP<9>   
                                  DT38     GND                     
                                  DT40     GND                     
                                  DT42     M_G_CPU1_SB_CA<6>       
                                  DT44     GND                     
                                  DT47     GND                     
                                  DT49     M_F_CPU1_CLK_DP<1>      
                                  DT51     GND                     
                                  DT53     GND                     
                                  DT55     M_F_CPU1_SA_DQS_DP<3>   
                                  DT57     GND                     
                                  DT59     GND                     
                                  DT61     M_G_CPU1_SA_DQS_DN<2>   
                                  DT63     GND                     
                                  DT65     GND                     
                                  DT67     M_F_CPU1_SA_DQS_DN<1>   
                                  DT69     GND                     
                                  DT71     GND                     
                                  DT73     M_G_CPU1_SA_DQS_DP<0>   
                                  DT75     GND                     
                                  DT77     M_H_CPU1_SA_DQ<1>       
                                  DT79     PVCCFA_EHV_FIVRA_CPU1   
                                  DT81     UPI_CPU1_CPU0_P3P3_DP<6>
                                  DT83     GND                     
                                  DT85     PVCCFA_EHV_FIVRA_CPU1   
                                  DT87     P5E_CPU1_PE3_TX_DN<4>   
                                  DT89     PVCCFA_EHV_FIVRA_CPU1   
                                  DT91     P5E_CPU1_PE3_RX_DP<5>   
                                  DU1      UPI_CPU0_CPU1_P0P1_DN<5>
                                  DU3      PVCCFA_EHV_FIVRA_CPU1   
                                  DU5      UPI_CPU1_CPU0_P1P0_DP<4>
                                  DU7      PVCCFA_EHV_FIVRA_CPU1   
                                  DU9      P5E_CPU1_PE2_RX_DN<10>  
                                  DU11     PVCCFA_EHV_FIVRA_CPU1   
                                  DU13     P5E_CPU1_PE2_TX_DN<10>  
                                  DU15     PVCCFA_EHV_FIVRA_CPU1   
                                  DU17     M_F_CPU1_SB_DQ<29>      
                                  DU19     M_F_CPU1_SB_DQ<25>      
                                  DU21     GND                     
                                  DU23     M_G_CPU1_SB_DQ<20>      
                                  DU25     M_G_CPU1_SB_DQ<17>      
                                  DU27     GND                     
                                  DU29     M_F_CPU1_SB_DQ<4>       
                                  DU31     M_F_CPU1_SB_DQ<1>       
                                  DU33     GND                     
                                  DU35     M_G_CPU1_SB_CB<0>       
                                  DU37     M_G_CPU1_SB_CB<5>       
                                  DU39     GND                     
                                  DU41     M_G_CPU1_SB_CS_N<2>     
                                  DU43     M_G_CPU1_SB_CA<4>       
                                  DU45     GND                     
                                  DU48     M_G_CPU1_SB_RSP<0>      
                                  DU50     M_F_CPU1_SB_CA<1>       
                                  DU52     GND                     
                                  DU54     M_F_CPU1_SA_DQ<28>      
                                  DU56     M_F_CPU1_SA_DQ<25>      
                                  DU58     GND                     
                                  DU60     M_G_CPU1_SA_DQ<20>      
                                  DU62     M_G_CPU1_SA_DQ<17>      
                                  DU64     GND                     
                                  DU66     M_F_CPU1_SA_DQ<12>      
                                  DU68     M_F_CPU1_SA_DQ<9>       
                                  DU70     GND                     
                                  DU72     M_G_CPU1_SA_DQ<4>       
                                  DU74     M_G_CPU1_SA_DQ<1>       
                                  DU76     GND                     
                                  DU78     GND                     
                                  DU80     UPI_CPU1_CPU0_P3P3_DN<6>
                                  DU82     UPI_CPU1_CPU0_P3P3_DP<7>
                                  DU84     GND                     
                                  DU86     P5E_CPU1_PE3_TX_DP<4>   
                                  DU88     GND                     
                                  DU90     P5E_CPU1_PE3_RX_DN<5>   
                                  DV2      UPI_CPU0_CPU1_P0P1_DP<5>
                                  DV4      GND                     
                                  DV6      UPI_CPU1_CPU0_P1P0_DN<4>
                                  DV8      GND                     
                                  DV10     P5E_CPU1_PE2_RX_DP<10>  
                                  DV12     GND                     
                                  DV14     P5E_CPU1_PE2_TX_DN<11>  
                                  DV16     GND                     
                                  DV18     M_F_CPU1_SB_DQS_DP<3>   
                                  DV20     M_F_CPU1_SB_DQ<24>      
                                  DV22     M_G_CPU1_SB_DQ<21>      
                                  DV24     M_G_CPU1_SB_DQS_DN<2>   
                                  DV26     M_G_CPU1_SB_DQ<16>      
                                  DV28     M_F_CPU1_SB_DQ<5>       
                                  DV30     M_F_CPU1_SB_DQS_DN<0>   
                                  DV32     M_F_CPU1_SB_DQ<0>       
                                  DV34     M_G_CPU1_SB_CB<1>       
                                  DV36     M_G_CPU1_SB_DQS_DN<9>   
                                  DV38     M_G_CPU1_SB_CB<4>       
                                  DV40     M_G_CPU1_SB_CS_N<3>     
                                  DV42     GND                     
                                  DV44     M_G_CPU1_SB_CA<2>       
                                  DV47     M_G_CPU1_SB_RSP<1>      
                                  DV49     M_F_CPU1_CLK_DN<1>      
                                  DV51     M_F_CPU1_SB_CA<0>       
                                  DV53     M_F_CPU1_SA_DQ<29>      
                                  DV55     M_F_CPU1_SA_DQS_DN<3>   
                                  DV57     M_F_CPU1_SA_DQ<24>      
                                  DV59     M_G_CPU1_SA_DQ<21>      
                                  DV61     M_G_CPU1_SA_DQS_DP<2>   
                                  DV63     M_G_CPU1_SA_DQ<16>      
                                  DV65     M_F_CPU1_SA_DQ<13>      
                                  DV67     M_F_CPU1_SA_DQS_DP<1>   
                                  DV69     M_F_CPU1_SA_DQ<8>       
                                  DV71     M_G_CPU1_SA_DQ<5>       
                                  DV73     M_G_CPU1_SA_DQS_DN<0>   
                                  DV75     M_G_CPU1_SA_DQ<0>       
                                  DV77     GND                     
                                  DV79     GND                     
                                  DV81     GND                     
                                  DV83     GND                     
                                  DV85     P5E_CPU1_PE3_TX_DN<3>   
                                  DV87     GND                     
                                  DV89     P5E_CPU1_PE3_RX_DN<4>   
                                  DV91     GND                     
                                  DW1      GND                     
                                  DW3      UPI_CPU0_CPU1_P0P1_DP<4>
                                  DW5      GND                     
                                  DW7      UPI_CPU1_CPU0_P1P0_DP<3>
                                  DW9      GND                     
                                  DW11     P5E_CPU1_PE2_RX_DP<11>  
                                  DW13     GND                     
                                  DW15     P5E_CPU1_PE2_TX_DP<11>  
                                  DW17     GND                     
                                  DW19     GND                     
                                  DW21     GND                     
                                  DW23     GND                     
                                  DW25     GND                     
                                  DW27     GND                     
                                  DW29     GND                     
                                  DW31     GND                     
                                  DW33     GND                     
                                  DW35     GND                     
                                  DW37     GND                     
                                  DW39     GND                     
                                  DW41     GND                     
                                  DW43     GND                     
                                  DW45     GND                     
                                  DW48     GND                     
                                  DW50     GND                     
                                  DW52     GND                     
                                  DW54     GND                     
                                  DW56     GND                     
                                  DW58     GND                     
                                  DW60     GND                     
                                  DW62     GND                     
                                  DW64     GND                     
                                  DW66     GND                     
                                  DW68     GND                     
                                  DW70     GND                     
                                  DW72     GND                     
                                  DW74     GND                     
                                  DW76     GND                     
                                  DW78     M_H_CPU1_SA_DQ<2>       
                                  DW80     GND                     
                                  DW82     GND                     
                                  DW84     GND                     
                                  DW86     P5E_CPU1_PE3_TX_DP<3>   
                                  DW88     GND                     
                                  DW90     P5E_CPU1_PE3_RX_DP<4>   
                                  DY2      UPI_CPU0_CPU1_P0P1_DN<4>
                                  DY4      GND                     
                                  DY6      UPI_CPU1_CPU0_P1P0_DN<3>
                                  DY8      GND                     
                                  DY10     P5E_CPU1_PE2_RX_DN<11>  
                                  DY12     GND                     
                                  DY14     P5E_CPU1_PE2_TX_DP<12>  
                                  DY16     GND                     
                                  DY18     M_F_CPU1_SB_DQS_DN<8>   
                                  DY20     M_F_CPU1_SB_DQ<26>      
                                  DY22     M_G_CPU1_SB_DQ<23>      
                                  DY24     M_G_CPU1_SB_DQS_DP<7>   
                                  DY26     M_G_CPU1_SB_DQ<18>      
                                  DY28     M_F_CPU1_SB_DQ<7>       
                                  DY30     M_F_CPU1_SB_DQS_DP<5>   
                                  DY32     M_F_CPU1_SB_DQ<2>       
                                  DY34     M_G_CPU1_SB_CB<3>       
                                  DY36     M_G_CPU1_SB_DQS_DP<4>   
                                  DY38     M_G_CPU1_SB_CB<6>       
                                  DY40     M_G_CPU1_SB_CS_N<1>     
                                  DY42     GND                     
                                  DY44     M_G_CPU1_SB_CA<3>       
                                  DY47     M_G_CPU1_SA_RSP<1>      
                                  DY49     M_F_CPU1_CLK_DN<0>      
                                  DY51     M_F_CPU1_SA_CA<6>       
                                  DY53     M_F_CPU1_SA_DQ<31>      
                                  DY55     M_F_CPU1_SA_DQS_DP<8>   
                                  DY57     M_F_CPU1_SA_DQ<26>      
                                  DY59     M_G_CPU1_SA_DQ<23>      
                                  DY61     M_G_CPU1_SA_DQS_DP<7>   
                                  DY63     M_G_CPU1_SA_DQ<18>      
                                  DY65     M_F_CPU1_SA_DQ<15>      
                                  DY67     M_F_CPU1_SA_DQS_DP<6>   
                                  DY69     M_F_CPU1_SA_DQ<10>      
                                  DY71     M_G_CPU1_SA_DQ<7>       
                                  DY73     M_G_CPU1_SA_DQS_DP<5>   
                                  DY75     M_G_CPU1_SA_DQ<2>       
                                  DY77     GND                     
                                  DY79     M_H_CPU1_SA_DQ<0>       
                                  DY81     UPI_CPU0_CPU1_P3P3_DN<8>
                                  DY83     UPI_CPU0_CPU1_P3P3_DP<7>
                                  DY85     PVCCFA_EHV_FIVRA_CPU1   
                                  DY87     P5E_CPU1_PE3_TX_DN<2>   
                                  DY89     PVCCFA_EHV_FIVRA_CPU1   
                                  DY91     P5E_CPU1_PE3_RX_DN<3>   
                                  E5       GND                     
                                  E7       M_A_CPU1_SB_DQ<31>      
                                  E9       M_A_CPU1_SB_DQS_DP<8>   
                                  E11      M_A_CPU1_SB_DQ<26>      
                                  E13      M_B_CPU1_SB_DQ<29>      
                                  E15      M_B_CPU1_SB_DQS_DN<8>   
                                  E17      M_B_CPU1_SB_DQ<26>      
                                  E19      M_A_CPU1_SB_DQ<23>      
                                  E21      M_A_CPU1_SB_DQS_DP<7>   
                                  E23      M_A_CPU1_SB_DQ<18>      
                                  E25      M_A_CPU1_SB_DQ<15>      
                                  E27      M_A_CPU1_SB_DQS_DP<6>   
                                  E29      M_A_CPU1_SB_DQ<10>      
                                  E31      M_A_CPU1_SB_CB<3>       
                                  E33      M_A_CPU1_SB_DQS_DP<4>   
                                  E35      M_A_CPU1_SB_CB<6>       
                                  E37      M_A_CPU1_SB_CS_N<3>     
                                  E39      GND                     
                                  E41      M_A_CPU1_SB_CA<3>       
                                  E43      M_A_CPU1_SB_CA<0>       
                                  E45      M_A_CPU1_CLK_DP<1>      
                                  E48      M_A_CPU1_SA_PAR         
                                  E50      M_A_CPU1_SA_CA<5>       
                                  E52      GND                     
                                  E54      M_A_CPU1_SA_CS_N<2>     
                                  E56      M_A_CPU1_SA_CB<7>       
                                  E58      M_A_CPU1_SA_DQS_DP<9>   
                                  E60      M_A_CPU1_SA_CB<2>       
                                  E62      M_A_CPU1_SA_DQ<31>      
                                  E64      M_A_CPU1_SA_DQS_DP<8>   
                                  E66      M_A_CPU1_SA_DQ<26>      
                                  E68      M_A_CPU1_SA_DQ<23>      
                                  E70      M_A_CPU1_SA_DQS_DP<7>   
                                  E72      M_A_CPU1_SA_DQ<17>      
                                  E74      GND                     
                                  E76      GND                     
                                  E78      GND                     
                                  E80      UPI_CPU0_CPU1_P2P2_DN<0>
                                  E82      UPI_CPU0_CPU1_P2P2_DP<1>
                                  E84      UPI_CPU1_CPU0_P2P2_DN<1>
                                  E86      GND                     
                                  E88      UPI_CPU1_CPU0_P2P2_DP<2>
                                  EA1      UPI_CPU0_CPU1_P0P1_DN<3>
                                  EA3      PVCCFA_EHV_FIVRA_CPU1   
                                  EA5      UPI_CPU1_CPU0_P1P0_DP<2>
                                  EA7      PVCCFA_EHV_FIVRA_CPU1   
                                  EA9      P5E_CPU1_PE2_RX_DN<12>  
                                  EA11     PVCCFA_EHV_FIVRA_CPU1   
                                  EA13     P5E_CPU1_PE2_TX_DN<12>  
                                  EA15     PVCCFA_EHV_FIVRA_CPU1   
                                  EA17     M_F_CPU1_SB_DQ<28>      
                                  EA19     M_F_CPU1_SB_DQ<27>      
                                  EA21     GND                     
                                  EA23     M_G_CPU1_SB_DQ<22>      
                                  EA25     M_G_CPU1_SB_DQ<19>      
                                  EA27     GND                     
                                  EA29     M_F_CPU1_SB_DQ<6>       
                                  EA31     M_F_CPU1_SB_DQ<3>       
                                  EA33     GND                     
                                  EA35     M_G_CPU1_SB_CB<2>       
                                  EA37     M_G_CPU1_SB_CB<7>       
                                  EA39     GND                     
                                  EA41     M_G_CPU1_SB_CS_N<0>     
                                  EA43     M_G_CPU1_SB_CA<5>       
                                  EA45     GND                     
                                  EA48     M_G_CPU1_SA_RSP<0>      
                                  EA50     M_F_CPU1_SA_PAR         
                                  EA52     GND                     
                                  EA54     M_F_CPU1_SA_DQ<30>      
                                  EA56     M_F_CPU1_SA_DQ<27>      
                                  EA58     GND                     
                                  EA60     M_G_CPU1_SA_DQ<22>      
                                  EA62     M_G_CPU1_SA_DQ<19>      
                                  EA64     GND                     
                                  EA66     M_F_CPU1_SA_DQ<14>      
                                  EA68     M_F_CPU1_SA_DQ<11>      
                                  EA70     GND                     
                                  EA72     M_G_CPU1_SA_DQ<6>       
                                  EA74     M_G_CPU1_SA_DQ<3>       
                                  EA76     GND                     
                                  EA78     GND                     
                                  EA80     GND                     
                                  EA82     UPI_CPU0_CPU1_P3P3_DN<7>
                                  EA84     GND                     
                                  EA86     P5E_CPU1_PE3_TX_DP<2>   
                                  EA88     GND                     
                                  EA90     P5E_CPU1_PE3_RX_DP<3>   
                                  EB2      UPI_CPU0_CPU1_P0P1_DP<3>
                                  EB4      GND                     
                                  EB6      UPI_CPU1_CPU0_P1P0_DN<2>
                                  EB8      GND                     
                                  EB10     P5E_CPU1_PE2_RX_DP<12>  
                                  EB12     GND                     
                                  EB14     P5E_CPU1_PE2_TX_DN<13>  
                                  EB16     GND                     
                                  EB18     M_F_CPU1_SB_DQS_DP<8>   
                                  EB20     GND                     
                                  EB22     GND                     
                                  EB24     M_G_CPU1_SB_DQS_DN<7>   
                                  EB26     GND                     
                                  EB28     GND                     
                                  EB30     M_F_CPU1_SB_DQS_DN<5>   
                                  EB32     GND                     
                                  EB34     GND                     
                                  EB36     M_G_CPU1_SB_DQS_DN<4>   
                                  EB38     GND                     
                                  EB40     GND                     
                                  EB42     M_G_CPU1_SB_PAR         
                                  EB44     GND                     
                                  EB47     GND                     
                                  EB49     M_F_CPU1_CLK_DP<0>      
                                  EB51     GND                     
                                  EB53     GND                     
                                  EB55     M_F_CPU1_SA_DQS_DN<8>   
                                  EB57     GND                     
                                  EB59     GND                     
                                  EB61     M_G_CPU1_SA_DQS_DN<7>   
                                  EB63     GND                     
                                  EB65     GND                     
                                  EB67     M_F_CPU1_SA_DQS_DN<6>   
                                  EB69     GND                     
                                  EB71     GND                     
                                  EB73     M_G_CPU1_SA_DQS_DN<5>   
                                  EB75     GND                     
                                  EB77     M_F_CPU1_SA_DQ<0>       
                                  EB79     GND                     
                                  EB81     UPI_CPU0_CPU1_P3P3_DP<8>
                                  EB83     GND                     
                                  EB85     P5E_CPU1_PE3_TX_DN<1>   
                                  EB87     GND                     
                                  EB89     P5E_CPU1_PE3_RX_DP<2>   
                                  EB91     GND                     
                                  EC1      GND                     
                                  EC3      UPI_CPU0_CPU1_P0P1_DP<2>
                                  EC5      GND                     
                                  EC7      UPI_CPU1_CPU0_P1P0_DN<1>
                                  EC9      GND                     
                                  EC11     P5E_CPU1_PE2_RX_DP<13>  
                                  EC13     GND                     
                                  EC15     P5E_CPU1_PE2_TX_DP<13>  
                                  EC17     M_F_CPU1_SB_DQ<30>      
                                  EC19     GND                     
                                  EC21     M_F_CPU1_SB_DQS_DP<1>   
                                  EC23     GND                     
                                  EC25     GND                     
                                  EC27     M_E_CPU1_SB_DQS_DP<0>   
                                  EC29     GND                     
                                  EC31     GND                     
                                  EC33     M_F_CPU1_SB_DQS_DP<9>   
                                  EC35     GND                     
                                  EC37     GND                     
                                  EC39     M_F_CPU1_SB_CA<6>       
                                  EC41     GND                     
                                  EC43     GND                     
                                  EC45     M_E_CPU1_CLK_DP<1>      
                                  EC48     GND                     
                                  EC50     GND                     
                                  EC52     M_F_CPU1_SA_CA<0>       
                                  EC54     GND                     
                                  EC56     GND                     
                                  EC58     M_F_CPU1_SA_DQS_DP<4>   
                                  EC60     GND                     
                                  EC62     GND                     
                                  EC64     M_F_CPU1_SA_DQS_DN<2>   
                                  EC66     GND                     
                                  EC68     GND                     
                                  EC70     M_E_CPU1_SA_DQS_DN<1>   
                                  EC72     GND                     
                                  EC74     GND                     
                                  EC76     M_F_CPU1_SA_DQS_DP<0>   
                                  EC78     PVCCFA_EHV_FIVRA_CPU1   
                                  EC80     UPI_CPU0_CPU1_P3P3_DN<6>
                                  EC82     GND                     
                                  EC84     GND                     
                                  EC86     P5E_CPU1_PE3_TX_DP<1>   
                                  EC88     GND                     
                                  EC90     P5E_CPU1_PE3_RX_DN<2>   
                                  ED2      UPI_CPU0_CPU1_P0P1_DN<2>
                                  ED4      GND                     
                                  ED6      UPI_CPU1_CPU0_P1P0_DP<1>
                                  ED8      GND                     
                                  ED10     P5E_CPU1_PE2_RX_DN<13>  
                                  ED12     GND                     
                                  ED14     P5E_CPU1_PE2_TX_DP<14>  
                                  ED16     GND                     
                                  ED18     GND                     
                                  ED20     M_F_CPU1_SB_DQ<12>      
                                  ED22     M_F_CPU1_SB_DQ<9>       
                                  ED24     GND                     
                                  ED26     M_E_CPU1_SB_DQ<4>       
                                  ED28     M_E_CPU1_SB_DQ<1>       
                                  ED30     GND                     
                                  ED32     M_F_CPU1_SB_CB<0>       
                                  ED34     M_F_CPU1_SB_CB<5>       
                                  ED36     GND                     
                                  ED38     M_F_CPU1_SB_CS_N<2>     
                                  ED40     M_F_CPU1_SB_CA<4>       
                                  ED42     GND                     
                                  ED44     M_E_CPU1_SA_CA<6>       
                                  ED47     M_H_CPU1_SB_RSP<1>      
                                  ED49     GND                     
                                  ED51     M_F_CPU1_SA_CA<2>       
                                  ED53     M_F_CPU1_SA_CS_N<3>     
                                  ED55     GND                     
                                  ED57     M_F_CPU1_SA_CB<4>       
                                  ED59     M_F_CPU1_SA_CB<1>       
                                  ED61     GND                     
                                  ED63     M_F_CPU1_SA_DQ<20>      
                                  ED65     M_F_CPU1_SA_DQ<17>      
                                  ED67     GND                     
                                  ED69     M_E_CPU1_SA_DQ<12>      
                                  ED71     M_E_CPU1_SA_DQ<9>       
                                  ED73     GND                     
                                  ED75     M_F_CPU1_SA_DQ<4>       
                                  ED77     M_F_CPU1_SA_DQ<2>       
                                  ED79     PVCCFA_EHV_FIVRA_CPU1   
                                  ED81     UPI_CPU0_CPU1_P3P3_DP<6>
                                  ED83     UPI_CPU0_CPU1_P3P3_DN<5>
                                  ED85     PVCCFA_EHV_FIVRA_CPU1   
                                  ED87     P5E_CPU1_PE3_TX_DP<0>   
                                  ED89     PVCCFA_EHV_FIVRA_CPU1   
                                  ED91     P5E_CPU1_PE3_RX_DN<1>   
                                  EE3      UPI_CPU0_CPU1_P0P1_DN<1>
                                  EE5      UPI_CPU1_CPU0_P1P0_DP<0>
                                  EE7      PVCCFA_EHV_FIVRA_CPU1   
                                  EE9      P5E_CPU1_PE2_RX_DN<14>  
                                  EE11     PVCCFA_EHV_FIVRA_CPU1   
                                  EE13     P5E_CPU1_PE2_TX_DN<14>  
                                  EE15     PVCCFA_EHV_FIVRA_CPU1   
                                  EE17     GND                     
                                  EE19     M_F_CPU1_SB_DQ<13>      
                                  EE21     M_F_CPU1_SB_DQS_DN<1>   
                                  EE23     M_F_CPU1_SB_DQ<8>       
                                  EE25     M_E_CPU1_SB_DQ<5>       
                                  EE27     M_E_CPU1_SB_DQS_DN<0>   
                                  EE29     M_E_CPU1_SB_DQ<0>       
                                  EE31     M_F_CPU1_SB_CB<1>       
                                  EE33     M_F_CPU1_SB_DQS_DN<9>   
                                  EE35     M_F_CPU1_SB_CB<4>       
                                  EE37     M_F_CPU1_SB_CS_N<3>     
                                  EE39     GND                     
                                  EE41     M_F_CPU1_SB_CA<2>       
                                  EE43     M_E_CPU1_SA_PAR         
                                  EE45     M_E_CPU1_CLK_DN<1>      
                                  EE48     M_H_CPU1_SB_RSP<0>      
                                  EE50     M_F_CPU1_SA_CA<4>       
                                  EE52     GND                     
                                  EE54     M_F_CPU1_SA_CS_N<2>     
                                  EE56     M_F_CPU1_SA_CB<5>       
                                  EE58     M_F_CPU1_SA_DQS_DN<4>   
                                  EE60     M_F_CPU1_SA_CB<0>       
                                  EE62     M_F_CPU1_SA_DQ<21>      
                                  EE64     M_F_CPU1_SA_DQS_DP<2>   
                                  EE66     M_F_CPU1_SA_DQ<16>      
                                  EE68     M_E_CPU1_SA_DQ<13>      
                                  EE70     M_E_CPU1_SA_DQS_DP<1>   
                                  EE72     M_E_CPU1_SA_DQ<8>       
                                  EE74     M_F_CPU1_SA_DQ<5>       
                                  EE76     M_F_CPU1_SA_DQS_DN<0>   
                                  EE78     GND                     
                                  EE80     GND                     
                                  EE82     UPI_CPU0_CPU1_P3P3_DP<4>
                                  EE84     PVCCFA_EHV_FIVRA_CPU1   
                                  EE86     P5E_CPU1_PE3_TX_DN<0>   
                                  EE88     GND                     
                                  EE90     P5E_CPU1_PE3_RX_DP<1>   
                                  EF2      GND                     
                                  EF4      GND                     
                                  EF6      UPI_CPU1_CPU0_P1P0_DN<0>
                                  EF8      GND                     
                                  EF10     P5E_CPU1_PE2_RX_DP<14>  
                                  EF12     GND                     
                                  EF14     P5E_CPU1_PE2_TX_DN<15>  
                                  EF16     GND                     
                                  EF18     GND                     
                                  EF20     GND                     
                                  EF22     GND                     
                                  EF24     GND                     
                                  EF26     GND                     
                                  EF28     GND                     
                                  EF30     GND                     
                                  EF32     GND                     
                                  EF34     GND                     
                                  EF36     GND                     
                                  EF38     GND                     
                                  EF40     GND                     
                                  EF42     GND                     
                                  EF44     GND                     
                                  EF47     GND                     
                                  EF49     GND                     
                                  EF51     GND                     
                                  EF53     GND                     
                                  EF55     GND                     
                                  EF57     GND                     
                                  EF59     GND                     
                                  EF61     GND                     
                                  EF63     GND                     
                                  EF65     GND                     
                                  EF67     GND                     
                                  EF69     GND                     
                                  EF71     GND                     
                                  EF73     GND                     
                                  EF75     GND                     
                                  EF77     GND                     
                                  EF79     PVCCFA_EHV_FIVRA_CPU1   
                                  EF81     UPI_CPU0_CPU1_P3P3_DN<4>
                                  EF83     UPI_CPU0_CPU1_P3P3_DP<5>
                                  EF85     GND                     
                                  EF87     GND                     
                                  EF89     GND                     
                                  EG3      UPI_CPU0_CPU1_P0P1_DP<1>
                                  EG5      GND                     
                                  EG7      GND                     
                                  EG9      GND                     
                                  EG11     P5E_CPU1_PE2_RX_DP<15>  
                                  EG13     GND                     
                                  EG15     P5E_CPU1_PE2_TX_DP<15>  
                                  EG19     M_F_CPU1_SB_DQ<15>      
                                  EG21     M_F_CPU1_SB_DQS_DP<6>   
                                  EG23     M_F_CPU1_SB_DQ<10>      
                                  EG25     M_E_CPU1_SB_DQ<7>       
                                  EG27     M_E_CPU1_SB_DQS_DP<5>   
                                  EG29     M_E_CPU1_SB_DQ<2>       
                                  EG31     M_F_CPU1_SB_CB<3>       
                                  EG33     M_F_CPU1_SB_DQS_DP<4>   
                                  EG35     M_F_CPU1_SB_CB<6>       
                                  EG37     M_F_CPU1_SB_CS_N<1>     
                                  EG39     GND                     
                                  EG41     M_F_CPU1_SB_CA<3>       
                                  EG43     M_E_CPU1_SB_CA<0>       
                                  EG45     M_E_CPU1_CLK_DP<0>      
                                  EG48     M_H_CPU1_SA_RSP<0>      
                                  EG50     M_F_CPU1_SA_CA<5>       
                                  EG52     GND                     
                                  EG54     M_F_CPU1_SA_CS_N<0>     
                                  EG56     M_F_CPU1_SA_CB<7>       
                                  EG58     M_F_CPU1_SA_DQS_DP<9>   
                                  EG60     M_F_CPU1_SA_CB<2>       
                                  EG62     M_F_CPU1_SA_DQ<23>      
                                  EG64     M_F_CPU1_SA_DQS_DP<7>   
                                  EG66     M_F_CPU1_SA_DQ<18>      
                                  EG68     M_E_CPU1_SA_DQ<15>      
                                  EG70     M_E_CPU1_SA_DQS_DP<6>   
                                  EG72     M_E_CPU1_SA_DQ<10>      
                                  EG74     M_F_CPU1_SA_DQ<7>       
                                  EG76     M_F_CPU1_SA_DQS_DP<5>   
                                  EG78     M_F_CPU1_SA_DQ<3>       
                                  EG80     PVCCFA_EHV_FIVRA_CPU1   
                                  EG82     GND                     
                                  EG84     GND                     
                                  EG86     GND                     
                                  EG88     GND                     
                                  EG90     GND                     
                                  EH2      UPI_CPU0_CPU1_P0P1_DN<0>
                                  EH4      GND                     
                                  EH6      GND                     
                                  EH8      M_G_CPU1_SB_DQ<25>      
                                  EH10     P5E_CPU1_PE2_RX_DN<15>  
                                  EH12     GND                     
                                  EH14     GND                     
                                  EH16     GND                     
                                  EH18     GND                     
                                  EH20     M_F_CPU1_SB_DQ<14>      
                                  EH22     M_F_CPU1_SB_DQ<11>      
                                  EH24     GND                     
                                  EH26     M_E_CPU1_SB_DQ<6>       
                                  EH28     M_E_CPU1_SB_DQ<3>       
                                  EH30     GND                     
                                  EH32     M_F_CPU1_SB_CB<2>       
                                  EH34     M_F_CPU1_SB_CB<7>       
                                  EH36     GND                     
                                  EH38     M_F_CPU1_SB_CS_N<0>     
                                  EH40     M_F_CPU1_SB_CA<5>       
                                  EH42     GND                     
                                  EH44     M_E_CPU1_SB_CA<1>       
                                  EH47     M_H_CPU1_SA_RSP<1>      
                                  EH49     GND                     
                                  EH51     M_F_CPU1_SA_CA<3>       
                                  EH53     M_F_CPU1_SA_CS_N<1>     
                                  EH55     GND                     
                                  EH57     M_F_CPU1_SA_CB<6>       
                                  EH59     M_F_CPU1_SA_CB<3>       
                                  EH61     GND                     
                                  EH63     M_F_CPU1_SA_DQ<22>      
                                  EH65     M_F_CPU1_SA_DQ<19>      
                                  EH67     GND                     
                                  EH69     M_E_CPU1_SA_DQ<14>      
                                  EH71     M_E_CPU1_SA_DQ<11>      
                                  EH73     GND                     
                                  EH75     M_F_CPU1_SA_DQ<6>       
                                  EH77     M_F_CPU1_SA_DQ<1>       
                                  EH79     GND                     
                                  EH81     GND                     
                                  EH83     GND                     
                                  EH85     UPI_CPU1_CPU0_P3P3_DN<0>
                                  EH87     UPI_CPU1_CPU0_P3P3_DP<4>
                                  EH89     P5E_CPU1_PE3_RX_DN<0>   
                                  EJ3      UPI_CPU0_CPU1_P0P1_DP<0>
                                  EJ5      M_G_CPU1_SB_DQ<29>      
                                  EJ7      GND                     
                                  EJ9      GND                     
                                  EJ11     GND                     
                                  EJ13     GND                     
                                  EJ15     PVCCFA_EHV_FIVRA_CPU1   
                                  EJ17     GND                     
                                  EJ19     GND                     
                                  EJ21     M_F_CPU1_SB_DQS_DN<6>   
                                  EJ23     GND                     
                                  EJ25     GND                     
                                  EJ27     M_E_CPU1_SB_DQS_DN<5>   
                                  EJ29     GND                     
                                  EJ31     GND                     
                                  EJ33     M_F_CPU1_SB_DQS_DN<4>   
                                  EJ35     GND                     
                                  EJ37     GND                     
                                  EJ39     M_F_CPU1_SB_PAR         
                                  EJ41     GND                     
                                  EJ43     GND                     
                                  EJ45     M_E_CPU1_CLK_DN<0>      
                                  EJ48     GND                     
                                  EJ50     GND                     
                                  EJ52     M_F_CPU1_SA_CA<1>       
                                  EJ54     GND                     
                                  EJ56     GND                     
                                  EJ58     M_F_CPU1_SA_DQS_DN<9>   
                                  EJ60     GND                     
                                  EJ62     GND                     
                                  EJ64     M_F_CPU1_SA_DQS_DN<7>   
                                  EJ66     GND                     
                                  EJ68     GND                     
                                  EJ70     M_E_CPU1_SA_DQS_DN<6>   
                                  EJ72     GND                     
                                  EJ74     GND                     
                                  EJ76     M_F_CPU1_SA_DQS_DN<5>   
                                  EJ78     GND                     
                                  EJ80     UPI_CPU0_CPU1_P3P3_DN<0>
                                  EJ82     UPI_CPU0_CPU1_P3P3_DP<3>
                                  EJ84     PVCCFA_EHV_FIVRA_CPU1   
                                  EJ86     UPI_CPU1_CPU0_P3P3_DN<4>
                                  EJ88     GND                     
                                  EJ90     P5E_CPU1_PE3_RX_DP<0>   
                                  EK2      GND                     
                                  EK4      GND                     
                                  EK6      M_G_CPU1_SB_DQ<28>      
                                  EK8      M_G_CPU1_SB_DQ<24>      
                                  EK10     GND                     
                                  EK12     M_F_CPU1_SB_DQS_DP<2>   
                                  EK14     GND                     
                                  EK16     GND                     
                                  EK18     M_E_CPU1_SB_DQS_DN<3>   
                                  EK20     GND                     
                                  EK22     GND                     
                                  EK24     M_E_CPU1_SB_DQS_DN<2>   
                                  EK26     GND                     
                                  EK28     GND                     
                                  EK30     M_E_CPU1_SB_DQS_DN<1>   
                                  EK32     GND                     
                                  EK34     GND                     
                                  EK36     M_E_CPU1_SB_DQS_DN<9>   
                                  EK38     GND                     
                                  EK40     GND                     
                                  EK42     M_E_CPU1_SB_CA<6>       
                                  EK44     GND                     
                                  EK47     GND                     
                                  EK49     M_E_CPU1_SA_CA<2>       
                                  EK51     GND                     
                                  EK53     GND                     
                                  EK55     M_E_CPU1_SA_DQS_DP<4>   
                                  EK57     GND                     
                                  EK59     GND                     
                                  EK61     M_E_CPU1_SA_DQS_DN<3>   
                                  EK63     GND                     
                                  EK65     GND                     
                                  EK67     M_E_CPU1_SA_DQS_DN<2>   
                                  EK69     GND                     
                                  EK71     GND                     
                                  EK73     M_E_CPU1_SA_DQ<5>       
                                  EK75     GND                     
                                  EK77     GND                     
                                  EK79     GND                     
                                  EK81     UPI_CPU0_CPU1_P3P3_DN<3>
                                  EK83     GND                     
                                  EK85     UPI_CPU1_CPU0_P3P3_DP<0>
                                  EK87     UPI_CPU1_CPU0_P3P3_DN<5>
                                  EK89     GND                     
                                  EL3      GND                     
                                  EL5      GND                     
                                  EL7      GND                     
                                  EL9      GND                     
                                  EL11     M_F_CPU1_SB_DQ<20>      
                                  EL13     M_F_CPU1_SB_DQ<17>      
                                  EL15     GND                     
                                  EL17     M_E_CPU1_SB_DQ<28>      
                                  EL19     M_E_CPU1_SB_DQ<25>      
                                  EL21     GND                     
                                  EL23     M_E_CPU1_SB_DQ<20>      
                                  EL25     M_E_CPU1_SB_DQ<17>      
                                  EL27     GND                     
                                  EL29     M_E_CPU1_SB_DQ<12>      
                                  EL31     M_E_CPU1_SB_DQ<9>       
                                  EL33     GND                     
                                  EL35     M_E_CPU1_SB_CB<0>       
                                  EL37     M_E_CPU1_SB_CB<5>       
                                  EL39     GND                     
                                  EL41     M_E_CPU1_SB_CS_N<3>     
                                  EL43     M_E_CPU1_SB_CA<4>       
                                  EL45     GND                     
                                  EL48     M_E_CPU1_SA_CA<3>       
                                  EL50     M_E_CPU1_SA_CS_N<3>     
                                  EL52     GND                     
                                  EL54     M_E_CPU1_SA_CB<4>       
                                  EL56     M_E_CPU1_SA_CB<1>       
                                  EL58     GND                     
                                  EL60     M_E_CPU1_SA_DQ<28>      
                                  EL62     M_E_CPU1_SA_DQ<25>      
                                  EL64     GND                     
                                  EL66     M_E_CPU1_SA_DQ<22>      
                                  EL68     M_E_CPU1_SA_DQS_DP<2>   
                                  EL70     GND                     
                                  EL72     GND                     
                                  EL74     M_E_CPU1_SA_DQ<4>       
                                  EL76     GND                     
                                  EL78     M_E_CPU1_SA_DQ<0>       
                                  EL80     UPI_CPU0_CPU1_P3P3_DP<0>
                                  EL82     UPI_CPU0_CPU1_P3P3_DN<2>
                                  EL84     UPI_CPU1_CPU0_P3P3_DN<1>
                                  EL86     GND                     
                                  EL88     UPI_CPU1_CPU0_P3P3_DP<5>
                                  EM4      M_G_CPU1_SB_DQ<31>      
                                  EM6      M_G_CPU1_SB_DQS_DN<8>   
                                  EM8      GND                     
                                  EM10     M_F_CPU1_SB_DQ<21>      
                                  EM12     M_F_CPU1_SB_DQS_DN<2>   
                                  EM14     M_F_CPU1_SB_DQ<16>      
                                  EM16     M_E_CPU1_SB_DQ<29>      
                                  EM18     M_E_CPU1_SB_DQS_DP<3>   
                                  EM20     M_E_CPU1_SB_DQ<24>      
                                  EM22     M_E_CPU1_SB_DQ<21>      
                                  EM24     M_E_CPU1_SB_DQS_DP<2>   
                                  EM26     M_E_CPU1_SB_DQ<16>      
                                  EM28     M_E_CPU1_SB_DQ<13>      
                                  EM30     M_E_CPU1_SB_DQS_DP<1>   
                                  EM32     M_E_CPU1_SB_DQ<8>       
                                  EM34     M_E_CPU1_SB_CB<1>       
                                  EM36     M_E_CPU1_SB_DQS_DP<9>   
                                  EM38     M_E_CPU1_SB_CB<4>       
                                  EM40     M_E_CPU1_SB_CS_N<2>     
                                  EM42     GND                     
                                  EM44     M_E_CPU1_SB_CA<2>       
                                  EM47     M_E_CPU1_SA_CA<4>       
                                  EM49     GND                     
                                  EM51     M_E_CPU1_SA_CS_N<2>     
                                  EM53     M_E_CPU1_SA_CB<5>       
                                  EM55     M_E_CPU1_SA_DQS_DN<4>   
                                  EM57     M_E_CPU1_SA_CB<0>       
                                  EM59     M_E_CPU1_SA_DQ<29>      
                                  EM61     M_E_CPU1_SA_DQS_DP<3>   
                                  EM63     M_E_CPU1_SA_DQ<24>      
                                  EM65     M_E_CPU1_SA_DQ<21>      
                                  EM67     M_E_CPU1_SA_DQS_DP<7>   
                                  EM69     M_E_CPU1_SA_DQ<17>      
                                  EM71     M_E_CPU1_SA_DQ<16>      
                                  EM73     GND                     
                                  EM75     M_E_CPU1_SA_DQS_DN<5>   
                                  EM77     M_E_CPU1_SA_DQ<1>       
                                  EM79     GND                     
                                  EM81     GND                     
                                  EM83     GND                     
                                  EM85     UPI_CPU1_CPU0_P3P3_DP<1>
                                  EM87     UPI_CPU1_CPU0_P3P3_DP<3>
                                  EN5      M_G_CPU1_SB_DQS_DP<8>   
                                  EN7      M_G_CPU1_SB_DQS_DP<3>   
                                  EN9      GND                     
                                  EN11     GND                     
                                  EN13     GND                     
                                  EN15     GND                     
                                  EN17     GND                     
                                  EN19     GND                     
                                  EN21     GND                     
                                  EN23     GND                     
                                  EN25     GND                     
                                  EN27     GND                     
                                  EN29     GND                     
                                  EN31     GND                     
                                  EN33     GND                     
                                  EN35     GND                     
                                  EN37     GND                     
                                  EN39     GND                     
                                  EN41     GND                     
                                  EN43     GND                     
                                  EN45     GND                     
                                  EN48     GND                     
                                  EN50     GND                     
                                  EN52     GND                     
                                  EN54     GND                     
                                  EN56     GND                     
                                  EN58     GND                     
                                  EN60     GND                     
                                  EN62     GND                     
                                  EN64     GND                     
                                  EN66     GND                     
                                  EN68     M_E_CPU1_SA_DQS_DN<7>   
                                  EN70     M_E_CPU1_SA_DQ<18>      
                                  EN72     GND                     
                                  EN74     M_E_CPU1_SA_DQS_DP<5>   
                                  EN76     M_E_CPU1_SA_DQS_DP<0>   
                                  EN78     GND                     
                                  EN80     GND                     
                                  EN82     UPI_CPU0_CPU1_P3P3_DP<2>
                                  EN84     PVCCFA_EHV_FIVRA_CPU1   
                                  EN86     UPI_CPU1_CPU0_P3P3_DP<2>
                                  EN88     GND                     
                                  EP4      M_G_CPU1_SB_DQ<30>      
                                  EP6      M_G_CPU1_SB_DQS_DN<3>   
                                  EP8      M_G_CPU1_SB_DQ<26>      
                                  EP10     M_F_CPU1_SB_DQ<23>      
                                  EP12     M_F_CPU1_SB_DQS_DP<7>   
                                  EP14     M_F_CPU1_SB_DQ<18>      
                                  EP16     M_E_CPU1_SB_DQ<31>      
                                  EP18     M_E_CPU1_SB_DQS_DP<8>   
                                  EP20     M_E_CPU1_SB_DQ<26>      
                                  EP22     M_E_CPU1_SB_DQ<23>      
                                  EP24     M_E_CPU1_SB_DQS_DP<7>   
                                  EP26     M_E_CPU1_SB_DQ<18>      
                                  EP28     M_E_CPU1_SB_DQ<15>      
                                  EP30     M_E_CPU1_SB_DQS_DP<6>   
                                  EP32     M_E_CPU1_SB_DQ<10>      
                                  EP34     M_E_CPU1_SB_CB<3>       
                                  EP36     M_E_CPU1_SB_DQS_DP<4>   
                                  EP38     M_E_CPU1_SB_CB<6>       
                                  EP40     M_E_CPU1_SB_CS_N<0>     
                                  EP42     M_E_CPU1_SB_PAR         
                                  EP44     M_E_CPU1_SB_CA<3>       
                                  EP47     M_E_CPU1_SA_CA<5>       
                                  EP49     M_E_CPU1_SA_CA<0>       
                                  EP51     M_E_CPU1_SA_CS_N<0>     
                                  EP53     M_E_CPU1_SA_CB<7>       
                                  EP55     M_E_CPU1_SA_DQS_DP<9>   
                                  EP57     M_E_CPU1_SA_CB<2>       
                                  EP59     M_E_CPU1_SA_DQ<31>      
                                  EP61     M_E_CPU1_SA_DQS_DP<8>   
                                  EP63     M_E_CPU1_SA_DQ<26>      
                                  EP65     M_E_CPU1_SA_DQ<23>      
                                  EP67     GND                     
                                  EP69     GND                     
                                  EP71     GND                     
                                  EP73     M_E_CPU1_SA_DQ<6>       
                                  EP75     M_E_CPU1_SA_DQS_DN<0>   
                                  EP77     GND                     
                                  EP79     M_E_CPU1_SA_DQ<2>       
                                  EP81     UPI_CPU0_CPU1_P3P3_DN<1>
                                  EP83     GND                     
                                  EP85     UPI_CPU1_CPU0_P3P3_DN<2>
                                  EP87     UPI_CPU1_CPU0_P3P3_DN<3>
                                  ER5      GND                     
                                  ER7      GND                     
                                  ER9      GND                     
                                  ER11     M_F_CPU1_SB_DQ<22>      
                                  ER13     M_F_CPU1_SB_DQ<19>      
                                  ER15     GND                     
                                  ER17     M_E_CPU1_SB_DQ<30>      
                                  ER19     M_E_CPU1_SB_DQ<27>      
                                  ER21     GND                     
                                  ER23     M_E_CPU1_SB_DQ<22>      
                                  ER25     M_E_CPU1_SB_DQ<19>      
                                  ER27     GND                     
                                  ER29     M_E_CPU1_SB_DQ<14>      
                                  ER31     M_E_CPU1_SB_DQ<11>      
                                  ER33     GND                     
                                  ER35     M_E_CPU1_SB_CB<2>       
                                  ER37     M_E_CPU1_SB_CB<7>       
                                  ER39     GND                     
                                  ER41     GND                     
                                  ER43     GND                     
                                  ER48     GND                     
                                  ER50     GND                     
                                  ER52     GND                     
                                  ER54     M_E_CPU1_SA_CB<6>       
                                  ER56     M_E_CPU1_SA_CB<3>       
                                  ER58     GND                     
                                  ER60     M_E_CPU1_SA_DQ<30>      
                                  ER62     M_E_CPU1_SA_DQ<27>      
                                  ER64     GND                     
                                  ER66     M_E_CPU1_SA_DQ<20>      
                                  ER68     M_E_CPU1_SA_DQ<19>      
                                  ER70     GND                     
                                  ER72     M_E_CPU1_SA_DQ<7>       
                                  ER74     GND                     
                                  ER76     M_E_CPU1_SA_DQ<3>       
                                  ER78     GND                     
                                  ER80     GND                     
                                  ER82     UPI_CPU0_CPU1_P3P3_DP<1>
                                  ER84     GND                     
                                  ER86     GND                     
                                  ET8      M_G_CPU1_SB_DQ<27>      
                                  ET10     GND                     
                                  ET12     M_F_CPU1_SB_DQS_DN<7>   
                                  ET14     GND                     
                                  ET16     GND                     
                                  ET18     M_E_CPU1_SB_DQS_DN<8>   
                                  ET20     GND                     
                                  ET22     GND                     
                                  ET24     M_E_CPU1_SB_DQS_DN<7>   
                                  ET26     GND                     
                                  ET28     GND                     
                                  ET30     M_E_CPU1_SB_DQS_DN<6>   
                                  ET32     GND                     
                                  ET34     GND                     
                                  ET36     M_E_CPU1_SB_DQS_DN<4>   
                                  ET38     GND                     
                                  ET40     M_E_CPU1_SB_CS_N<1>     
                                  ET42     M_E_CPU1_SB_CA<5>       
                                  ET49     M_E_CPU1_SA_CA<1>       
                                  ET51     M_E_CPU1_SA_CS_N<1>     
                                  ET53     GND                     
                                  ET55     M_E_CPU1_SA_DQS_DN<9>   
                                  ET57     GND                     
                                  ET59     GND                     
                                  ET61     M_E_CPU1_SA_DQS_DN<8>   
                                  F4       GND                     
                                  F6       GND                     
                                  F8       M_A_CPU1_SB_DQ<30>      
                                  F10      M_A_CPU1_SB_DQ<27>      
                                  F12      GND                     
                                  F14      M_B_CPU1_SB_DQ<31>      
                                  F16      M_B_CPU1_SB_DQ<27>      
                                  F18      GND                     
                                  F20      M_A_CPU1_SB_DQ<22>      
                                  F22      M_A_CPU1_SB_DQ<19>      
                                  F24      GND                     
                                  F26      M_A_CPU1_SB_DQ<14>      
                                  F28      M_A_CPU1_SB_DQ<11>      
                                  F30      GND                     
                                  F32      M_A_CPU1_SB_CB<2>       
                                  F34      M_A_CPU1_SB_CB<7>       
                                  F36      GND                     
                                  F38      M_A_CPU1_SB_CS_N<2>     
                                  F40      M_A_CPU1_SB_CA<5>       
                                  F42      GND                     
                                  F44      M_A_CPU1_SB_CA<1>       
                                  F47      PWRGD_DRAMPWRGD_CPU1_CD_LVC1_R
                                  F49      GND                     
                                  F51      M_A_CPU1_SA_CA<3>       
                                  F53      M_A_CPU1_SA_CS_N<3>     
                                  F55      GND                     
                                  F57      M_A_CPU1_SA_CB<6>       
                                  F59      M_A_CPU1_SA_CB<3>       
                                  F61      GND                     
                                  F63      M_A_CPU1_SA_DQ<30>      
                                  F65      M_A_CPU1_SA_DQ<27>      
                                  F67      GND                     
                                  F69      M_A_CPU1_SA_DQ<22>      
                                  F71      M_A_CPU1_SA_DQ<19>      
                                  F73      GND                     
                                  F75      M_A_CPU1_SA_DQ<7>       
                                  F77      M_A_CPU1_SA_DQS_DP<5>   
                                  F79      GND                     
                                  F81      UPI_CPU0_CPU1_P2P2_DN<1>
                                  F83      GND                     
                                  F85      UPI_CPU1_CPU0_P2P2_DP<1>
                                  F87      UPI_CPU1_CPU0_P2P2_DN<3>
                                  F89      GND                     
                                  G3       GND                     
                                  G7       GND                     
                                  G9       M_A_CPU1_SB_DQS_DN<8>   
                                  G11      GND                     
                                  G13      GND                     
                                  G15      M_B_CPU1_SB_DQS_DP<8>   
                                  G17      GND                     
                                  G19      GND                     
                                  G21      M_A_CPU1_SB_DQS_DN<7>   
                                  G23      GND                     
                                  G25      GND                     
                                  G27      M_A_CPU1_SB_DQS_DN<6>   
                                  G29      GND                     
                                  G31      GND                     
                                  G33      M_A_CPU1_SB_DQS_DN<4>   
                                  G35      GND                     
                                  G37      GND                     
                                  G39      M_A_CPU1_SB_PAR         
                                  G41      GND                     
                                  G43      GND                     
                                  G45      M_A_CPU1_CLK_DN<1>      
                                  G48      GND                     
                                  G50      GND                     
                                  G52      M_A_CPU1_SA_CA<1>       
                                  G54      GND                     
                                  G56      GND                     
                                  G58      M_A_CPU1_SA_DQS_DN<9>   
                                  G60      GND                     
                                  G62      GND                     
                                  G64      M_A_CPU1_SA_DQS_DN<8>   
                                  G66      GND                     
                                  G68      GND                     
                                  G70      M_A_CPU1_SA_DQS_DN<7>   
                                  G72      GND                     
                                  G74      GND                     
                                  G76      M_A_CPU1_SA_DQ<6>       
                                  G78      M_A_CPU1_SA_DQ<3>       
                                  G80      UPI_CPU0_CPU1_P2P2_DP<0>
                                  G82      UPI_CPU0_CPU1_P2P2_DN<2>
                                  G84      GND                     
                                  G86      UPI_CPU1_CPU0_P2P2_DP<4>
                                  G88      GND                     
                                  G90      GND                     
                                  H2       GND                     
                                  H4       GND                     
                                  H6       GND                     
                                  H8       GND                     
                                  H10      GND                     
                                  H14      GND                     
                                  H16      GND                     
                                  H18      M_B_CPU1_SB_DQS_DN<2>   
                                  H20      GND                     
                                  H22      GND                     
                                  H24      M_B_CPU1_SB_DQS_DN<1>   
                                  H26      GND                     
                                  H28      GND                     
                                  H30      M_A_CPU1_SB_DQS_DN<0>   
                                  H32      GND                     
                                  H34      GND                     
                                  H36      M_B_CPU1_SB_DQS_DP<9>   
                                  H38      GND                     
                                  H40      GND                     
                                  H42      M_B_CPU1_SB_CA<6>       
                                  H44      GND                     
                                  H47      GND                     
                                  H49      M_B_CPU1_SA_CA<0>       
                                  H51      GND                     
                                  H53      GND                     
                                  H55      M_B_CPU1_SA_DQS_DN<4>   
                                  H57      GND                     
                                  H59      GND                     
                                  H61      M_B_CPU1_SA_DQS_DN<2>   
                                  H63      GND                     
                                  H65      GND                     
                                  H67      M_A_CPU1_SA_DQS_DN<1>   
                                  H69      GND                     
                                  H71      GND                     
                                  H73      M_B_CPU1_SA_DQS_DN<0>   
                                  H75      GND                     
                                  H77      M_A_CPU1_SA_DQS_DN<5>   
                                  H79      GND                     
                                  H81      GND                     
                                  H83      UPI_CPU0_CPU1_P2P2_DP<2>
                                  H85      UPI_CPU1_CPU0_P2P2_DN<4>
                                  H87      UPI_CPU1_CPU0_P2P2_DP<3>
                                  H89      PVCCFA_EHV_FIVRA_CPU1   
                                  J3       UPI_CPU1_CPU0_P0P1_DP<0>
                                  J5       GND                     
                                  J7       PVCCFA_EHV_FIVRA_CPU1   
                                  J9       GND                     
                                  J11      PVCCFA_EHV_FIVRA_CPU1   
                                  J15      GND                     
                                  J17      M_B_CPU1_SB_DQ<20>      
                                  J19      M_B_CPU1_SB_DQ<17>      
                                  J21      GND                     
                                  J23      M_B_CPU1_SB_DQ<12>      
                                  J25      M_B_CPU1_SB_DQ<9>       
                                  J27      GND                     
                                  J29      M_A_CPU1_SB_DQ<4>       
                                  J31      M_A_CPU1_SB_DQ<1>       
                                  J33      GND                     
                                  J35      M_B_CPU1_SB_CB<0>       
                                  J37      M_B_CPU1_SB_CB<5>       
                                  J39      GND                     
                                  J41      M_B_CPU1_SB_CS_N<0>     
                                  J43      M_B_CPU1_SB_CA<4>       
                                  J45      GND                     
                                  J48      M_B_CPU1_SA_CA<2>       
                                  J50      M_B_CPU1_SA_CS_N<1>     
                                  J52      GND                     
                                  J54      M_B_CPU1_SA_CB<4>       
                                  J56      M_B_CPU1_SA_CB<1>       
                                  J58      GND                     
                                  J60      M_B_CPU1_SA_DQ<20>      
                                  J62      M_B_CPU1_SA_DQ<17>      
                                  J64      GND                     
                                  J66      M_A_CPU1_SA_DQ<12>      
                                  J68      M_A_CPU1_SA_DQ<9>       
                                  J70      GND                     
                                  J72      M_B_CPU1_SA_DQ<4>       
                                  J74      M_B_CPU1_SA_DQ<1>       
                                  J76      GND                     
                                  J78      GND                     
                                  J80      PVCCFA_EHV_FIVRA_CPU1   
                                  J82      UPI_CPU0_CPU1_P2P2_DN<4>
                                  J84      GND                     
                                  J86      GND                     
                                  J88      GND                     
                                  J90      P5E_CPU1_PE4_RX_DN<15>  
                                  K2       GND                     
                                  K4       UPI_CPU1_CPU0_P0P1_DN<0>
                                  K6       UPI_CPU0_CPU1_P1P0_DN<0>
                                  K8       GND                     
                                  K10      P5E_CPU1_PE0_RX_DN<15>  
                                  K12      GND                     
                                  K14      GND                     
                                  K16      M_B_CPU1_SB_DQ<21>      
                                  K18      M_B_CPU1_SB_DQS_DP<2>   
                                  K20      M_B_CPU1_SB_DQ<16>      
                                  K22      M_B_CPU1_SB_DQ<13>      
                                  K24      M_B_CPU1_SB_DQS_DP<1>   
                                  K26      M_B_CPU1_SB_DQ<8>       
                                  K28      M_A_CPU1_SB_DQ<5>       
                                  K30      M_A_CPU1_SB_DQS_DP<0>   
                                  K32      M_A_CPU1_SB_DQ<0>       
                                  K34      M_B_CPU1_SB_CB<1>       
                                  K36      M_B_CPU1_SB_DQS_DN<9>   
                                  K38      M_B_CPU1_SB_CB<4>       
                                  K40      M_B_CPU1_SB_CS_N<1>     
                                  K42      GND                     
                                  K44      M_B_CPU1_SB_CA<2>       
                                  K47      M_B_CPU1_SA_CA<4>       
                                  K49      GND                     
                                  K51      M_B_CPU1_SA_CS_N<0>     
                                  K53      M_B_CPU1_SA_CB<5>       
                                  K55      M_B_CPU1_SA_DQS_DP<4>   
                                  K57      M_B_CPU1_SA_CB<0>       
                                  K59      M_B_CPU1_SA_DQ<21>      
                                  K61      M_B_CPU1_SA_DQS_DP<2>   
                                  K63      M_B_CPU1_SA_DQ<16>      
                                  K65      M_A_CPU1_SA_DQ<13>      
                                  K67      M_A_CPU1_SA_DQS_DP<1>   
                                  K69      M_A_CPU1_SA_DQ<8>       
                                  K71      M_B_CPU1_SA_DQ<5>       
                                  K73      M_B_CPU1_SA_DQS_DP<0>   
                                  K75      M_B_CPU1_SA_DQ<0>       
                                  K77      GND                     
                                  K79      UPI_CPU0_CPU1_P2P2_DN<3>
                                  K81      UPI_CPU0_CPU1_P2P2_DP<5>
                                  K83      GND                     
                                  K85      GND                     
                                  K87      PVCCFA_EHV_FIVRA_CPU1   
                                  K89      P5E_CPU1_PE4_RX_DP<15>  
                                  L3       UPI_CPU1_CPU0_P0P1_DP<1>
                                  L5       GND                     
                                  L7       UPI_CPU0_CPU1_P1P0_DP<0>
                                  L9       GND                     
                                  L11      P5E_CPU1_PE0_RX_DP<15>  
                                  L13      GND                     
                                  L15      GND                     
                                  L17      GND                     
                                  L19      GND                     
                                  L21      GND                     
                                  L23      GND                     
                                  L25      GND                     
                                  L27      GND                     
                                  L29      GND                     
                                  L31      GND                     
                                  L33      GND                     
                                  L35      GND                     
                                  L37      GND                     
                                  L39      GND                     
                                  L41      GND                     
                                  L43      GND                     
                                  L45      GND                     
                                  L48      GND                     
                                  L50      GND                     
                                  L52      GND                     
                                  L54      GND                     
                                  L56      GND                     
                                  L58      GND                     
                                  L60      GND                     
                                  L62      GND                     
                                  L64      GND                     
                                  L66      GND                     
                                  L68      GND                     
                                  L70      GND                     
                                  L72      GND                     
                                  L74      GND                     
                                  L76      GND                     
                                  L78      GND                     
                                  L80      UPI_CPU0_CPU1_P2P2_DN<5>
                                  L82      UPI_CPU0_CPU1_P2P2_DP<4>
                                  L84      PVCCFA_EHV_FIVRA_CPU1   
                                  L86      P5E_CPU1_PE4_TX_DN<15>  
                                  L88      GND                     
                                  L90      GND                     
                                  M2       UPI_CPU1_CPU0_P0P1_DN<1>
                                  M4       GND                     
                                  M6       UPI_CPU0_CPU1_P1P0_DP<1>
                                  M8       GND                     
                                  M10      P5E_CPU1_PE0_RX_DN<14>  
                                  M12      GND                     
                                  M14      P5E_CPU1_PE0_TX_DP<15>  
                                  M16      M_B_CPU1_SB_DQ<23>      
                                  M18      M_B_CPU1_SB_DQS_DN<7>   
                                  M20      M_B_CPU1_SB_DQ<18>      
                                  M22      M_B_CPU1_SB_DQ<15>      
                                  M24      M_B_CPU1_SB_DQS_DN<6>   
                                  M26      M_B_CPU1_SB_DQ<10>      
                                  M28      M_A_CPU1_SB_DQ<7>       
                                  M30      M_A_CPU1_SB_DQS_DN<5>   
                                  M32      M_A_CPU1_SB_DQ<2>       
                                  M34      M_B_CPU1_SB_CB<3>       
                                  M36      M_B_CPU1_SB_DQS_DP<4>   
                                  M38      M_B_CPU1_SB_CB<6>       
                                  M40      M_B_CPU1_SB_CS_N<3>     
                                  M42      GND                     
                                  M44      M_B_CPU1_SB_CA<3>       
                                  M47      M_B_CPU1_SA_CA<5>       
                                  M49      GND                     
                                  M51      M_B_CPU1_SA_CS_N<2>     
                                  M53      M_B_CPU1_SA_CB<7>       
                                  M55      M_B_CPU1_SA_DQS_DN<9>   
                                  M57      M_B_CPU1_SA_CB<2>       
                                  M59      M_B_CPU1_SA_DQ<23>      
                                  M61      M_B_CPU1_SA_DQS_DN<7>   
                                  M63      M_B_CPU1_SA_DQ<18>      
                                  M65      M_A_CPU1_SA_DQ<15>      
                                  M67      M_A_CPU1_SA_DQS_DP<6>   
                                  M69      M_A_CPU1_SA_DQ<10>      
                                  M71      M_B_CPU1_SA_DQ<7>       
                                  M73      M_B_CPU1_SA_DQS_DN<5>   
                                  M75      M_B_CPU1_SA_DQ<2>       
                                  M77      M_A_CPU1_SA_DQ<2>       
                                  M79      UPI_CPU0_CPU1_P2P2_DP<3>
                                  M81      GND                     
                                  M83      GND                     
                                  M85      PVCCFA_EHV_FIVRA_CPU1   
                                  M87      P5E_CPU1_PE4_TX_DP<15>  
                                  M89      PVCCFA_EHV_FIVRA_CPU1   
                                  N1       UPI_CPU1_CPU0_P0P1_DN<2>
                                  N3       PVCCFA_EHV_CPU1         
                                  N5       UPI_CPU0_CPU1_P1P0_DN<1>
                                  N7       PVCCFA_EHV_FIVRA_CPU1   
                                  N9       P5E_CPU1_PE0_RX_DP<14>  
                                  N11      PVCCFA_EHV_FIVRA_CPU1   
                                  N13      P5E_CPU1_PE0_TX_DN<15>  
                                  N15      GND                     
                                  N17      M_B_CPU1_SB_DQ<22>      
                                  N19      M_B_CPU1_SB_DQ<19>      
                                  N21      GND                     
                                  N23      M_B_CPU1_SB_DQ<14>      
                                  N25      M_B_CPU1_SB_DQ<11>      
                                  N27      GND                     
                                  N29      M_A_CPU1_SB_DQ<6>       
                                  N31      M_A_CPU1_SB_DQ<3>       
                                  N33      GND                     
                                  N35      M_B_CPU1_SB_CB<2>       
                                  N37      M_B_CPU1_SB_CB<7>       
                                  N39      GND                     
                                  N41      M_B_CPU1_SB_CS_N<2>     
                                  N43      M_B_CPU1_SB_CA<5>       
                                  N45      GND                     
                                  N48      M_B_CPU1_SA_CA<3>       
                                  N50      M_B_CPU1_SA_CS_N<3>     
                                  N52      GND                     
                                  N54      M_B_CPU1_SA_CB<6>       
                                  N56      M_B_CPU1_SA_CB<3>       
                                  N58      GND                     
                                  N60      M_B_CPU1_SA_DQ<22>      
                                  N62      M_B_CPU1_SA_DQ<19>      
                                  N64      GND                     
                                  N66      M_A_CPU1_SA_DQ<14>      
                                  N68      M_A_CPU1_SA_DQ<11>      
                                  N70      GND                     
                                  N72      M_B_CPU1_SA_DQ<6>       
                                  N74      M_B_CPU1_SA_DQ<3>       
                                  N76      GND                     
                                  N78      GND                     
                                  N80      GND                     
                                  N82      GND                     
                                  N84      GND                     
                                  N86      P5E_CPU1_PE4_TX_DP<14>  
                                  N88      GND                     
                                  N90      P5E_CPU1_PE4_RX_DP<14>  
                                  P2       UPI_CPU1_CPU0_P0P1_DP<2>
                                  P4       GND                     
                                  P6       UPI_CPU0_CPU1_P1P0_DN<2>
                                  P8       GND                     
                                  P10      P5E_CPU1_PE0_RX_DN<13>  
                                  P12      GND                     
                                  P14      P5E_CPU1_PE0_TX_DN<14>  
                                  P16      GND                     
                                  P18      M_B_CPU1_SB_DQS_DP<7>   
                                  P20      GND                     
                                  P22      GND                     
                                  P24      M_B_CPU1_SB_DQS_DP<6>   
                                  P26      GND                     
                                  P28      GND                     
                                  P30      M_A_CPU1_SB_DQS_DP<5>   
                                  P32      GND                     
                                  P34      GND                     
                                  P36      M_B_CPU1_SB_DQS_DN<4>   
                                  P38      GND                     
                                  P40      GND                     
                                  P42      M_B_CPU1_SB_PAR         
                                  P44      GND                     
                                  P47      GND                     
                                  P49      M_B_CPU1_SA_CA<1>       
                                  P51      GND                     
                                  P53      GND                     
                                  P55      M_B_CPU1_SA_DQS_DP<9>   
                                  P57      GND                     
                                  P59      GND                     
                                  P61      M_B_CPU1_SA_DQS_DP<7>   
                                  P63      GND                     
                                  P65      GND                     
                                  P67      M_A_CPU1_SA_DQS_DN<6>   
                                  P69      GND                     
                                  P71      GND                     
                                  P73      M_B_CPU1_SA_DQS_DP<5>   
                                  P75      GND                     
                                  P77      GND                     
                                  P79      PVCCFA_EHV_FIVRA_CPU1   
                                  P81      UPI_CPU1_CPU0_P2P2_DN<5>
                                  P83      UPI_CPU1_CPU0_P2P2_DP<6>
                                  P85      P5E_CPU1_PE4_TX_DN<14>  
                                  P87      GND                     
                                  P89      P5E_CPU1_PE4_RX_DN<14>  
                                  P91      GND                     
                                  R1       GND                     
                                  R3       UPI_CPU1_CPU0_P0P1_DP<3>
                                  R5       GND                     
                                  R7       UPI_CPU0_CPU1_P1P0_DP<2>
                                  R9       GND                     
                                  R11      P5E_CPU1_PE0_RX_DP<13>  
                                  R13      GND                     
                                  R15      P5E_CPU1_PE0_TX_DP<14>  
                                  R17      GND                     
                                  R19      GND                     
                                  R21      M_C_CPU1_SB_DQS_DN<2>   
                                  R23      GND                     
                                  R25      GND                     
                                  R27      M_B_CPU1_SB_DQS_DN<0>   
                                  R29      GND                     
                                  R31      GND                     
                                  R33      M_C_CPU1_SB_DQS_DN<9>   
                                  R35      GND                     
                                  R37      GND                     
                                  R39      M_C_CPU1_SB_CA<6>       
                                  R41      GND                     
                                  R43      GND                     
                                  R45      M_B_CPU1_CLK_DN<0>      
                                  R48      GND                     
                                  R50      GND                     
                                  R52      M_C_CPU1_SA_CA<0>       
                                  R54      GND                     
                                  R56      GND                     
                                  R58      M_B_CPU1_SA_DQS_DN<3>   
                                  R60      GND                     
                                  R62      GND                     
                                  R64      M_C_CPU1_SA_DQS_DN<2>   
                                  R66      GND                     
                                  R68      GND                     
                                  R70      M_B_CPU1_SA_DQS_DN<1>   
                                  R72      GND                     
                                  R74      GND                     
                                  R76      M_C_CPU1_SA_DQS_DN<0>   
                                  R78      GND                     
                                  R80      PVCCFA_EHV_FIVRA_CPU1   
                                  R82      UPI_CPU1_CPU0_P2P2_DN<6>
                                  R84      GND                     
                                  R86      P5E_CPU1_PE4_TX_DN<13>  
                                  R88      GND                     
                                  R90      P5E_CPU1_PE4_RX_DP<13>  
                                  T2       UPI_CPU1_CPU0_P0P1_DN<3>
                                  T4       GND                     
                                  T6       UPI_CPU0_CPU1_P1P0_DP<3>
                                  T8       GND                     
                                  T10      P5E_CPU1_PE0_RX_DN<12>  
                                  T12      GND                     
                                  T14      P5E_CPU1_PE0_TX_DP<13>  
                                  T16      GND                     
                                  T18      GND                     
                                  T20      M_C_CPU1_SB_DQ<20>      
                                  T22      M_C_CPU1_SB_DQ<17>      
                                  T24      GND                     
                                  T26      M_B_CPU1_SB_DQ<4>       
                                  T28      M_B_CPU1_SB_DQ<1>       
                                  T30      GND                     
                                  T32      M_C_CPU1_SB_CB<0>       
                                  T34      M_C_CPU1_SB_CB<5>       
                                  T36      GND                     
                                  T38      M_C_CPU1_SB_CS_N<0>     
                                  T40      M_C_CPU1_SB_CA<4>       
                                  T42      GND                     
                                  T44      M_B_CPU1_SB_CA<0>       
                                  T47      M_C_CPU1_SA_PAR         
                                  T49      GND                     
                                  T51      M_C_CPU1_SA_CA<2>       
                                  T53      M_C_CPU1_SA_CS_N<1>     
                                  T55      GND                     
                                  T57      M_B_CPU1_SA_DQ<28>      
                                  T59      M_B_CPU1_SA_DQ<25>      
                                  T61      GND                     
                                  T63      M_C_CPU1_SA_DQ<20>      
                                  T65      M_C_CPU1_SA_DQ<17>      
                                  T67      GND                     
                                  T69      M_B_CPU1_SA_DQ<12>      
                                  T71      M_B_CPU1_SA_DQ<9>       
                                  T73      GND                     
                                  T75      M_C_CPU1_SA_DQ<4>       
                                  T77      M_C_CPU1_SA_DQ<1>       
                                  T79      GND                     
                                  T81      UPI_CPU1_CPU0_P2P2_DP<5>
                                  T83      GND                     
                                  T85      PVCCFA_EHV_FIVRA_CPU1   
                                  T87      P5E_CPU1_PE4_TX_DP<13>  
                                  T89      PVCCFA_EHV_FIVRA_CPU1   
                                  T91      P5E_CPU1_PE4_RX_DN<13>  
                                  U1       UPI_CPU1_CPU0_P0P1_DN<4>
                                  U3       PVCCFA_EHV_CPU1         
                                  U5       UPI_CPU0_CPU1_P1P0_DN<3>
                                  U7       PVCCFA_EHV_FIVRA_CPU1   
                                  U9       P5E_CPU1_PE0_RX_DP<12>  
                                  U11      PVCCFA_EHV_FIVRA_CPU1   
                                  U13      P5E_CPU1_PE0_TX_DN<13>  
                                  U15      PVCCFA_EHV_FIVRA_CPU1   
                                  U19      M_C_CPU1_SB_DQ<21>      
                                  U21      M_C_CPU1_SB_DQS_DP<2>   
                                  U23      M_C_CPU1_SB_DQ<16>      
                                  U25      M_B_CPU1_SB_DQ<5>       
                                  U27      M_B_CPU1_SB_DQS_DP<0>   
                                  U29      M_B_CPU1_SB_DQ<0>       
                                  U31      M_C_CPU1_SB_CB<1>       
                                  U33      M_C_CPU1_SB_DQS_DP<9>   
                                  U35      M_C_CPU1_SB_CB<4>       
                                  U37      M_C_CPU1_SB_CS_N<1>     
                                  U39      GND                     
                                  U41      M_C_CPU1_SB_CA<2>       
                                  U43      M_B_CPU1_SB_CA<1>       
                                  U45      M_B_CPU1_CLK_DP<0>      
                                  U48      M_C_CPU1_SA_CA<6>       
                                  U50      M_C_CPU1_SA_CA<4>       
                                  U52      GND                     
                                  U54      M_C_CPU1_SA_CS_N<0>     
                                  U56      M_B_CPU1_SA_DQ<29>      
                                  U58      M_B_CPU1_SA_DQS_DP<3>   
                                  U60      M_B_CPU1_SA_DQ<24>      
                                  U62      M_C_CPU1_SA_DQ<21>      
                                  U64      M_C_CPU1_SA_DQS_DP<2>   
                                  U66      M_C_CPU1_SA_DQ<16>      
                                  U68      M_B_CPU1_SA_DQ<13>      
                                  U70      M_B_CPU1_SA_DQS_DP<1>   
                                  U72      M_B_CPU1_SA_DQ<8>       
                                  U74      M_C_CPU1_SA_DQ<5>       
                                  U76      M_C_CPU1_SA_DQS_DP<0>   
                                  U78      M_C_CPU1_SA_DQ<0>       
                                  U80      UPI_CPU1_CPU0_P2P2_DN<7>
                                  U82      GND                     
                                  U84      GND                     
                                  U86      P5E_CPU1_PE4_TX_DN<12>  
                                  U88      GND                     
                                  U90      P5E_CPU1_PE4_RX_DP<12>  
                                  V2       UPI_CPU1_CPU0_P0P1_DP<4>
                                  V4       GND                     
                                  V6       UPI_CPU0_CPU1_P1P0_DN<4>
                                  V8       GND                     
                                  V10      P5E_CPU1_PE0_RX_DN<11>  
                                  V12      GND                     
                                  V14      P5E_CPU1_PE0_TX_DN<12>  
                                  V16      GND                     
                                  V18      GND                     
                                  V20      GND                     
                                  V22      GND                     
                                  V24      GND                     
                                  V26      GND                     
                                  V28      GND                     
                                  V30      GND                     
                                  V32      GND                     
                                  V34      GND                     
                                  V36      GND                     
                                  V38      GND                     
                                  V40      GND                     
                                  V42      GND                     
                                  V44      GND                     
                                  V47      GND                     
                                  V49      GND                     
                                  V51      GND                     
                                  V53      GND                     
                                  V55      GND                     
                                  V57      GND                     
                                  V59      GND                     
                                  V61      GND                     
                                  V63      GND                     
                                  V65      GND                     
                                  V67      GND                     
                                  V69      GND                     
                                  V71      GND                     
                                  V73      GND                     
                                  V75      GND                     
                                  V77      GND                     
                                  V79      GND                     
                                  V81      UPI_CPU1_CPU0_P2P2_DP<7>
                                  V83      UPI_CPU1_CPU0_P2P2_DN<8>
                                  V85      P5E_CPU1_PE4_TX_DP<12>  
                                  V87      GND                     
                                  V89      P5E_CPU1_PE4_RX_DN<12>  
                                  V91      GND                     
                                  W1       GND                     
                                  W3       UPI_CPU1_CPU0_P0P1_DP<5>
                                  W5       GND                     
                                  W7       UPI_CPU0_CPU1_P1P0_DP<4>
                                  W9       GND                     
                                  W11      P5E_CPU1_PE0_RX_DP<11>  
                                  W13      GND                     
                                  W15      P5E_CPU1_PE0_TX_DP<12>  
                                  W19      M_C_CPU1_SB_DQ<23>      
                                  W21      M_C_CPU1_SB_DQS_DN<7>   
                                  W23      M_C_CPU1_SB_DQ<18>      
                                  W25      M_B_CPU1_SB_DQ<7>       
                                  W27      M_B_CPU1_SB_DQS_DN<5>   
                                  W29      M_B_CPU1_SB_DQ<2>       
                                  W31      M_C_CPU1_SB_CB<3>       
                                  W33      M_C_CPU1_SB_DQS_DN<4>   
                                  W35      M_C_CPU1_SB_CB<6>       
                                  W37      M_C_CPU1_SB_CS_N<3>     
                                  W39      GND                     
                                  W41      M_C_CPU1_SB_CA<3>       
                                  W43      M_B_CPU1_SA_PAR         
                                  W45      M_B_CPU1_CLK_DN<1>      
                                  W48      M_C_CPU1_SB_CA<0>       
                                  W50      M_C_CPU1_SA_CA<5>       
                                  W52      GND                     
                                  W54      M_C_CPU1_SA_CS_N<2>     
                                  W56      M_B_CPU1_SA_DQ<31>      
                                  W58      M_B_CPU1_SA_DQS_DP<8>   
                                  W60      M_B_CPU1_SA_DQ<26>      
                                  W62      M_C_CPU1_SA_DQ<23>      
                                  W64      M_C_CPU1_SA_DQS_DP<7>   
                                  W66      M_C_CPU1_SA_DQ<18>      
                                  W68      M_B_CPU1_SA_DQ<15>      
                                  W70      M_B_CPU1_SA_DQS_DP<6>   
                                  W72      M_B_CPU1_SA_DQ<10>      
                                  W74      M_C_CPU1_SA_DQ<7>       
                                  W76      M_C_CPU1_SA_DQS_DN<5>   
                                  W78      M_C_CPU1_SA_DQ<2>       
                                  W80      PVCCFA_EHV_FIVRA_CPU1   
                                  W82      UPI_CPU1_CPU0_P2P2_DP<9>
                                  W84      GND                     
                                  W86      P5E_CPU1_PE4_TX_DN<11>  
                                  W88      GND                     
                                  W90      P5E_CPU1_PE4_RX_DP<11>  
                                  Y2       UPI_CPU1_CPU0_P0P1_DN<5>
                                  Y4       GND                     
                                  Y6       UPI_CPU0_CPU1_P1P0_DP<5>
                                  Y8       GND                     
                                  Y10      P5E_CPU1_PE0_RX_DP<10>  
                                  Y12      GND                     
                                  Y14      P5E_CPU1_PE0_TX_DP<11>  
                                  Y16      GND                     
                                  Y18      GND                     
                                  Y20      M_C_CPU1_SB_DQ<22>      
                                  Y22      M_C_CPU1_SB_DQ<19>      
                                  Y24      GND                     
                                  Y26      M_B_CPU1_SB_DQ<6>       
                                  Y28      M_B_CPU1_SB_DQ<3>       
                                  Y30      GND                     
                                  Y32      M_C_CPU1_SB_CB<2>       
                                  Y34      M_C_CPU1_SB_CB<7>       
                                  Y36      GND                     
                                  Y38      M_C_CPU1_SB_CS_N<2>     
                                  Y40      M_C_CPU1_SB_CA<5>       
                                  Y42      GND                     
                                  Y44      M_B_CPU1_SA_CA<6>       
                                  Y47      M_C_CPU1_SB_CA<1>       
                                  Y49      GND                     
                                  Y51      M_C_CPU1_SA_CA<3>       
                                  Y53      M_C_CPU1_SA_CS_N<3>     
                                  Y55      GND                     
                                  Y57      M_B_CPU1_SA_DQ<30>      
                                  Y59      M_B_CPU1_SA_DQ<27>      
                                  Y61      GND                     
                                  Y63      M_C_CPU1_SA_DQ<22>      
                                  Y65      M_C_CPU1_SA_DQ<19>      
                                  Y67      GND                     
                                  Y69      M_B_CPU1_SA_DQ<14>      
                                  Y71      M_B_CPU1_SA_DQ<11>      
                                  Y73      GND                     
                                  Y75      M_C_CPU1_SA_DQ<6>       
                                  Y77      M_C_CPU1_SA_DQ<3>       
                                  Y79      PVCCFA_EHV_FIVRA_CPU1   
                                  Y81      UPI_CPU1_CPU0_P2P2_DN<9>
                                  Y83      UPI_CPU1_CPU0_P2P2_DP<8>
                                  Y85      PVCCFA_EHV_FIVRA_CPU1   
                                  Y87      P5E_CPU1_PE4_TX_DP<11>  
                                  Y89      PVCCFA_EHV_FIVRA_CPU1   
                                  Y91      P5E_CPU1_PE4_RX_DN<11>  
U2               SOCKET4677_AZIFS054P001C01-SOCA A9       M_A_CPU0_SB_DQS_DN<3>   
                                  A11      GND                     
                                  A13      GND                     
                                  A15      M_B_CPU0_SB_DQS_DN<3>   
                                  A17      GND                     
                                  A19      GND                     
                                  A21      M_A_CPU0_SB_DQS_DN<2>   
                                  A23      GND                     
                                  A25      GND                     
                                  A27      M_A_CPU0_SB_DQS_DN<1>   
                                  A29      GND                     
                                  A31      GND                     
                                  A33      M_A_CPU0_SB_DQS_DN<9>   
                                  A35      GND                     
                                  A37      GND                     
                                  A39      M_A_CPU0_SB_CA<6>       
                                  A41      GND                     
                                  A43      PWRGD_DRAMPWRGD_CPU0_AB_LVC1_R
                                  A50      GND                     
                                  A52      M_A_CPU0_SA_CA<0>       
                                  A54      GND                     
                                  A56      GND                     
                                  A58      M_A_CPU0_SA_DQS_DN<4>   
                                  A60      GND                     
                                  A62      GND                     
                                  A64      M_A_CPU0_SA_DQS_DN<3>   
                                  AA1      UPI_CPU0_CPU1_P0P1_DN<6>
                                  AA3      PVCCFA_EHV_CPU0         
                                  AA5      UPI_CPU1_CPU0_P1P0_DP<5>
                                  AA7      PVCCFA_EHV_FIVRA_CPU0   
                                  AA9      P5E_CPU0_PE0_RX_DN<10>  
                                  AA11     PVCCFA_EHV_FIVRA_CPU0   
                                  AA13     P5E_CPU0_PE0_TX_DN<11>  
                                  AA15     PVCCFA_EHV_FIVRA_CPU0   
                                  AA17     M_C_CPU0_SB_DQ<28>      
                                  AA19     GND                     
                                  AA21     M_C_CPU0_SB_DQS_DP<7>   
                                  AA23     GND                     
                                  AA25     GND                     
                                  AA27     M_B_CPU0_SB_DQS_DP<5>   
                                  AA29     GND                     
                                  AA31     GND                     
                                  AA33     M_C_CPU0_SB_DQS_DP<4>   
                                  AA35     GND                     
                                  AA37     GND                     
                                  AA39     M_C_CPU0_SB_PAR         
                                  AA41     GND                     
                                  AA43     GND                     
                                  AA45     M_B_CPU0_CLK_DP<1>      
                                  AA48     GND                     
                                  AA50     GND                     
                                  AA52     M_C_CPU0_SA_CA<1>       
                                  AA54     GND                     
                                  AA56     GND                     
                                  AA58     M_B_CPU0_SA_DQS_DN<8>   
                                  AA60     GND                     
                                  AA62     GND                     
                                  AA64     M_C_CPU0_SA_DQS_DN<7>   
                                  AA66     GND                     
                                  AA68     GND                     
                                  AA70     M_B_CPU0_SA_DQS_DN<6>   
                                  AA72     GND                     
                                  AA74     GND                     
                                  AA76     M_C_CPU0_SA_DQS_DP<5>   
                                  AA78     GND                     
                                  AA80     GND                     
                                  AA82     GND                     
                                  AA84     GND                     
                                  AA86     P5E_CPU0_PE4_TX_DN<10>  
                                  AA88     GND                     
                                  AA90     P5E_CPU0_PE4_RX_DP<10>  
                                  AB2      UPI_CPU0_CPU1_P0P1_DP<6>
                                  AB4      GND                     
                                  AB6      UPI_CPU1_CPU0_P1P0_DN<6>
                                  AB8      GND                     
                                  AB10     P5E_CPU0_PE0_RX_DN<9>   
                                  AB12     GND                     
                                  AB14     P5E_CPU0_PE0_TX_DN<10>  
                                  AB16     GND                     
                                  AB18     M_C_CPU0_SB_DQS_DN<3>   
                                  AB20     GND                     
                                  AB22     GND                     
                                  AB24     M_D_CPU0_SB_DQS_DN<2>   
                                  AB26     GND                     
                                  AB28     GND                     
                                  AB30     M_C_CPU0_SB_DQS_DN<1>   
                                  AB32     GND                     
                                  AB34     GND                     
                                  AB36     M_C_CPU0_SB_DQS_DN<0>   
                                  AB38     GND                     
                                  AB40     GND                     
                                  AB42     M_D_CPU0_SB_CA<6>       
                                  AB44     GND                     
                                  AB47     GND                     
                                  AB49     M_C_CPU0_CLK_DN<0>      
                                  AB51     GND                     
                                  AB53     GND                     
                                  AB55     M_C_CPU0_SA_DQS_DP<4>   
                                  AB57     GND                     
                                  AB59     GND                     
                                  AB61     M_C_CPU0_SA_DQS_DN<3>   
                                  AB63     GND                     
                                  AB65     GND                     
                                  AB67     M_C_CPU0_SA_DQS_DN<1>   
                                  AB69     GND                     
                                  AB71     GND                     
                                  AB73     M_D_CPU0_SA_DQS_DN<0>   
                                  AB75     GND                     
                                  AB77     GND                     
                                  AB79     GND                     
                                  AB81     GND                     
                                  AB83     GND                     
                                  AB85     P5E_CPU0_PE4_TX_DP<10>  
                                  AB87     GND                     
                                  AB89     P5E_CPU0_PE4_RX_DN<10>  
                                  AB91     GND                     
                                  AC1      GND                     
                                  AC3      UPI_CPU0_CPU1_P0P1_DP<7>
                                  AC5      GND                     
                                  AC7      UPI_CPU1_CPU0_P1P0_DP<6>
                                  AC9      GND                     
                                  AC11     P5E_CPU0_PE0_RX_DP<9>   
                                  AC13     GND                     
                                  AC15     P5E_CPU0_PE0_TX_DP<10>  
                                  AC17     M_C_CPU0_SB_DQ<30>      
                                  AC19     M_C_CPU0_SB_DQ<25>      
                                  AC21     GND                     
                                  AC23     M_D_CPU0_SB_DQ<20>      
                                  AC25     M_D_CPU0_SB_DQ<17>      
                                  AC27     GND                     
                                  AC29     M_C_CPU0_SB_DQ<12>      
                                  AC31     M_C_CPU0_SB_DQ<9>       
                                  AC33     GND                     
                                  AC35     M_C_CPU0_SB_DQ<4>       
                                  AC37     M_C_CPU0_SB_DQ<1>       
                                  AC39     GND                     
                                  AC41     M_D_CPU0_SB_CS_N<0>     
                                  AC43     M_D_CPU0_SB_CA<4>       
                                  AC45     GND                     
                                  AC48     M_C_CPU0_SA_RSP<0>      
                                  AC50     M_D_CPU0_SA_RSP<1>      
                                  AC52     GND                     
                                  AC54     M_C_CPU0_SA_CB<4>       
                                  AC56     M_C_CPU0_SA_CB<1>       
                                  AC58     GND                     
                                  AC60     M_C_CPU0_SA_DQ<28>      
                                  AC62     M_C_CPU0_SA_DQ<25>      
                                  AC64     GND                     
                                  AC66     M_C_CPU0_SA_DQ<12>      
                                  AC68     M_C_CPU0_SA_DQ<9>       
                                  AC70     GND                     
                                  AC72     M_D_CPU0_SA_DQ<4>       
                                  AC74     M_D_CPU0_SA_DQ<1>       
                                  AC76     GND                     
                                  AC80     UPI_CPU1_CPU0_P2P2_DN<17>
                                  AC82     UPI_CPU1_CPU0_P2P2_DN<16>
                                  AC84     GND                     
                                  AC86     P5E_CPU0_PE4_TX_DN<9>   
                                  AC88     GND                     
                                  AC90     P5E_CPU0_PE4_RX_DP<9>   
                                  AD2      UPI_CPU0_CPU1_P0P1_DN<7>
                                  AD4      GND                     
                                  AD6      UPI_CPU1_CPU0_P1P0_DP<7>
                                  AD8      GND                     
                                  AD10     P5E_CPU0_PE0_RX_DP<8>   
                                  AD12     GND                     
                                  AD14     P5E_CPU0_PE0_TX_DP<9>   
                                  AD16     GND                     
                                  AD18     M_C_CPU0_SB_DQS_DP<3>   
                                  AD20     M_C_CPU0_SB_DQ<24>      
                                  AD22     M_D_CPU0_SB_DQ<21>      
                                  AD24     M_D_CPU0_SB_DQS_DP<2>   
                                  AD26     M_D_CPU0_SB_DQ<16>      
                                  AD28     M_C_CPU0_SB_DQ<13>      
                                  AD30     M_C_CPU0_SB_DQS_DP<1>   
                                  AD32     M_C_CPU0_SB_DQ<8>       
                                  AD34     M_C_CPU0_SB_DQ<5>       
                                  AD36     M_C_CPU0_SB_DQS_DP<0>   
                                  AD38     M_C_CPU0_SB_DQ<0>       
                                  AD40     M_D_CPU0_SB_CS_N<3>     
                                  AD42     GND                     
                                  AD44     M_D_CPU0_SB_CA<2>       
                                  AD47     M_C_CPU0_SA_RSP<1>      
                                  AD49     M_C_CPU0_CLK_DP<0>      
                                  AD51     M_D_CPU0_SA_RSP<0>      
                                  AD53     M_C_CPU0_SA_CB<5>       
                                  AD55     M_C_CPU0_SA_DQS_DN<4>   
                                  AD57     M_C_CPU0_SA_CB<0>       
                                  AD59     M_C_CPU0_SA_DQ<29>      
                                  AD61     M_C_CPU0_SA_DQS_DP<3>   
                                  AD63     M_C_CPU0_SA_DQ<24>      
                                  AD65     M_C_CPU0_SA_DQ<13>      
                                  AD67     M_C_CPU0_SA_DQS_DP<1>   
                                  AD69     M_C_CPU0_SA_DQ<8>       
                                  AD71     M_D_CPU0_SA_DQ<5>       
                                  AD73     M_D_CPU0_SA_DQS_DP<0>   
                                  AD75     M_D_CPU0_SA_DQ<0>       
                                  AD79     GND                     
                                  AD81     UPI_CPU1_CPU0_P2P2_DP<16>
                                  AD83     GND                     
                                  AD85     PVCCFA_EHV_FIVRA_CPU0   
                                  AD87     P5E_CPU0_PE4_TX_DP<9>   
                                  AD89     PVCCFA_EHV_FIVRA_CPU0   
                                  AD91     P5E_CPU0_PE4_RX_DN<9>   
                                  AE1      UPI_CPU0_CPU1_P0P1_DP<8>
                                  AE3      PVCCFA_EHV_CPU0         
                                  AE5      UPI_CPU1_CPU0_P1P0_DN<7>
                                  AE7      PVCCFA_EHV_FIVRA_CPU0   
                                  AE9      P5E_CPU0_PE0_RX_DN<8>   
                                  AE11     PVCCFA_EHV_FIVRA_CPU0   
                                  AE13     P5E_CPU0_PE0_TX_DN<9>   
                                  AE15     PVCCFA_EHV_FIVRA_CPU0   
                                  AE17     GND                     
                                  AE19     GND                     
                                  AE21     GND                     
                                  AE23     GND                     
                                  AE25     GND                     
                                  AE27     GND                     
                                  AE29     GND                     
                                  AE31     GND                     
                                  AE33     GND                     
                                  AE35     GND                     
                                  AE37     GND                     
                                  AE39     GND                     
                                  AE41     GND                     
                                  AE43     GND                     
                                  AE45     GND                     
                                  AE48     GND                     
                                  AE50     GND                     
                                  AE52     GND                     
                                  AE54     GND                     
                                  AE56     GND                     
                                  AE58     GND                     
                                  AE60     GND                     
                                  AE62     GND                     
                                  AE64     GND                     
                                  AE66     GND                     
                                  AE68     GND                     
                                  AE70     GND                     
                                  AE72     GND                     
                                  AE74     GND                     
                                  AE76     GND                     
                                  AE78     GND                     
                                  AE80     UPI_CPU1_CPU0_P2P2_DP<17>
                                  AE82     UPI_CPU1_CPU0_P2P2_DP<14>
                                  AE84     GND                     
                                  AE86     P5E_CPU0_PE4_TX_DN<8>   
                                  AE88     GND                     
                                  AE90     P5E_CPU0_PE4_RX_DP<8>   
                                  AF2      UPI_CPU0_CPU1_P0P1_DN<8>
                                  AF4      GND                     
                                  AF6      UPI_CPU1_CPU0_P1P0_DN<8>
                                  AF8      GND                     
                                  AF10     P5E_CPU0_PE0_RX_DN<7>   
                                  AF12     GND                     
                                  AF14     P5E_CPU0_PE0_TX_DN<8>   
                                  AF16     GND                     
                                  AF18     M_C_CPU0_SB_DQS_DN<8>   
                                  AF20     M_C_CPU0_SB_DQ<26>      
                                  AF22     M_D_CPU0_SB_DQ<23>      
                                  AF24     M_D_CPU0_SB_DQS_DN<7>   
                                  AF26     M_D_CPU0_SB_DQ<18>      
                                  AF28     M_C_CPU0_SB_DQ<15>      
                                  AF30     M_C_CPU0_SB_DQS_DN<6>   
                                  AF32     M_C_CPU0_SB_DQ<10>      
                                  AF34     M_C_CPU0_SB_DQ<7>       
                                  AF36     M_C_CPU0_SB_DQS_DN<5>   
                                  AF38     M_C_CPU0_SB_DQ<2>       
                                  AF40     M_D_CPU0_SB_CS_N<2>     
                                  AF42     GND                     
                                  AF44     M_D_CPU0_SB_CA<3>       
                                  AF47     M_C_CPU0_SB_RSP<1>      
                                  AF49     M_C_CPU0_CLK_DN<1>      
                                  AF51     M_D_CPU0_SB_RSP<0>      
                                  AF53     M_C_CPU0_SA_CB<7>       
                                  AF55     M_C_CPU0_SA_DQS_DP<9>   
                                  AF57     M_C_CPU0_SA_CB<2>       
                                  AF59     M_C_CPU0_SA_DQ<31>      
                                  AF61     M_C_CPU0_SA_DQS_DN<8>   
                                  AF63     M_C_CPU0_SA_DQ<26>      
                                  AF65     M_C_CPU0_SA_DQ<15>      
                                  AF67     M_C_CPU0_SA_DQS_DP<6>   
                                  AF69     M_C_CPU0_SA_DQ<10>      
                                  AF71     M_D_CPU0_SA_DQ<7>       
                                  AF73     M_D_CPU0_SA_DQS_DP<5>   
                                  AF75     M_D_CPU0_SA_DQ<2>       
                                  AF77     PVCCFA_EHV_FIVRA_CPU0   
                                  AF79     UPI_CPU1_CPU0_P2P2_DP<15>
                                  AF81     GND                     
                                  AF83     UPI_CPU1_CPU0_P2P2_DN<14>
                                  AF85     P5E_CPU0_PE4_TX_DP<8>   
                                  AF87     GND                     
                                  AF89     P5E_CPU0_PE4_RX_DN<8>   
                                  AF91     GND                     
                                  AG1      GND                     
                                  AG3      UPI_CPU0_CPU1_P0P1_DP<9>
                                  AG5      GND                     
                                  AG7      UPI_CPU1_CPU0_P1P0_DP<8>
                                  AG9      GND                     
                                  AG11     P5E_CPU0_PE0_RX_DP<7>   
                                  AG13     GND                     
                                  AG15     P5E_CPU0_PE0_TX_DP<8>   
                                  AG17     M_C_CPU0_SB_DQ<29>      
                                  AG19     M_C_CPU0_SB_DQ<27>      
                                  AG21     GND                     
                                  AG23     M_D_CPU0_SB_DQ<22>      
                                  AG25     M_D_CPU0_SB_DQ<19>      
                                  AG27     GND                     
                                  AG29     M_C_CPU0_SB_DQ<14>      
                                  AG31     M_C_CPU0_SB_DQ<11>      
                                  AG33     GND                     
                                  AG35     M_C_CPU0_SB_DQ<6>       
                                  AG37     M_C_CPU0_SB_DQ<3>       
                                  AG39     GND                     
                                  AG41     M_D_CPU0_SB_CS_N<1>     
                                  AG43     M_D_CPU0_SB_CA<5>       
                                  AG45     GND                     
                                  AG48     M_C_CPU0_SB_RSP<0>      
                                  AG50     M_D_CPU0_SB_RSP<1>      
                                  AG52     GND                     
                                  AG54     M_C_CPU0_SA_CB<6>       
                                  AG56     M_C_CPU0_SA_CB<3>       
                                  AG58     GND                     
                                  AG60     M_C_CPU0_SA_DQ<30>      
                                  AG62     M_C_CPU0_SA_DQ<27>      
                                  AG64     GND                     
                                  AG66     M_C_CPU0_SA_DQ<14>      
                                  AG68     M_C_CPU0_SA_DQ<11>      
                                  AG70     GND                     
                                  AG72     M_D_CPU0_SA_DQ<6>       
                                  AG74     M_D_CPU0_SA_DQ<3>       
                                  AG76     GND                     
                                  AG78     PVCCFA_EHV_FIVRA_CPU0   
                                  AG80     UPI_CPU1_CPU0_P2P2_DN<15>
                                  AG82     UPI_CPU1_CPU0_P2P2_DP<12>
                                  AG84     GND                     
                                  AG86     P5E_CPU0_PE4_TX_DN<7>   
                                  AG88     GND                     
                                  AG90     P5E_CPU0_PE4_RX_DP<7>   
                                  AH2      UPI_CPU0_CPU1_P0P1_DN<9>
                                  AH4      GND                     
                                  AH6      UPI_CPU1_CPU0_P1P0_DN<9>
                                  AH8      GND                     
                                  AH10     P5E_CPU0_PE0_RX_DP<6>   
                                  AH12     GND                     
                                  AH14     P5E_CPU0_PE0_TX_DP<7>   
                                  AH16     GND                     
                                  AH18     M_C_CPU0_SB_DQS_DP<8>   
                                  AH20     GND                     
                                  AH22     GND                     
                                  AH24     M_D_CPU0_SB_DQS_DP<7>   
                                  AH26     GND                     
                                  AH28     GND                     
                                  AH30     M_C_CPU0_SB_DQS_DP<6>   
                                  AH32     GND                     
                                  AH34     GND                     
                                  AH36     M_C_CPU0_SB_DQS_DP<5>   
                                  AH38     GND                     
                                  AH40     GND                     
                                  AH42     M_D_CPU0_SB_PAR         
                                  AH44     GND                     
                                  AH47     GND                     
                                  AH49     M_C_CPU0_CLK_DP<1>      
                                  AH51     GND                     
                                  AH53     GND                     
                                  AH55     M_C_CPU0_SA_DQS_DN<9>   
                                  AH57     GND                     
                                  AH59     GND                     
                                  AH61     M_C_CPU0_SA_DQS_DP<8>   
                                  AH63     GND                     
                                  AH65     GND                     
                                  AH67     M_C_CPU0_SA_DQS_DN<6>   
                                  AH69     GND                     
                                  AH71     GND                     
                                  AH73     M_D_CPU0_SA_DQS_DN<5>   
                                  AH75     GND                     
                                  AH77     GND                     
                                  AH79     GND                     
                                  AH81     UPI_CPU1_CPU0_P2P2_DP<13>
                                  AH83     GND                     
                                  AH85     PVCCFA_EHV_FIVRA_CPU0   
                                  AH87     P5E_CPU0_PE4_TX_DP<7>   
                                  AH89     PVCCFA_EHV_FIVRA_CPU0   
                                  AH91     P5E_CPU0_PE4_RX_DN<7>   
                                  AJ1      UPI_CPU0_CPU1_P0P1_DP<10>
                                  AJ3      PVCCFA_EHV_CPU0         
                                  AJ5      UPI_CPU1_CPU0_P1P0_DP<9>
                                  AJ7      PVCCFA_EHV_FIVRA_CPU0   
                                  AJ9      P5E_CPU0_PE0_RX_DN<6>   
                                  AJ11     PVCCFA_EHV_FIVRA_CPU0   
                                  AJ13     P5E_CPU0_PE0_TX_DN<7>   
                                  AJ15     PVCCFA_EHV_FIVRA_CPU0   
                                  AJ17     M_C_CPU0_SB_DQ<31>      
                                  AJ19     GND                     
                                  AJ21     M_D_CPU0_SB_DQS_DN<3>   
                                  AJ23     GND                     
                                  AJ25     GND                     
                                  AJ27     M_D_CPU0_SB_DQS_DN<1>   
                                  AJ29     GND                     
                                  AJ31     GND                     
                                  AJ33     M_D_CPU0_SB_DQS_DN<0>   
                                  AJ35     GND                     
                                  AJ37     GND                     
                                  AJ39     M_D_CPU0_SB_DQS_DN<9>   
                                  AJ41     GND                     
                                  AJ43     GND                     
                                  AJ45     M_D_CPU0_CLK_DN<0>      
                                  AJ48     GND                     
                                  AJ50     GND                     
                                  AJ52     M_D_CPU0_SA_CA<0>       
                                  AJ54     GND                     
                                  AJ56     GND                     
                                  AJ58     M_D_CPU0_SA_DQS_DN<4>   
                                  AJ60     GND                     
                                  AJ62     GND                     
                                  AJ64     M_D_CPU0_SA_DQS_DN<3>   
                                  AJ66     GND                     
                                  AJ68     GND                     
                                  AJ70     M_D_CPU0_SA_DQS_DN<2>   
                                  AJ72     GND                     
                                  AJ74     GND                     
                                  AJ76     M_D_CPU0_SA_DQS_DN<1>   
                                  AJ78     GND                     
                                  AJ80     UPI_CPU1_CPU0_P2P2_DN<13>
                                  AJ82     UPI_CPU1_CPU0_P2P2_DN<12>
                                  AJ84     GND                     
                                  AJ86     P5E_CPU0_PE4_TX_DN<6>   
                                  AJ88     GND                     
                                  AJ90     P5E_CPU0_PE4_RX_DP<6>   
                                  AK2      UPI_CPU0_CPU1_P0P1_DN<10>
                                  AK4      GND                     
                                  AK6      UPI_CPU1_CPU0_P1P0_DP<10>
                                  AK8      GND                     
                                  AK10     P5E_CPU0_PE0_RX_DN<5>   
                                  AK12     GND                     
                                  AK14     P5E_CPU0_PE0_TX_DN<6>   
                                  AK16     GND                     
                                  AK18     GND                     
                                  AK20     M_D_CPU0_SB_DQ<28>      
                                  AK22     M_D_CPU0_SB_DQ<25>      
                                  AK24     GND                     
                                  AK26     M_D_CPU0_SB_DQ<12>      
                                  AK28     M_D_CPU0_SB_DQ<9>       
                                  AK30     GND                     
                                  AK32     M_D_CPU0_SB_DQ<4>       
                                  AK34     M_D_CPU0_SB_DQ<1>       
                                  AK36     GND                     
                                  AK38     M_D_CPU0_SB_CB<0>       
                                  AK40     M_D_CPU0_SB_CB<5>       
                                  AK42     GND                     
                                  AK44     M_D_CPU0_SB_CA<0>       
                                  AK47     M_B_CPU0_SA_RSP<1>      
                                  AK49     GND                     
                                  AK51     M_D_CPU0_SA_CA<2>       
                                  AK53     M_D_CPU0_SA_CS_N<1>     
                                  AK55     GND                     
                                  AK57     M_D_CPU0_SA_CB<4>       
                                  AK59     M_D_CPU0_SA_CB<1>       
                                  AK61     GND                     
                                  AK63     M_D_CPU0_SA_DQ<28>      
                                  AK65     M_D_CPU0_SA_DQ<25>      
                                  AK67     GND                     
                                  AK69     M_D_CPU0_SA_DQ<20>      
                                  AK71     M_D_CPU0_SA_DQ<17>      
                                  AK73     GND                     
                                  AK75     M_D_CPU0_SA_DQ<12>      
                                  AK77     M_D_CPU0_SA_DQ<9>       
                                  AK79     GND                     
                                  AK81     GND                     
                                  AK83     GND                     
                                  AK85     P5E_CPU0_PE4_TX_DP<6>   
                                  AK87     GND                     
                                  AK89     P5E_CPU0_PE4_RX_DN<6>   
                                  AK91     GND                     
                                  AL1      GND                     
                                  AL3      UPI_CPU0_CPU1_P0P1_DP<11>
                                  AL5      GND                     
                                  AL7      UPI_CPU1_CPU0_P1P0_DN<10>
                                  AL9      GND                     
                                  AL11     P5E_CPU0_PE0_RX_DP<5>   
                                  AL13     GND                     
                                  AL15     P5E_CPU0_PE0_TX_DP<6>   
                                  AL17     GND                     
                                  AL19     M_D_CPU0_SB_DQ<29>      
                                  AL21     M_D_CPU0_SB_DQS_DP<3>   
                                  AL23     M_D_CPU0_SB_DQ<24>      
                                  AL25     M_D_CPU0_SB_DQ<13>      
                                  AL27     M_D_CPU0_SB_DQS_DP<1>   
                                  AL29     M_D_CPU0_SB_DQ<8>       
                                  AL31     M_D_CPU0_SB_DQ<5>       
                                  AL33     M_D_CPU0_SB_DQS_DP<0>   
                                  AL35     M_D_CPU0_SB_DQ<0>       
                                  AL37     M_D_CPU0_SB_CB<1>       
                                  AL39     M_D_CPU0_SB_DQS_DP<9>   
                                  AL41     M_D_CPU0_SB_CB<4>       
                                  AL43     M_D_CPU0_SB_CA<1>       
                                  AL45     M_D_CPU0_CLK_DP<0>      
                                  AL48     M_B_CPU0_SA_RSP<0>      
                                  AL50     M_D_CPU0_SA_CA<4>       
                                  AL52     GND                     
                                  AL54     M_D_CPU0_SA_CS_N<0>     
                                  AL56     M_D_CPU0_SA_CB<5>       
                                  AL58     M_D_CPU0_SA_DQS_DP<4>   
                                  AL60     M_D_CPU0_SA_CB<0>       
                                  AL62     M_D_CPU0_SA_DQ<29>      
                                  AL64     M_D_CPU0_SA_DQS_DP<3>   
                                  AL66     M_D_CPU0_SA_DQ<24>      
                                  AL68     M_D_CPU0_SA_DQ<21>      
                                  AL70     M_D_CPU0_SA_DQS_DP<2>   
                                  AL72     M_D_CPU0_SA_DQ<16>      
                                  AL74     M_D_CPU0_SA_DQ<13>      
                                  AL76     M_D_CPU0_SA_DQS_DP<1>   
                                  AL78     M_D_CPU0_SA_DQ<8>       
                                  AL80     GND                     
                                  AL82     GND                     
                                  AL84     GND                     
                                  AL86     P5E_CPU0_PE4_TX_DN<5>   
                                  AL88     GND                     
                                  AL90     P5E_CPU0_PE4_RX_DP<5>   
                                  AM2      UPI_CPU0_CPU1_P0P1_DN<11>
                                  AM4      GND                     
                                  AM6      UPI_CPU1_CPU0_P1P0_DN<11>
                                  AM8      GND                     
                                  AM10     P5E_CPU0_PE0_RX_DN<4>   
                                  AM12     GND                     
                                  AM14     P5E_CPU0_PE0_TX_DP<5>   
                                  AM16     GND                     
                                  AM18     GND                     
                                  AM20     GND                     
                                  AM22     GND                     
                                  AM24     GND                     
                                  AM26     GND                     
                                  AM28     GND                     
                                  AM30     GND                     
                                  AM32     GND                     
                                  AM34     GND                     
                                  AM36     GND                     
                                  AM38     GND                     
                                  AM40     GND                     
                                  AM42     GND                     
                                  AM44     GND                     
                                  AM47     GND                     
                                  AM49     GND                     
                                  AM51     GND                     
                                  AM53     GND                     
                                  AM55     GND                     
                                  AM57     GND                     
                                  AM59     GND                     
                                  AM61     GND                     
                                  AM63     GND                     
                                  AM65     GND                     
                                  AM67     GND                     
                                  AM69     GND                     
                                  AM71     GND                     
                                  AM73     GND                     
                                  AM75     GND                     
                                  AM77     GND                     
                                  AM79     PVCCFA_EHV_FIVRA_CPU0   
                                  AM81     UPI_CPU0_CPU1_P2P2_DN<11>
                                  AM83     UPI_CPU0_CPU1_P2P2_DP<10>
                                  AM85     PVCCFA_EHV_FIVRA_CPU0   
                                  AM87     P5E_CPU0_PE4_TX_DP<5>   
                                  AM89     PVCCFA_EHV_FIVRA_CPU0   
                                  AM91     P5E_CPU0_PE4_RX_DN<5>   
                                  AN1      UPI_CPU0_CPU1_P0P1_DN<12>
                                  AN3      PVCCFA_EHV_CPU0         
                                  AN5      UPI_CPU1_CPU0_P1P0_DP<11>
                                  AN7      PVCCFA_EHV_FIVRA_CPU0   
                                  AN9      P5E_CPU0_PE0_RX_DP<4>   
                                  AN11     PVCCFA_EHV_FIVRA_CPU0   
                                  AN13     P5E_CPU0_PE0_TX_DN<5>   
                                  AN15     PVCCFA_EHV_FIVRA_CPU0   
                                  AN19     M_D_CPU0_SB_DQ<31>      
                                  AN21     M_D_CPU0_SB_DQS_DN<8>   
                                  AN23     M_D_CPU0_SB_DQ<26>      
                                  AN25     M_D_CPU0_SB_DQ<15>      
                                  AN27     M_D_CPU0_SB_DQS_DN<6>   
                                  AN29     M_D_CPU0_SB_DQ<10>      
                                  AN31     M_D_CPU0_SB_DQ<7>       
                                  AN33     M_D_CPU0_SB_DQS_DN<5>   
                                  AN35     M_D_CPU0_SB_DQ<2>       
                                  AN37     M_D_CPU0_SB_CB<3>       
                                  AN39     M_D_CPU0_SB_DQS_DP<4>   
                                  AN41     M_D_CPU0_SB_CB<6>       
                                  AN43     M_D_CPU0_SA_CA<6>       
                                  AN45     M_D_CPU0_CLK_DN<1>      
                                  AN48     M_B_CPU0_SB_RSP<0>      
                                  AN50     M_D_CPU0_SA_CA<5>       
                                  AN52     GND                     
                                  AN54     M_D_CPU0_SA_CS_N<2>     
                                  AN56     M_D_CPU0_SA_CB<7>       
                                  AN58     M_D_CPU0_SA_DQS_DN<9>   
                                  AN60     M_D_CPU0_SA_CB<2>       
                                  AN62     M_D_CPU0_SA_DQ<31>      
                                  AN64     M_D_CPU0_SA_DQS_DN<8>   
                                  AN66     M_D_CPU0_SA_DQ<26>      
                                  AN68     M_D_CPU0_SA_DQ<23>      
                                  AN70     M_D_CPU0_SA_DQS_DN<7>   
                                  AN72     M_D_CPU0_SA_DQ<18>      
                                  AN74     M_D_CPU0_SA_DQ<15>      
                                  AN76     M_D_CPU0_SA_DQS_DN<6>   
                                  AN78     M_D_CPU0_SA_DQ<10>      
                                  AN80     PVCCFA_EHV_FIVRA_CPU0   
                                  AN82     UPI_CPU0_CPU1_P2P2_DN<10>
                                  AN84     GND                     
                                  AN86     P5E_CPU0_PE4_TX_DP<4>   
                                  AN88     GND                     
                                  AN90     P5E_CPU0_PE4_RX_DP<4>   
                                  AP2      UPI_CPU0_CPU1_P0P1_DP<12>
                                  AP4      GND                     
                                  AP6      UPI_CPU1_CPU0_P1P0_DP<12>
                                  AP8      GND                     
                                  AP10     P5E_CPU0_PE0_RX_DN<3>   
                                  AP12     GND                     
                                  AP14     P5E_CPU0_PE0_TX_DN<4>   
                                  AP16     GND                     
                                  AP18     GND                     
                                  AP20     M_D_CPU0_SB_DQ<30>      
                                  AP22     M_D_CPU0_SB_DQ<27>      
                                  AP24     GND                     
                                  AP26     M_D_CPU0_SB_DQ<14>      
                                  AP28     M_D_CPU0_SB_DQ<11>      
                                  AP30     GND                     
                                  AP32     M_D_CPU0_SB_DQ<6>       
                                  AP34     M_D_CPU0_SB_DQ<3>       
                                  AP36     GND                     
                                  AP38     M_D_CPU0_SB_CB<2>       
                                  AP40     M_D_CPU0_SB_CB<7>       
                                  AP42     GND                     
                                  AP44     M_D_CPU0_SA_PAR         
                                  AP47     M_B_CPU0_SB_RSP<1>      
                                  AP49     GND                     
                                  AP51     M_D_CPU0_SA_CA<3>       
                                  AP53     M_D_CPU0_SA_CS_N<3>     
                                  AP55     GND                     
                                  AP57     M_D_CPU0_SA_CB<6>       
                                  AP59     M_D_CPU0_SA_CB<3>       
                                  AP61     GND                     
                                  AP63     M_D_CPU0_SA_DQ<30>      
                                  AP65     M_D_CPU0_SA_DQ<27>      
                                  AP67     GND                     
                                  AP69     M_D_CPU0_SA_DQ<22>      
                                  AP71     M_D_CPU0_SA_DQ<19>      
                                  AP73     GND                     
                                  AP75     M_D_CPU0_SA_DQ<14>      
                                  AP77     M_D_CPU0_SA_DQ<11>      
                                  AP79     GND                     
                                  AP81     UPI_CPU0_CPU1_P2P2_DP<11>
                                  AP83     GND                     
                                  AP85     P5E_CPU0_PE4_TX_DN<4>   
                                  AP87     GND                     
                                  AP89     P5E_CPU0_PE4_RX_DN<4>   
                                  AP91     GND                     
                                  AR1      GND                     
                                  AR3      UPI_CPU0_CPU1_P0P1_DN<13>
                                  AR5      GND                     
                                  AR7      UPI_CPU1_CPU0_P1P0_DN<12>
                                  AR9      GND                     
                                  AR11     P5E_CPU0_PE0_RX_DP<3>   
                                  AR13     GND                     
                                  AR15     P5E_CPU0_PE0_TX_DP<4>   
                                  AR19     GND                     
                                  AR21     M_D_CPU0_SB_DQS_DP<8>   
                                  AR23     GND                     
                                  AR25     GND                     
                                  AR27     M_D_CPU0_SB_DQS_DP<6>   
                                  AR29     GND                     
                                  AR31     GND                     
                                  AR33     M_D_CPU0_SB_DQS_DP<5>   
                                  AR35     GND                     
                                  AR37     GND                     
                                  AR39     M_D_CPU0_SB_DQS_DN<4>   
                                  AR41     GND                     
                                  AR43     GND                     
                                  AR45     M_D_CPU0_CLK_DP<1>      
                                  AR48     GND                     
                                  AR50     GND                     
                                  AR52     M_D_CPU0_SA_CA<1>       
                                  AR54     GND                     
                                  AR56     GND                     
                                  AR58     M_D_CPU0_SA_DQS_DP<9>   
                                  AR60     GND                     
                                  AR62     GND                     
                                  AR64     M_D_CPU0_SA_DQS_DP<8>   
                                  AR66     GND                     
                                  AR68     GND                     
                                  AR70     M_D_CPU0_SA_DQS_DP<7>   
                                  AR72     GND                     
                                  AR74     GND                     
                                  AR76     M_D_CPU0_SA_DQS_DP<6>   
                                  AR78     GND                     
                                  AR80     UPI_CPU0_CPU1_P2P2_DN<9>
                                  AR82     GND                     
                                  AR84     GND                     
                                  AR86     P5E_CPU0_PE4_TX_DN<3>   
                                  AR88     GND                     
                                  AR90     P5E_CPU0_PE4_RX_DP<3>   
                                  AT2      UPI_CPU0_CPU1_P0P1_DP<13>
                                  AT4      GND                     
                                  AT6      UPI_CPU1_CPU0_P1P0_DN<13>
                                  AT8      GND                     
                                  AT10     P5E_CPU0_PE0_RX_DP<2>   
                                  AT12     GND                     
                                  AT14     P5E_CPU0_PE0_TX_DP<3>   
                                  AT16     GND                     
                                  AT18     PD_CPU0_BIST_ENABLE     
                                  AT20     GND                     
                                  AT22     GND                     
                                  AT26     GND                     
                                  AT28     GND                     
                                  AT30     CLK_100M_DB2000_CPU0_BCLK0_DN
                                  AT32     GND                     
                                  AT34     GND                     
                                  AT36     PVCCD_HV_CPU0           
                                  AT38     GND                     
                                  AT40     GND                     
                                  AT42     M_A_CPU0_SA_RSP<0>      
                                  AT44     GND                     
                                  AT47     M_C_CPU0_ALERT_N        
                                  AT49     M_A_CPU0_ALERT_N        
                                  AT51     GND                     
                                  AT53     GND                     
                                  AT55     PVCCD_HV_CPU0           
                                  AT57     GND                     
                                  AT59     GND                     
                                  AT61     PVCCFA_EHV_CPU0         
                                  AT63     GND                     
                                  AT65     GND                     
                                  AT69     GND                     
                                  AT71     GND                     
                                  AT73     PVCCFA_EHV_FIVRA_CPU0   
                                  AT75     GND                     
                                  AT77     GND                     
                                  AT79     GND                     
                                  AT81     UPI_CPU0_CPU1_P2P2_DP<9>
                                  AT83     UPI_CPU0_CPU1_P2P2_DN<8>
                                  AT85     VSENSE_PVCCFA_EHV_FIVRA_CPU0_DN
                                  AT87     P5E_CPU0_PE4_TX_DP<3>   
                                  AT89     PVCCFA_EHV_FIVRA_CPU0   
                                  AT91     P5E_CPU0_PE4_RX_DN<3>   
                                  AU1      UPI_CPU0_CPU1_P0P1_DN<14>
                                  AU3      PVCCD_HV_CPU0           
                                  AU5      UPI_CPU1_CPU0_P1P0_DP<13>
                                  AU7      PVCCD_HV_CPU0           
                                  AU9      P5E_CPU0_PE0_RX_DN<2>   
                                  AU11     VSENSE_PVCCFA_EHV_CPU0_DP
                                  AU13     P5E_CPU0_PE0_TX_DN<3>   
                                  AU15     PVCCFA_EHV_FIVRA_CPU0   
                                  AU17     PU_CPU0_FRMAGENT        
                                  AU19     H_CPU0_PROCHOT_LVC1_N   
                                  AU21     H_CPU0_MEMHOT_IN_LVC1_N 
                                  AU23     PU_CPU0_SAFE_MODE_BOOT  
                                  AU27     GND                     
                                  AU29     CLK_100M_DB2000_CPU0_BCLK2_DN
                                  AU31     GND                     
                                  AU35     PVCCD_HV_CPU0           
                                  AU37     GND                     
                                  AU39     GND                     
                                  AU41     GND                     
                                  AU43     M_A_CPU0_SA_RSP<1>      
                                  AU45     GND                     
                                  AU48     GND                     
                                  AU50     RST_CPU0_DRAM_AB_N      
                                  AU54     PVCCD_HV_CPU0           
                                  AU60     PVCCFA_EHV_CPU0         
                                  AU70     GND                     
                                  AU72     GND                     
                                  AU74     GND                     
                                  AU76     GND                     
                                  AU78     UPI_CPU0_CPU1_P2P2_DN<12>
                                  AU80     GND                     
                                  AU82     UPI_CPU0_CPU1_P2P2_DP<7>
                                  AU84     GND                     
                                  AU86     P5E_CPU0_PE4_TX_DN<2>   
                                  AU88     GND                     
                                  AU90     P5E_CPU0_PE4_RX_DP<2>   
                                  AV2      UPI_CPU0_CPU1_P0P1_DP<14>
                                  AV4      GND                     
                                  AV6      UPI_CPU1_CPU0_P1P0_DP<14>
                                  AV8      GND                     
                                  AV10     P5E_CPU0_PE0_RX_DN<1>   
                                  AV12     GND                     
                                  AV14     P5E_CPU0_PE0_TX_DN<2>   
                                  AV16     GND                     
                                  AV18     H_CPU0_NMI_LVC1_N       
                                  AV20     PWRGD_CPU0_LVC1         
                                  AV22     H_CPU0_PREQ_QS_GTL_R_N  
                                  AV24     H_CPU0_MEMTRIP_LVC1_R_N 
                                  AV28     CLK_100M_DB2000_CPU0_BCLK2_DP
                                  AV30     CLK_100M_DB2000_CPU0_BCLK0_DP
                                  AV34     PVCCD_HV_CPU0           
                                  AV36     PVCCD_HV_CPU0           
                                  AV42     M_A_CPU0_SB_RSP<1>      
                                  AV44     M_A_CPU0_SB_RSP<0>      
                                  AV47     M_D_CPU0_ALERT_N        
                                  AV49     M_B_CPU0_ALERT_N        
                                  AV51     RST_CPU0_DRAM_CD_N      
                                  AV53     PVCCD_HV_CPU0           
                                  AV55     PVCCD_HV_CPU0           
                                  AV57     FM_CPU_FBRK_DEBUG_R_N   
                                  AV61     PVCCFA_EHV_CPU0         
                                  AV69     FM_S3M_CPU0_LVC1_GPIO_2 
                                  AV71     FM_S3M_CPU0_LVC1_GPIO_1 
                                  AV73     UPI_CPU1_CPU0_P2P2_DN<10>
                                  AV75     UPI_CPU1_CPU0_P2P2_DN<7>
                                  AV77     GND                     
                                  AV79     UPI_CPU0_CPU1_P2P2_DP<12>
                                  AV81     UPI_CPU0_CPU1_P2P2_DN<7>
                                  AV83     UPI_CPU0_CPU1_P2P2_DP<8>
                                  AV85     P5E_CPU0_PE4_TX_DP<2>   
                                  AV87     GND                     
                                  AV89     P5E_CPU0_PE4_RX_DN<2>   
                                  AV91     GND                     
                                  AW1      GND                     
                                  AW3      UPI_CPU0_CPU1_P0P1_DN<15>
                                  AW5      GND                     
                                  AW7      UPI_CPU1_CPU0_P1P0_DN<14>
                                  AW9      GND                     
                                  AW11     P5E_CPU0_PE0_RX_DP<1>   
                                  AW13     GND                     
                                  AW15     P5E_CPU0_PE0_TX_DP<2>   
                                  AW17     PD_CPU0_DMIMODE_OVERRIDE
                                  AW21     GND                     
                                  AW23     GND                     
                                  AW25     GND                     
                                  AW60     PVCCFA_EHV_CPU0         
                                  AW62     GND                     
                                  AW66     GND                     
                                  AW68     GND                     
                                  AW70     FM_S3M_CPU0_LVC1_GPIO_4 
                                  AW72     GND                     
                                  AW74     UPI_CPU1_CPU0_P2P2_DP<7>
                                  AW76     PVCCFA_EHV_FIVRA_CPU0   
                                  AW78     UPI_CPU0_CPU1_P2P2_DN<13>
                                  AW80     GND                     
                                  AW82     GND                     
                                  AW84     GND                     
                                  AW86     P5E_CPU0_PE4_TX_DN<1>   
                                  AW88     GND                     
                                  AW90     P5E_CPU0_PE4_RX_DP<1>   
                                  AY2      UPI_CPU0_CPU1_P0P1_DP<15>
                                  AY4      GND                     
                                  AY6      UPI_CPU1_CPU0_P1P0_DN<15>
                                  AY8      GND                     
                                  AY10     P5E_CPU0_PE0_RX_DP<0>   
                                  AY12     GND                     
                                  AY14     P5E_CPU0_PE0_TX_DP<1>   
                                  AY16     GND                     
                                  AY18     PVCCINFAON_CPU0         
                                  AY20     PU_TAP_ODT_CPU0_EN      
                                  AY22     H_CPU0_ERR1_LVC1_R_N    
                                  AY63     FM_CPU0_PKGID1          
                                  AY69     FM_S3M_CPU0_LVC1_GPIO_3 
                                  AY71     GND                     
                                  AY73     UPI_CPU1_CPU0_P2P2_DP<10>
                                  AY75     UPI_CPU1_CPU0_P2P2_DN<9>
                                  AY77     GND                     
                                  AY79     GND                     
                                  AY81     GND                     
                                  AY83     GND                     
                                  AY85     VSENSE_PVCCFA_EHV_FIVRA_CPU0_DP
                                  AY87     P5E_CPU0_PE4_TX_DP<1>   
                                  AY89     PVCCFA_EHV_FIVRA_CPU0   
                                  AY91     P5E_CPU0_PE4_RX_DN<1>   
                                  B6       GND                     
                                  B8       M_A_CPU0_SB_DQ<28>      
                                  B10      M_A_CPU0_SB_DQ<25>      
                                  B12      GND                     
                                  B14      M_B_CPU0_SB_DQ<30>      
                                  B16      M_B_CPU0_SB_DQ<25>      
                                  B18      GND                     
                                  B20      M_A_CPU0_SB_DQ<20>      
                                  B22      M_A_CPU0_SB_DQ<17>      
                                  B24      GND                     
                                  B26      M_A_CPU0_SB_DQ<12>      
                                  B28      M_A_CPU0_SB_DQ<9>       
                                  B30      GND                     
                                  B32      M_A_CPU0_SB_CB<0>       
                                  B34      M_A_CPU0_SB_CB<5>       
                                  B36      GND                     
                                  B38      M_A_CPU0_SB_CS_N<0>     
                                  B40      M_A_CPU0_SB_CA<4>       
                                  B42      GND                     
                                  B44      M_A_CPU0_CLK_DN<0>      
                                  B49      GND                     
                                  B51      M_A_CPU0_SA_CA<2>       
                                  B53      M_A_CPU0_SA_CS_N<1>     
                                  B55      GND                     
                                  B57      M_A_CPU0_SA_CB<4>       
                                  B59      M_A_CPU0_SA_CB<1>       
                                  B61      GND                     
                                  B63      M_A_CPU0_SA_DQ<28>      
                                  B65      M_A_CPU0_SA_DQ<25>      
                                  B67      GND                     
                                  B69      M_A_CPU0_SA_DQ<20>      
                                  B71      M_A_CPU0_SA_DQS_DN<2>   
                                  B73      M_A_CPU0_SA_DQ<16>      
                                  B75      GND                     
                                  B77      M_A_CPU0_SA_DQS_DN<0>   
                                  B79      M_A_CPU0_SA_DQ<1>       
                                  B81      M_A_CPU0_SA_DQ<0>       
                                  B83      GND                     
                                  B85      UPI_CPU0_CPU1_P2P2_DN<23>
                                  B87      GND                     
                                  BA1      UPI_CPU0_CPU1_P0P1_DP<16>
                                  BA3      PVCCD_HV_CPU0           
                                  BA5      UPI_CPU1_CPU0_P1P0_DP<15>
                                  BA7      PVCCD_HV_CPU0           
                                  BA9      P5E_CPU0_PE0_RX_DN<0>   
                                  BA11     VSENSE_PVCCFA_EHV_CPU0_DN
                                  BA13     P5E_CPU0_PE0_TX_DN<1>   
                                  BA15     PVCCINFAON_CPU0         
                                  BA17     GND                     
                                  BA19     PVNN_MAIN_CPU0          
                                  BA21     P3V3_AUX                
                                  BA23     PU_CPU0_UPI0_AC_COUPLING
                                  BA60     GND                     
                                  BA64     GND                     
                                  BA70     FM_S3M_CPU0_LVC1_GPIO_0 
                                  BA72     UPI_CPU1_CPU0_P2P2_DP<11>
                                  BA74     GND                     
                                  BA76     UPI_CPU1_CPU0_P2P2_DP<9>
                                  BA78     UPI_CPU0_CPU1_P2P2_DP<13>
                                  BA80     UPI_CPU0_CPU1_P2P2_DN<6>
                                  BA82     UPI_CPU0_CPU1_P2P2_DP<5>
                                  BA84     GND                     
                                  BA86     P5E_CPU0_PE4_TX_DN<0>   
                                  BA88     GND                     
                                  BA90     P5E_CPU0_PE4_RX_DP<0>   
                                  BB2      UPI_CPU0_CPU1_P0P1_DN<16>
                                  BB4      GND                     
                                  BB6      UPI_CPU1_CPU0_P1P0_DP<16>
                                  BB8      GND                     
                                  BB10     GND                     
                                  BB12     GND                     
                                  BB14     P5E_CPU0_PE0_TX_DN<0>   
                                  BB16     GND                     
                                  BB18     DMI_CPU0_PCH_RX_C_DN<0> 
                                  BB20     GND                     
                                  BB22     GND                     
                                  BB24     GND                     
                                  BB26     GND                     
                                  BB63     GND                     
                                  BB65     PU_CPU0_UPI2_AC_COUPLING
                                  BB69     GND                     
                                  BB71     GND                     
                                  BB73     UPI_CPU1_CPU0_P2P2_DN<11>
                                  BB75     UPI_CPU1_CPU0_P2P2_DP<8>
                                  BB77     GND                     
                                  BB79     GND                     
                                  BB81     UPI_CPU0_CPU1_P2P2_DP<6>
                                  BB83     GND                     
                                  BB85     P5E_CPU0_PE4_TX_DP<0>   
                                  BB87     GND                     
                                  BB89     P5E_CPU0_PE4_RX_DN<0>   
                                  BB91     GND                     
                                  BC1      GND                     
                                  BC3      UPI_CPU0_CPU1_P0P1_DP<17>
                                  BC5      GND                     
                                  BC7      UPI_CPU1_CPU0_P1P0_DN<16>
                                  BC9      GND                     
                                  BC11     P5E_CPU0_PE1_RX_DP<15>  
                                  BC13     GND                     
                                  BC15     P5E_CPU0_PE0_TX_DP<0>   
                                  BC17     GND                     
                                  BC19     DMI_CPU0_PCH_RX_C_DP<0> 
                                  BC21     P3V3_AUX                
                                  BC60     PVCCINFAON_CPU0         
                                  BC62     GND                     
                                  BC66     GND                     
                                  BC72     GND                     
                                  BC74     UPI_CPU1_CPU0_P2P2_DN<0>
                                  BC76     GND                     
                                  BC78     GND                     
                                  BC80     UPI_CPU0_CPU1_P2P2_DP<3>
                                  BC82     UPI_CPU0_CPU1_P2P2_DN<5>
                                  BC84     GND                     
                                  BC86     GND                     
                                  BC88     GND                     
                                  BC90     VSENSE_PVCCIN_CPU0_DN   
                                  BD2      UPI_CPU0_CPU1_P0P1_DN<17>
                                  BD4      GND                     
                                  BD6      UPI_CPU1_CPU0_P1P0_DN<17>
                                  BD8      GND                     
                                  BD10     P5E_CPU0_PE1_RX_DN<15>  
                                  BD12     GND                     
                                  BD14     P5E_CPU0_PE1_TX_DP<15>  
                                  BD16     GND                     
                                  BD18     DMI_CPU0_PCH_RX_C_DN<1> 
                                  BD20     GND                     
                                  BD22     H_CPU0_ERR2_LVC1_R_N    
                                  BD24     H_PMAX_TRIGGER_IO_CPU0  
                                  BD26     SVID_DIO0_CPU0          
                                  BD73     UPI_CPU1_CPU0_P2P2_DP<0>
                                  BD75     UPI_CPU1_CPU0_P2P2_DN<8>
                                  BD79     UPI_CPU0_CPU1_P2P2_DN<3>
                                  BD81     GND                     
                                  BD83     UPI_CPU0_CPU1_P2P2_DP<4>
                                  BD85     GND                     
                                  BD87     VSENSE_PVCCIN_CPU0_DP   
                                  BD89     GND                     
                                  BD91     PVCCIN_CPU0             
                                  BE1      UPI_CPU0_CPU1_P0P1_DP<18>
                                  BE3      PVCCD_HV_CPU0           
                                  BE5      UPI_CPU1_CPU0_P1P0_DP<17>
                                  BE7      PVCCD_HV_CPU0           
                                  BE9      P5E_CPU0_PE1_RX_DN<14>  
                                  BE11     PVCCD_HV_CPU0           
                                  BE13     P5E_CPU0_PE1_TX_DN<15>  
                                  BE15     PVCCINFAON_CPU0         
                                  BE17     DMI_CPU0_PCH_RX_C_DP<1> 
                                  BE19     PVNN_MAIN_CPU0          
                                  BE60     PVCCINFAON_CPU0         
                                  BE64     GND                     
                                  BE66     GND                     
                                  BE68     GND                     
                                  BE72     PVCCFA_EHV_FIVRA_CPU0   
                                  BE74     GND                     
                                  BE76     GND                     
                                  BE78     GND                     
                                  BE80     UPI_CPU0_CPU1_P2P2_DP<1>
                                  BE82     UPI_CPU0_CPU1_P2P2_DN<4>
                                  BE84     GND                     
                                  BE86     PVCCIN_CPU0             
                                  BE88     PVCCIN_CPU0             
                                  BE90     PVCCIN_CPU0             
                                  BF2      UPI_CPU0_CPU1_P0P1_DN<18>
                                  BF4      GND                     
                                  BF6      UPI_CPU1_CPU0_P1P0_DP<18>
                                  BF8      GND                     
                                  BF10     P5E_CPU0_PE1_RX_DP<14>  
                                  BF12     GND                     
                                  BF14     P5E_CPU0_PE1_TX_DN<14>  
                                  BF16     GND                     
                                  BF18     DMI_CPU0_PCH_RX_C_DN<2> 
                                  BF20     GND                     
                                  BF22     H_CPU0_ERR0_LVC1_R_N    
                                  BF26     SVID_CLK1_CPU0          
                                  BF61     GND                     
                                  BF63     GND                     
                                  BF73     GND                     
                                  BF75     GND                     
                                  BF77     PVCCFA_EHV_FIVRA_CPU0   
                                  BF79     GND                     
                                  BF81     UPI_CPU0_CPU1_P2P2_DN<2>
                                  BF83     GND                     
                                  BF85     PVCCIN_CPU0             
                                  BF87     PVCCIN_CPU0             
                                  BF89     PVCCIN_CPU0             
                                  BF91     PVCCIN_CPU0             
                                  BG1      GND                     
                                  BG3      UPI_CPU0_CPU1_P0P1_DP<19>
                                  BG5      GND                     
                                  BG7      UPI_CPU1_CPU0_P1P0_DN<18>
                                  BG9      GND                     
                                  BG11     P5E_CPU0_PE1_RX_DP<13>  
                                  BG13     GND                     
                                  BG15     P5E_CPU0_PE1_TX_DP<14>  
                                  BG17     GND                     
                                  BG19     DMI_CPU0_PCH_RX_C_DP<2> 
                                  BG21     GND                     
                                  BG23     GND                     
                                  BG25     GND                     
                                  BG60     PVCCINFAON_CPU0         
                                  BG70     GND                     
                                  BG72     FM_CPU0_PROC_ID0        
                                  BG74     UPI_CPU1_CPU0_P2P2_DP<3>
                                  BG76     UPI_CPU1_CPU0_P2P2_DP<6>
                                  BG80     UPI_CPU0_CPU1_P2P2_DN<1>
                                  BG82     UPI_CPU0_CPU1_P2P2_DP<2>
                                  BG84     PVCCIN_CPU0             
                                  BG86     PVCCIN_CPU0             
                                  BG88     PVCCIN_CPU0             
                                  BG90     PVCCIN_CPU0             
                                  BH2      UPI_CPU0_CPU1_P0P1_DN<19>
                                  BH4      GND                     
                                  BH6      UPI_CPU1_CPU0_P1P0_DN<19>
                                  BH8      GND                     
                                  BH10     P5E_CPU0_PE1_RX_DN<13>  
                                  BH12     GND                     
                                  BH14     P5E_CPU0_PE1_TX_DP<13>  
                                  BH16     GND                     
                                  BH18     DMI_CPU0_PCH_RX_C_DN<3> 
                                  BH20     GND                     
                                  BH22     H_CPU0_RMCA_LVC1_R_N    
                                  BH24     PECI_CPU0_GTL_R         
                                  BH26     SVID_CLK0_CPU0          
                                  BH61     RST_CPU0_LVC1_N         
                                  BH67     GND                     
                                  BH71     FM_CPU0_PROC_ID1        
                                  BH73     GND                     
                                  BH75     UPI_CPU1_CPU0_P2P2_DN<6>
                                  BH77     GND                     
                                  BH79     PVCCFA_EHV_FIVRA_CPU0   
                                  BH81     GND                     
                                  BH83     GND                     
                                  BH85     PVCCIN_CPU0             
                                  BH87     PVCCIN_CPU0             
                                  BH89     PVCCIN_CPU0             
                                  BH91     PVCCIN_CPU0             
                                  BJ1      UPI_CPU0_CPU1_P0P1_DN<20>
                                  BJ3      PVCCD_HV_CPU0           
                                  BJ5      UPI_CPU1_CPU0_P1P0_DP<19>
                                  BJ7      PVCCD_HV_CPU0           
                                  BJ9      P5E_CPU0_PE1_RX_DN<12>  
                                  BJ11     PVCCD_HV_CPU0           
                                  BJ13     P5E_CPU0_PE1_TX_DN<13>  
                                  BJ15     PVCCINFAON_CPU0         
                                  BJ17     DMI_CPU0_PCH_RX_C_DP<3> 
                                  BJ19     PVNN_MAIN_CPU0          
                                  BJ23     DBP_CPU0_HOOK8_MBP2_GTL_QS_R_N
                                  BJ25     SVID_ALERT1_CPU0_N      
                                  BJ60     PVCCINFAON_CPU0         
                                  BJ62     GND                     
                                  BJ68     GND                     
                                  BJ72     PVCCFA_EHV_FIVRA_CPU0   
                                  BJ74     UPI_CPU1_CPU0_P2P2_DN<3>
                                  BJ76     UPI_CPU1_CPU0_P2P2_DN<5>
                                  BJ78     PVCCFA_EHV_FIVRA_CPU0   
                                  BJ80     GND                     
                                  BJ82     GND                     
                                  BJ84     GND                     
                                  BJ86     GND                     
                                  BJ88     GND                     
                                  BJ90     GND                     
                                  BK2      UPI_CPU0_CPU1_P0P1_DP<20>
                                  BK4      GND                     
                                  BK6      UPI_CPU1_CPU0_P1P0_DP<20>
                                  BK8      GND                     
                                  BK10     P5E_CPU0_PE1_RX_DP<12>  
                                  BK12     GND                     
                                  BK14     P5E_CPU0_PE1_TX_DN<12>  
                                  BK16     GND                     
                                  BK18     DMI_CPU0_PCH_RX_C_DP<4> 
                                  BK20     GND                     
                                  BK24     DBP_CPU0_HOOK9_MBP3_GTL_QS_R_N
                                  BK26     SVID_ALERT0_CPU0_N      
                                  BK61     PVCCINFAON_CPU0         
                                  BK65     GND                     
                                  BK71     GND                     
                                  BK73     UPI_CPU1_CPU0_P2P2_DN<1>
                                  BK75     GND                     
                                  BK77     UPI_CPU1_CPU0_P2P2_DP<5>
                                  BK79     GND                     
                                  BK81     PVCCIN_CPU0             
                                  BK83     PVCCIN_CPU0             
                                  BK85     PVCCIN_CPU0             
                                  BK87     PVCCIN_CPU0             
                                  BK89     PVCCIN_CPU0             
                                  BK91     PVCCIN_CPU0             
                                  BL1      GND                     
                                  BL3      UPI_CPU0_CPU1_P0P1_DN<21>
                                  BL5      GND                     
                                  BL7      UPI_CPU1_CPU0_P1P0_DN<20>
                                  BL9      GND                     
                                  BL11     P5E_CPU0_PE1_RX_DP<11>  
                                  BL13     GND                     
                                  BL15     P5E_CPU0_PE1_TX_DP<12>  
                                  BL17     GND                     
                                  BL19     DMI_CPU0_PCH_RX_C_DN<4> 
                                  BL23     DBP_CPU0_MBP0_GTL_R_N   
                                  BL25     SVID_DIO1_CPU0          
                                  BL62     H_CPU0_THERMTRIP_LVC1_R_N
                                  BL64     FM_CPU0_PKGID0          
                                  BL68     GND                     
                                  BL70     GND                     
                                  BL72     GND                     
                                  BL74     UPI_CPU1_CPU0_P2P2_DP<1>
                                  BL76     UPI_CPU1_CPU0_P2P2_DP<4>
                                  BL78     GND                     
                                  BL80     PVCCIN_CPU0             
                                  BL82     PVCCIN_CPU0             
                                  BL84     PVCCIN_CPU0             
                                  BL86     PVCCIN_CPU0             
                                  BL88     PVCCIN_CPU0             
                                  BL90     PVCCIN_CPU0             
                                  BM2      UPI_CPU0_CPU1_P0P1_DP<21>
                                  BM4      GND                     
                                  BM6      UPI_CPU1_CPU0_P1P0_DN<21>
                                  BM8      GND                     
                                  BM10     P5E_CPU0_PE1_RX_DN<11>  
                                  BM12     GND                     
                                  BM14     P5E_CPU0_PE1_TX_DP<11>  
                                  BM16     GND                     
                                  BM18     DMI_CPU0_PCH_RX_C_DN<5> 
                                  BM20     GND                     
                                  BM22     GND                     
                                  BM24     GND                     
                                  BM26     GND                     
                                  BM61     GND                     
                                  BM71     UPI_CPU0_CPU1_P2P2_DN<0>
                                  BM73     GND                     
                                  BM75     UPI_CPU1_CPU0_P2P2_DN<2>
                                  BM77     GND                     
                                  BM79     PVCCIN_CPU0             
                                  BM81     PVCCIN_CPU0             
                                  BM83     PVCCIN_CPU0             
                                  BM85     PVCCIN_CPU0             
                                  BM87     PVCCIN_CPU0             
                                  BM89     PVCCIN_CPU0             
                                  BM91     PVCCIN_CPU0             
                                  BN3      UPI_CPU0_CPU1_P0P1_DN<22>
                                  BN5      UPI_CPU1_CPU0_P1P0_DP<21>
                                  BN7      PVCCD_HV_CPU0           
                                  BN9      P5E_CPU0_PE1_RX_DN<10>  
                                  BN11     VSENSE_PVCCD_HV_CPU0_DN 
                                  BN13     P5E_CPU0_PE1_TX_DN<11>  
                                  BN15     PVCCINFAON_CPU0         
                                  BN17     DMI_CPU0_PCH_RX_C_DP<5> 
                                  BN19     PVNN_MAIN_CPU0          
                                  BN23     H_CPU0_BMCINIT_LVC1     
                                  BN25     DBP_CPU0_MBP1_GTL_R_N   
                                  BN31     GND                     
                                  BN33     PVCCIN_CPU0             
                                  BN35     PVCCIN_CPU0             
                                  BN37     PVCCIN_CPU0             
                                  BN39     PVCCIN_CPU0             
                                  BN41     PVCCIN_CPU0             
                                  BN43     PVCCIN_CPU0             
                                  BN45     PVCCIN_CPU0             
                                  BN48     PVCCIN_CPU0             
                                  BN50     PVCCIN_CPU0             
                                  BN52     PVCCIN_CPU0             
                                  BN54     PVCCIN_CPU0             
                                  BN56     PVCCIN_CPU0             
                                  BN58     PVCCIN_CPU0             
                                  BN60     PVCCIN_CPU0             
                                  BN62     GND                     
                                  BN64     FM_CPU0_PKGID2          
                                  BN70     GND                     
                                  BN72     UPI_CPU0_CPU1_P2P2_DP<0>
                                  BN74     UPI_CPU1_CPU0_P2P2_DP<2>
                                  BN76     UPI_CPU1_CPU0_P2P2_DN<4>
                                  BN78     PVCCIN_CPU0             
                                  BN80     PVCCIN_CPU0             
                                  BN82     PVCCIN_CPU0             
                                  BN84     PVCCIN_CPU0             
                                  BN86     PVCCIN_CPU0             
                                  BN88     PVCCIN_CPU0             
                                  BN90     PVCCIN_CPU0             
                                  BP2      GND                     
                                  BP4      GND                     
                                  BP6      UPI_CPU1_CPU0_P1P0_DP<22>
                                  BP8      GND                     
                                  BP10     P5E_CPU0_PE1_RX_DP<10>  
                                  BP12     GND                     
                                  BP14     P5E_CPU0_PE1_TX_DN<10>  
                                  BP16     GND                     
                                  BP18     DMI_CPU0_PCH_RX_C_DP<6> 
                                  BP20     GND                     
                                  BP24     H_CPU0_CATERR_LVC1_R_N  
                                  BP26     H_CPU0_PRDY_QS_GTL_R_N  
                                  BP32     PVCCIN_CPU0             
                                  BP34     PVCCIN_CPU0             
                                  BP36     PVCCIN_CPU0             
                                  BP38     PVCCIN_CPU0             
                                  BP40     PVCCIN_CPU0             
                                  BP42     PVCCIN_CPU0             
                                  BP44     PVCCIN_CPU0             
                                  BP47     PVCCIN_CPU0             
                                  BP49     PVCCIN_CPU0             
                                  BP51     PVCCIN_CPU0             
                                  BP53     PVCCIN_CPU0             
                                  BP55     PVCCIN_CPU0             
                                  BP57     PVCCIN_CPU0             
                                  BP59     PVCCIN_CPU0             
                                  BP61     PVCCIN_CPU0             
                                  BP63     GND                     
                                  BP71     GND                     
                                  BP73     GND                     
                                  BP75     GND                     
                                  BP77     GND                     
                                  BP79     PVCCIN_CPU0             
                                  BP81     PVCCIN_CPU0             
                                  BP83     PVCCIN_CPU0             
                                  BP85     PVCCIN_CPU0             
                                  BP87     PVCCIN_CPU0             
                                  BP89     PVCCIN_CPU0             
                                  BR3      UPI_CPU0_CPU1_P0P1_DP<22>
                                  BR5      GND                     
                                  BR7      UPI_CPU1_CPU0_P1P0_DN<22>
                                  BR9      GND                     
                                  BR11     P5E_CPU0_PE1_RX_DP<9>   
                                  BR13     GND                     
                                  BR15     P5E_CPU0_PE1_TX_DP<10>  
                                  BR17     GND                     
                                  BR19     DMI_CPU0_PCH_RX_C_DN<6> 
                                  BR23     H_CPU0_MON_FAIL_LVC1_R_N
                                  BR25     JTAG_DBP_CPU0_QS_GTL_R_TMS
                                  BR27     GND                     
                                  BR29     GND                     
                                  BR31     GND                     
                                  BR33     GND                     
                                  BR35     GND                     
                                  BR37     GND                     
                                  BR39     GND                     
                                  BR41     GND                     
                                  BR43     GND                     
                                  BR45     GND                     
                                  BR48     GND                     
                                  BR50     GND                     
                                  BR52     GND                     
                                  BR54     GND                     
                                  BR56     GND                     
                                  BR58     GND                     
                                  BR60     PVCCIN_CPU0             
                                  BR62     PVCCIN_CPU0             
                                  BR64     GND                     
                                  BR66     GND                     
                                  BR68     GND                     
                                  BR70     GND                     
                                  BR72     GND                     
                                  BR74     GND                     
                                  BR76     GND                     
                                  BR78     PVCCIN_CPU0             
                                  BR80     GND                     
                                  BR82     GND                     
                                  BR84     GND                     
                                  BR86     GND                     
                                  BR88     GND                     
                                  BR90     GND                     
                                  BT2      UPI_CPU0_CPU1_P0P1_DN<23>
                                  BT4      GND                     
                                  BT6      UPI_CPU1_CPU0_P1P0_DN<23>
                                  BT8      GND                     
                                  BT10     P5E_CPU0_PE1_RX_DN<9>   
                                  BT12     GND                     
                                  BT14     P5E_CPU0_PE1_TX_DP<9>   
                                  BT16     GND                     
                                  BT18     DMI_CPU0_PCH_RX_C_DP<7> 
                                  BT20     GND                     
                                  BT22     I3C_SPD_DDRABCD_CPU0_SCL
                                  BT24     JTAG_DBP_CPU0_GTL_R_TCK 
                                  BT26     PU_CPU0_TXT_AGENT       
                                  BT32     PVCCIN_CPU0             
                                  BT34     PVCCIN_CPU0             
                                  BT36     PVCCIN_CPU0             
                                  BT38     PVCCIN_CPU0             
                                  BT40     PVCCIN_CPU0             
                                  BT42     PVCCIN_CPU0             
                                  BT44     PVCCIN_CPU0             
                                  BT47     PVCCIN_CPU0             
                                  BT49     PVCCIN_CPU0             
                                  BT51     PVCCIN_CPU0             
                                  BT53     PVCCIN_CPU0             
                                  BT55     PVCCIN_CPU0             
                                  BT57     PVCCIN_CPU0             
                                  BT59     PVCCIN_CPU0             
                                  BT61     PVCCIN_CPU0             
                                  BT63     PVCCIN_CPU0             
                                  BT65     PVCCIN_CPU0             
                                  BT67     PVCCIN_CPU0             
                                  BT69     PVCCIN_CPU0             
                                  BT71     PVCCIN_CPU0             
                                  BT73     PVCCIN_CPU0             
                                  BT75     PVCCIN_CPU0             
                                  BT77     PVCCIN_CPU0             
                                  BT79     PVCCIN_CPU0             
                                  BT81     PVCCIN_CPU0             
                                  BT83     PVCCIN_CPU0             
                                  BT85     PVCCIN_CPU0             
                                  BT87     PVCCIN_CPU0             
                                  BT89     PVCCIN_CPU0             
                                  BU3      UPI_CPU0_CPU1_P0P1_DP<23>
                                  BU5      UPI_CPU1_CPU0_P1P0_DP<23>
                                  BU7      GND                     
                                  BU9      P5E_CPU0_PE1_RX_DN<8>   
                                  BU11     VSENSE_PVCCD_HV_CPU0_DP 
                                  BU13     P5E_CPU0_PE1_TX_DN<9>   
                                  BU15     GND                     
                                  BU17     DMI_CPU0_PCH_RX_C_DN<7> 
                                  BU19     GND                     
                                  BU21     GND                     
                                  BU23     GND                     
                                  BU25     GND                     
                                  BU31     GND                     
                                  BU33     PVCCIN_CPU0             
                                  BU35     PVCCIN_CPU0             
                                  BU37     PVCCIN_CPU0             
                                  BU39     PVCCIN_CPU0             
                                  BU41     PVCCIN_CPU0             
                                  BU43     PVCCIN_CPU0             
                                  BU45     PVCCIN_CPU0             
                                  BU48     PVCCIN_CPU0             
                                  BU50     PVCCIN_CPU0             
                                  BU52     PVCCIN_CPU0             
                                  BU54     PVCCIN_CPU0             
                                  BU56     PVCCIN_CPU0             
                                  BU58     PVCCIN_CPU0             
                                  BU60     PVCCIN_CPU0             
                                  BU62     PVCCIN_CPU0             
                                  BU64     PVCCIN_CPU0             
                                  BU66     PVCCIN_CPU0             
                                  BU68     PVCCIN_CPU0             
                                  BU70     PVCCIN_CPU0             
                                  BU72     PVCCIN_CPU0             
                                  BU74     PVCCIN_CPU0             
                                  BU76     PVCCIN_CPU0             
                                  BU78     PVCCIN_CPU0             
                                  BU80     PVCCIN_CPU0             
                                  BU82     PVCCIN_CPU0             
                                  BU84     PVCCIN_CPU0             
                                  BU86     PVCCIN_CPU0             
                                  BU88     PVCCIN_CPU0             
                                  BU90     PVCCIN_CPU0             
                                  BV2      GND                     
                                  BV4      GND                     
                                  BV6      GND                     
                                  BV8      GND                     
                                  BV10     P5E_CPU0_PE1_RX_DP<8>   
                                  BV12     GND                     
                                  BV14     P5E_CPU0_PE1_TX_DN<8>   
                                  BV16     GND                     
                                  BV18     GND                     
                                  BV20     GND                     
                                  BV24     JTAG_DBP_CPU0_GTL_R_TDI 
                                  BV26     FM_PEHPCPU0_ALERT_N     
                                  BV32     PVCCIN_CPU0             
                                  BV34     PVCCIN_CPU0             
                                  BV36     PVCCIN_CPU0             
                                  BV38     PVCCIN_CPU0             
                                  BV40     PVCCIN_CPU0             
                                  BV42     PVCCIN_CPU0             
                                  BV44     PVCCIN_CPU0             
                                  BV47     PVCCIN_CPU0             
                                  BV49     PVCCIN_CPU0             
                                  BV51     PVCCIN_CPU0             
                                  BV53     PVCCIN_CPU0             
                                  BV55     PVCCIN_CPU0             
                                  BV57     PVCCIN_CPU0             
                                  BV59     PVCCIN_CPU0             
                                  BV61     PVCCIN_CPU0             
                                  BV63     PVCCIN_CPU0             
                                  BV65     PVCCIN_CPU0             
                                  BV67     PVCCIN_CPU0             
                                  BV69     PVCCIN_CPU0             
                                  BV71     PVCCIN_CPU0             
                                  BV73     PVCCIN_CPU0             
                                  BV75     PVCCIN_CPU0             
                                  BV77     PVCCIN_CPU0             
                                  BV79     PVCCIN_CPU0             
                                  BV81     PVCCIN_CPU0             
                                  BV83     PVCCIN_CPU0             
                                  BV85     PVCCIN_CPU0             
                                  BV87     PVCCIN_CPU0             
                                  BV89     PVCCIN_CPU0             
                                  BW3      GND                     
                                  BW5      GND                     
                                  BW7      UPI_CPU0_CPU1_P1P0_DN<23>
                                  BW9      GND                     
                                  BW11     P5E_CPU0_PE1_RX_DP<7>   
                                  BW13     GND                     
                                  BW15     P5E_CPU0_PE1_TX_DP<8>   
                                  BW17     GND                     
                                  BW19     DMI_CPU0_PCH_TX_DP<0>   
                                  BW25     JTAG_CPU0_MUX_GTL_TDO   
                                  BW27     GND                     
                                  BW29     GND                     
                                  BW31     GND                     
                                  BW33     PVCCIN_CPU0             
                                  BW35     PVCCIN_CPU0             
                                  BW37     PVCCIN_CPU0             
                                  BW39     PVCCIN_CPU0             
                                  BW41     PVCCIN_CPU0             
                                  BW43     PVCCIN_CPU0             
                                  BW45     PVCCIN_CPU0             
                                  BW48     PVCCIN_CPU0             
                                  BW50     PVCCIN_CPU0             
                                  BW52     PVCCIN_CPU0             
                                  BW54     PVCCIN_CPU0             
                                  BW56     PVCCIN_CPU0             
                                  BW58     PVCCIN_CPU0             
                                  BW60     PVCCIN_CPU0             
                                  BW62     PVCCIN_CPU0             
                                  BW64     PVCCIN_CPU0             
                                  BW66     PVCCIN_CPU0             
                                  BW68     PVCCIN_CPU0             
                                  BW70     PVCCIN_CPU0             
                                  BW72     PVCCIN_CPU0             
                                  BW74     PVCCIN_CPU0             
                                  BW76     PVCCIN_CPU0             
                                  BW78     PVCCIN_CPU0             
                                  BW80     PVCCIN_CPU0             
                                  BW82     PVCCIN_CPU0             
                                  BW84     PVCCIN_CPU0             
                                  BW86     PVCCIN_CPU0             
                                  BW88     PVCCIN_CPU0             
                                  BW90     PVCCIN_CPU0             
                                  BY2      UPI_CPU1_CPU0_P0P1_DN<23>
                                  BY4      GND                     
                                  BY6      UPI_CPU0_CPU1_P1P0_DP<23>
                                  BY8      GND                     
                                  BY10     P5E_CPU0_PE1_RX_DN<7>   
                                  BY12     GND                     
                                  BY14     P5E_CPU0_PE1_TX_DP<7>   
                                  BY16     GND                     
                                  BY18     DMI_CPU0_PCH_TX_DN<1>   
                                  BY20     GND                     
                                  BY22     I3C_SPD_DDRABCD_CPU0_SDA
                                  BY24     PD_EXT_CLK_SEL_CPU0     
                                  BY26     SMB_PEHPCPU0_GTL_SDA    
                                  BY32     PVCCIN_CPU0             
                                  BY34     PVCCIN_CPU0             
                                  BY36     PVCCIN_CPU0             
                                  BY38     PVCCIN_CPU0             
                                  BY40     PVCCIN_CPU0             
                                  BY42     PVCCIN_CPU0             
                                  BY44     PVCCIN_CPU0             
                                  BY47     PVCCIN_CPU0             
                                  BY49     PVCCIN_CPU0             
                                  BY51     PVCCIN_CPU0             
                                  BY53     PVCCIN_CPU0             
                                  BY55     PVCCIN_CPU0             
                                  BY57     PVCCIN_CPU0             
                                  BY59     PVCCIN_CPU0             
                                  BY61     PVCCIN_CPU0             
                                  BY63     PVCCIN_CPU0             
                                  BY65     PVCCIN_CPU0             
                                  BY67     PVCCIN_CPU0             
                                  BY69     PVCCIN_CPU0             
                                  BY71     PVCCIN_CPU0             
                                  BY73     PVCCIN_CPU0             
                                  BY75     PVCCIN_CPU0             
                                  BY77     PVCCIN_CPU0             
                                  BY79     PVCCIN_CPU0             
                                  BY81     PVCCIN_CPU0             
                                  BY83     PVCCIN_CPU0             
                                  BY85     PVCCIN_CPU0             
                                  BY87     PVCCIN_CPU0             
                                  BY89     PVCCIN_CPU0             
                                  C5       GND                     
                                  C7       M_A_CPU0_SB_DQ<29>      
                                  C9       M_A_CPU0_SB_DQS_DP<3>   
                                  C11      M_A_CPU0_SB_DQ<24>      
                                  C13      M_B_CPU0_SB_DQ<28>      
                                  C15      M_B_CPU0_SB_DQS_DP<3>   
                                  C17      M_B_CPU0_SB_DQ<24>      
                                  C19      M_A_CPU0_SB_DQ<21>      
                                  C21      M_A_CPU0_SB_DQS_DP<2>   
                                  C23      M_A_CPU0_SB_DQ<16>      
                                  C25      M_A_CPU0_SB_DQ<13>      
                                  C27      M_A_CPU0_SB_DQS_DP<1>   
                                  C29      M_A_CPU0_SB_DQ<8>       
                                  C31      M_A_CPU0_SB_CB<1>       
                                  C33      M_A_CPU0_SB_DQS_DP<9>   
                                  C35      M_A_CPU0_SB_CB<4>       
                                  C37      M_A_CPU0_SB_CS_N<1>     
                                  C39      GND                     
                                  C41      M_A_CPU0_SB_CA<2>       
                                  C43      M_A_CPU0_CLK_DP<0>      
                                  C45      GND                     
                                  C48      M_A_CPU0_SA_CA<6>       
                                  C50      M_A_CPU0_SA_CA<4>       
                                  C52      GND                     
                                  C54      M_A_CPU0_SA_CS_N<0>     
                                  C56      M_A_CPU0_SA_CB<5>       
                                  C58      M_A_CPU0_SA_DQS_DP<4>   
                                  C60      M_A_CPU0_SA_CB<0>       
                                  C62      M_A_CPU0_SA_DQ<29>      
                                  C64      M_A_CPU0_SA_DQS_DP<3>   
                                  C66      M_A_CPU0_SA_DQ<24>      
                                  C68      M_A_CPU0_SA_DQ<21>      
                                  C70      M_A_CPU0_SA_DQS_DP<2>   
                                  C72      GND                     
                                  C74      GND                     
                                  C76      M_A_CPU0_SA_DQ<4>       
                                  C78      GND                     
                                  C80      GND                     
                                  C82      GND                     
                                  C84      PVCCFA_EHV_FIVRA_CPU0   
                                  C86      GND                     
                                  C88      PVCCFA_EHV_FIVRA_CPU0   
                                  CA3      GND                     
                                  CA5      UPI_CPU0_CPU1_P1P0_DN<22>
                                  CA7      PVCCD_HV_CPU0           
                                  CA9      P5E_CPU0_PE1_RX_DN<6>   
                                  CA11     VSENSE_PVCCINFAON_CPU0_DP
                                  CA13     P5E_CPU0_PE1_TX_DN<7>   
                                  CA15     PVCCINFAON_CPU0         
                                  CA17     DMI_CPU0_PCH_TX_DP<1>   
                                  CA19     DMI_CPU0_PCH_TX_DN<0>   
                                  CA25     SMB_PEHPCPU0_GTL_SCL    
                                  CA31     GND                     
                                  CA33     PVCCIN_CPU0             
                                  CA35     PVCCIN_CPU0             
                                  CA37     PVCCIN_CPU0             
                                  CA39     PVCCIN_CPU0             
                                  CA41     PVCCIN_CPU0             
                                  CA43     PVCCIN_CPU0             
                                  CA45     PVCCIN_CPU0             
                                  CA48     PVCCIN_CPU0             
                                  CA50     PVCCIN_CPU0             
                                  CA52     PVCCIN_CPU0             
                                  CA54     PVCCIN_CPU0             
                                  CA56     PVCCIN_CPU0             
                                  CA58     PVCCIN_CPU0             
                                  CA60     PVCCIN_CPU0             
                                  CA62     PVCCIN_CPU0             
                                  CA64     PVCCIN_CPU0             
                                  CA66     PVCCIN_CPU0             
                                  CA68     PVCCIN_CPU0             
                                  CA70     PVCCIN_CPU0             
                                  CA72     PVCCIN_CPU0             
                                  CA74     PVCCIN_CPU0             
                                  CA76     PVCCIN_CPU0             
                                  CA78     PVCCIN_CPU0             
                                  CA80     PVCCIN_CPU0             
                                  CA82     PVCCIN_CPU0             
                                  CA84     PVCCIN_CPU0             
                                  CA86     PVCCIN_CPU0             
                                  CA88     PVCCIN_CPU0             
                                  CA90     PVCCIN_CPU0             
                                  CB2      UPI_CPU1_CPU0_P0P1_DP<23>
                                  CB4      GND                     
                                  CB6      UPI_CPU0_CPU1_P1P0_DP<22>
                                  CB8      GND                     
                                  CB10     P5E_CPU0_PE1_RX_DP<6>   
                                  CB12     GND                     
                                  CB14     P5E_CPU0_PE1_TX_DN<6>   
                                  CB16     GND                     
                                  CB18     DMI_CPU0_PCH_TX_DP<2>   
                                  CB20     GND                     
                                  CB22     GND                     
                                  CB24     GND                     
                                  CB26     GND                     
                                  CB28     GND                     
                                  CB32     GND                     
                                  CB34     GND                     
                                  CB36     GND                     
                                  CB38     GND                     
                                  CB40     GND                     
                                  CB42     GND                     
                                  CB44     GND                     
                                  CB47     GND                     
                                  CB49     GND                     
                                  CB51     GND                     
                                  CB53     GND                     
                                  CB55     GND                     
                                  CB57     GND                     
                                  CB59     GND                     
                                  CB61     PVCCIN_CPU0             
                                  CB63     GND                     
                                  CB65     GND                     
                                  CB67     GND                     
                                  CB69     GND                     
                                  CB71     GND                     
                                  CB73     GND                     
                                  CB75     PVCCIN_CPU0             
                                  CB77     PVCCIN_CPU0             
                                  CB79     GND                     
                                  CB81     GND                     
                                  CB83     GND                     
                                  CB85     GND                     
                                  CB87     GND                     
                                  CB89     GND                     
                                  CC3      UPI_CPU1_CPU0_P0P1_DN<22>
                                  CC5      GND                     
                                  CC7      UPI_CPU0_CPU1_P1P0_DN<21>
                                  CC9      GND                     
                                  CC11     P5E_CPU0_PE1_RX_DP<5>   
                                  CC13     GND                     
                                  CC15     P5E_CPU0_PE1_TX_DP<6>   
                                  CC17     GND                     
                                  CC19     DMI_CPU0_PCH_TX_DN<2>   
                                  CC31     GND                     
                                  CC33     PVCCIN_CPU0             
                                  CC35     PVCCIN_CPU0             
                                  CC37     PVCCIN_CPU0             
                                  CC39     PVCCIN_CPU0             
                                  CC41     PVCCIN_CPU0             
                                  CC43     PVCCIN_CPU0             
                                  CC45     PVCCIN_CPU0             
                                  CC48     PVCCIN_CPU0             
                                  CC50     PVCCIN_CPU0             
                                  CC52     PVCCIN_CPU0             
                                  CC54     PVCCIN_CPU0             
                                  CC56     PVCCIN_CPU0             
                                  CC58     PVCCIN_CPU0             
                                  CC60     PVCCIN_CPU0             
                                  CC62     GND                     
                                  CC68     PVPP_HBM_CPU0           
                                  CC70     GND                     
                                  CC72     GND                     
                                  CC74     GND                     
                                  CC76     PVCCIN_CPU0             
                                  CC78     PVCCIN_CPU0             
                                  CC80     PVCCIN_CPU0             
                                  CC82     PVCCIN_CPU0             
                                  CC84     PVCCIN_CPU0             
                                  CC86     PVCCIN_CPU0             
                                  CC88     PVCCIN_CPU0             
                                  CC90     PVCCIN_CPU0             
                                  CD2      UPI_CPU1_CPU0_P0P1_DP<22>
                                  CD4      GND                     
                                  CD6      UPI_CPU0_CPU1_P1P0_DP<21>
                                  CD8      GND                     
                                  CD10     P5E_CPU0_PE1_RX_DN<5>   
                                  CD12     GND                     
                                  CD14     P5E_CPU0_PE1_TX_DP<5>   
                                  CD16     GND                     
                                  CD18     DMI_CPU0_PCH_TX_DP<3>   
                                  CD20     GND                     
                                  CD32     PVCCIN_CPU0             
                                  CD34     PVCCIN_CPU0             
                                  CD36     PVCCIN_CPU0             
                                  CD38     PVCCIN_CPU0             
                                  CD40     PVCCIN_CPU0             
                                  CD42     PVCCIN_CPU0             
                                  CD44     PVCCIN_CPU0             
                                  CD47     PVCCIN_CPU0             
                                  CD49     PVCCIN_CPU0             
                                  CD51     PVCCIN_CPU0             
                                  CD53     PVCCIN_CPU0             
                                  CD55     PVCCIN_CPU0             
                                  CD57     PVCCIN_CPU0             
                                  CD59     PVCCIN_CPU0             
                                  CD61     GND                     
                                  CD63     SMB_S3M_CPU0_SDA        
                                  CD67     PVPP_HBM_CPU0           
                                  CD73     UPI_CPU0_CPU1_P3P3_DN<0>
                                  CD75     GND                     
                                  CD77     GND                     
                                  CD79     PVCCIN_CPU0             
                                  CD81     PVCCIN_CPU0             
                                  CD83     PVCCIN_CPU0             
                                  CD85     PVCCIN_CPU0             
                                  CD87     PVCCIN_CPU0             
                                  CD89     PVCCIN_CPU0             
                                  CE1      UPI_CPU1_CPU0_P0P1_DP<21>
                                  CE3      GND                     
                                  CE5      UPI_CPU0_CPU1_P1P0_DP<20>
                                  CE7      PVCCD_HV_CPU0           
                                  CE9      P5E_CPU0_PE1_RX_DN<4>   
                                  CE11     VSENSE_PVCCINFAON_CPU0_DN
                                  CE13     P5E_CPU0_PE1_TX_DN<5>   
                                  CE15     PVCCINFAON_CPU0         
                                  CE17     DMI_CPU0_PCH_TX_DN<3>   
                                  CE19     PVCCINFAON_CPU0         
                                  CE60     GND                     
                                  CE64     SMB_S3M_CPU0_SCL        
                                  CE66     GND                     
                                  CE68     PVPP_HBM_CPU0           
                                  CE72     GND                     
                                  CE74     PVCCFA_EHV_FIVRA_CPU0   
                                  CE76     GND                     
                                  CE78     GND                     
                                  CE80     PVCCIN_CPU0             
                                  CE82     PVCCIN_CPU0             
                                  CE84     PVCCIN_CPU0             
                                  CE86     PVCCIN_CPU0             
                                  CE88     PVCCIN_CPU0             
                                  CE90     PVCCIN_CPU0             
                                  CF2      UPI_CPU1_CPU0_P0P1_DN<21>
                                  CF4      GND                     
                                  CF6      UPI_CPU0_CPU1_P1P0_DN<20>
                                  CF8      GND                     
                                  CF10     P5E_CPU0_PE1_RX_DP<4>   
                                  CF12     GND                     
                                  CF14     P5E_CPU0_PE1_TX_DN<4>   
                                  CF16     GND                     
                                  CF18     DMI_CPU0_PCH_TX_DN<4>   
                                  CF20     GND                     
                                  CF26     H_CPU0_MEMHOT_OUT_LVC1_R_N
                                  CF61     PUD_PCH_BOOT_MODE_CPU0  
                                  CF67     PVPP_HBM_CPU0           
                                  CF69     GND                     
                                  CF71     GND                     
                                  CF73     UPI_CPU0_CPU1_P3P3_DP<0>
                                  CF75     UPI_CPU0_CPU1_P3P3_DP<3>
                                  CF77     UPI_CPU0_CPU1_P3P3_DP<4>
                                  CF79     PVCCIN_CPU0             
                                  CF81     PVCCIN_CPU0             
                                  CF83     PVCCIN_CPU0             
                                  CF85     PVCCIN_CPU0             
                                  CF87     PVCCIN_CPU0             
                                  CF89     PVCCIN_CPU0             
                                  CF91     PVCCIN_CPU0             
                                  CG1      GND                     
                                  CG3      UPI_CPU1_CPU0_P0P1_DN<20>
                                  CG5      GND                     
                                  CG7      UPI_CPU0_CPU1_P1P0_DN<19>
                                  CG9      GND                     
                                  CG11     P5E_CPU0_PE1_RX_DP<3>   
                                  CG13     GND                     
                                  CG15     P5E_CPU0_PE1_TX_DP<4>   
                                  CG17     GND                     
                                  CG19     DMI_CPU0_PCH_TX_DP<4>   
                                  CG21     GND                     
                                  CG23     GND                     
                                  CG25     GND                     
                                  CG62     GND                     
                                  CG64     GND                     
                                  CG66     FM_CPU0_SKTOCC_LVT3_N   
                                  CG68     PVPP_HBM_CPU0           
                                  CG70     GND                     
                                  CG72     GND                     
                                  CG74     GND                     
                                  CG76     UPI_CPU0_CPU1_P3P3_DN<4>
                                  CG78     GND                     
                                  CG80     PVCCIN_CPU0             
                                  CG82     PVCCIN_CPU0             
                                  CG84     PVCCIN_CPU0             
                                  CG86     PVCCIN_CPU0             
                                  CG88     PVCCIN_CPU0             
                                  CG90     PVCCIN_CPU0             
                                  CH2      UPI_CPU1_CPU0_P0P1_DP<20>
                                  CH4      GND                     
                                  CH6      UPI_CPU0_CPU1_P1P0_DP<19>
                                  CH8      GND                     
                                  CH10     P5E_CPU0_PE1_RX_DN<3>   
                                  CH12     GND                     
                                  CH14     P5E_CPU0_PE1_TX_DP<3>   
                                  CH16     GND                     
                                  CH18     DMI_CPU0_PCH_TX_DP<5>   
                                  CH20     GND                     
                                  CH22     PD_CPU0_ENH_MCECC_DIS   
                                  CH65     PU_S3M_CPU0_CPLD_STATUS 
                                  CH67     GND                     
                                  CH71     PWRGD_S0_PWROK_CPU0_LVC1
                                  CH73     GND                     
                                  CH75     UPI_CPU0_CPU1_P3P3_DN<3>
                                  CH77     UPI_CPU0_CPU1_P3P3_DN<6>
                                  CH79     GND                     
                                  CH81     PVCCIN_CPU0             
                                  CH83     GND                     
                                  CH85     GND                     
                                  CH87     GND                     
                                  CH89     GND                     
                                  CH91     PVCCIN_CPU0             
                                  CJ1      UPI_CPU1_CPU0_P0P1_DP<19>
                                  CJ3      PVCCINFAON_CPU0         
                                  CJ5      UPI_CPU0_CPU1_P1P0_DP<18>
                                  CJ7      PVCCINFAON_CPU0         
                                  CJ9      P5E_CPU0_PE1_RX_DN<2>   
                                  CJ11     PVCCINFAON_CPU0         
                                  CJ13     P5E_CPU0_PE1_TX_DN<3>   
                                  CJ15     PVCCINFAON_CPU0         
                                  CJ17     DMI_CPU0_PCH_TX_DN<5>   
                                  CJ19     PVCCINFAON_CPU0         
                                  CJ60     GND                     
                                  CJ64     PU_S3M_CPU0_CPLD_CONFD  
                                  CJ72     PUD_XTAL_CPU0_MODE1     
                                  CJ74     UPI_CPU0_CPU1_P3P3_DP<2>
                                  CJ76     GND                     
                                  CJ78     UPI_CPU0_CPU1_P3P3_DP<6>
                                  CJ80     GND                     
                                  CJ82     PVCCIN_CPU0             
                                  CJ84     PVCCIN_CPU0             
                                  CJ86     PVCCIN_CPU0             
                                  CJ88     PVCCIN_CPU0             
                                  CJ90     PVCCIN_CPU0             
                                  CK2      UPI_CPU1_CPU0_P0P1_DN<19>
                                  CK4      GND                     
                                  CK6      UPI_CPU0_CPU1_P1P0_DN<18>
                                  CK8      GND                     
                                  CK10     P5E_CPU0_PE1_RX_DP<2>   
                                  CK12     GND                     
                                  CK14     P5E_CPU0_PE1_TX_DN<2>   
                                  CK16     GND                     
                                  CK18     DMI_CPU0_PCH_TX_DP<6>   
                                  CK20     GND                     
                                  CK26     GND                     
                                  CK63     GND                     
                                  CK65     FM_S3M_CPU0_CPLD_CONFIG_N
                                  CK69     GND                     
                                  CK71     PU_CPU0_UPI3_AC_COUPLING
                                  CK73     PVCCFA_EHV_FIVRA_CPU0   
                                  CK75     UPI_CPU0_CPU1_P3P3_DN<2>
                                  CK77     UPI_CPU0_CPU1_P3P3_DP<7>
                                  CK79     PVCCFA_EHV_FIVRA_CPU0   
                                  CK81     GND                     
                                  CK83     PVCCIN_CPU0             
                                  CK85     PVCCIN_CPU0             
                                  CK87     PVCCIN_CPU0             
                                  CK89     PVCCIN_CPU0             
                                  CK91     PVCCIN_CPU0             
                                  CL1      GND                     
                                  CL3      UPI_CPU1_CPU0_P0P1_DN<18>
                                  CL5      GND                     
                                  CL7      UPI_CPU0_CPU1_P1P0_DN<17>
                                  CL9      GND                     
                                  CL11     P5E_CPU0_PE1_RX_DP<1>   
                                  CL13     GND                     
                                  CL15     P5E_CPU0_PE1_TX_DP<2>   
                                  CL17     GND                     
                                  CL19     DMI_CPU0_PCH_TX_DN<6>   
                                  CL62     GND                     
                                  CL72     PUD_XTAL_CPU0_MODE0     
                                  CL74     GND                     
                                  CL76     UPI_CPU0_CPU1_P3P3_DN<5>
                                  CL78     GND                     
                                  CL80     GND                     
                                  CL82     GND                     
                                  CL84     PVCCIN_CPU0             
                                  CL86     PVCCIN_CPU0             
                                  CL88     PVCCIN_CPU0             
                                  CL90     PVCCIN_CPU0             
                                  CM2      UPI_CPU1_CPU0_P0P1_DP<18>
                                  CM4      GND                     
                                  CM6      UPI_CPU0_CPU1_P1P0_DP<17>
                                  CM8      GND                     
                                  CM10     P5E_CPU0_PE1_RX_DN<1>   
                                  CM12     GND                     
                                  CM14     P5E_CPU0_PE1_TX_DP<1>   
                                  CM16     GND                     
                                  CM18     DMI_CPU0_PCH_TX_DN<7>   
                                  CM20     GND                     
                                  CM22     GND                     
                                  CM24     GND                     
                                  CM61     GND                     
                                  CM65     GND                     
                                  CM67     GND                     
                                  CM71     SMB_CPU0_PIROM_3V3AUX_SDA_R
                                  CM73     PVCCFA_EHV_FIVRA_CPU0   
                                  CM75     UPI_CPU0_CPU1_P3P3_DP<5>
                                  CM77     UPI_CPU0_CPU1_P3P3_DN<7>
                                  CM79     GND                     
                                  CM81     GND                     
                                  CM83     GND                     
                                  CM85     GND                     
                                  CM87     PVCCIN_CPU0             
                                  CM89     PVCCIN_CPU0             
                                  CM91     PVCCIN_CPU0             
                                  CN1      UPI_CPU1_CPU0_P0P1_DP<17>
                                  CN3      PVCCINFAON_CPU0         
                                  CN5      UPI_CPU0_CPU1_P1P0_DP<16>
                                  CN7      PVCCINFAON_CPU0         
                                  CN9      P5E_CPU0_PE1_RX_DN<0>   
                                  CN11     PVCCINFAON_CPU0         
                                  CN13     P5E_CPU0_PE1_TX_DN<1>   
                                  CN15     PVCCINFAON_CPU0         
                                  CN17     DMI_CPU0_PCH_TX_DP<7>   
                                  CN19     PVCCINFAON_CPU0         
                                  CN25     H_CPU0_PMSYNC_CPU1_R    
                                  CN64     PVCCINFAON_CPU0         
                                  CN66     PVCCINFAON_CPU0         
                                  CN68     GND                     
                                  CN70     GND                     
                                  CN72     GND                     
                                  CN74     GND                     
                                  CN76     GND                     
                                  CN78     PVCCFA_EHV_FIVRA_CPU0   
                                  CN80     UPI_CPU1_CPU0_P3P3_DN<2>
                                  CN82     UPI_CPU1_CPU0_P3P3_DP<3>
                                  CN84     GND                     
                                  CN86     GND                     
                                  CN88     PVCCIN_CPU0             
                                  CN90     PVCCIN_CPU0             
                                  CP2      UPI_CPU1_CPU0_P0P1_DN<17>
                                  CP4      GND                     
                                  CP6      UPI_CPU0_CPU1_P1P0_DN<16>
                                  CP8      GND                     
                                  CP10     P5E_CPU0_PE1_RX_DP<0>   
                                  CP12     GND                     
                                  CP14     P5E_CPU0_PE1_TX_DN<0>   
                                  CP16     GND                     
                                  CP18     GND                     
                                  CP20     H_CPU0_PM_FAST_WAKE_N   
                                  CP22     JTAG_CPU0_PLD_TDO       
                                  CP63     PVCCINFAON_CPU0         
                                  CP65     PVCCINFAON_CPU0         
                                  CP67     PVCCINFAON_CPU0         
                                  CP71     PD_PIROM_CPU0_ADDR2     
                                  CP73     PVCCFA_EHV_FIVRA_CPU0   
                                  CP75     GND                     
                                  CP77     GND                     
                                  CP79     GND                     
                                  CP81     UPI_CPU1_CPU0_P3P3_DN<3>
                                  CP83     GND                     
                                  CP85     P5E_CPU0_PE3_TX_DN<15>  
                                  CP87     GND                     
                                  CP89     PVCCIN_CPU0             
                                  CP91     GND                     
                                  CR1      GND                     
                                  CR3      UPI_CPU1_CPU0_P0P1_DN<16>
                                  CR5      GND                     
                                  CR7      UPI_CPU0_CPU1_P1P0_DN<15>
                                  CR9      GND                     
                                  CR11     GND                     
                                  CR13     GND                     
                                  CR15     P5E_CPU0_PE1_TX_DP<0>   
                                  CR17     GND                     
                                  CR62     GND                     
                                  CR64     GND                     
                                  CR66     PVCCINFAON_CPU0         
                                  CR70     PD_PIROM_CPU0_ADDR0     
                                  CR72     PU_PIROM_CPU0_SM_WP     
                                  CR74     UPI_CPU0_CPU1_P3P3_DP<8>
                                  CR76     UPI_CPU0_CPU1_P3P3_DP<9>
                                  CR78     GND                     
                                  CR80     UPI_CPU1_CPU0_P3P3_DP<2>
                                  CR82     UPI_CPU1_CPU0_P3P3_DN<5>
                                  CR84     GND                     
                                  CR86     P5E_CPU0_PE3_TX_DP<15>  
                                  CR88     GND                     
                                  CR90     GND                     
                                  CT2      UPI_CPU1_CPU0_P0P1_DP<16>
                                  CT4      GND                     
                                  CT6      UPI_CPU0_CPU1_P1P0_DP<15>
                                  CT8      GND                     
                                  CT10     GND                     
                                  CT12     GND                     
                                  CT14     P5E_CPU0_PE2_TX_DN<0>   
                                  CT16     GND                     
                                  CT18     I3C_SPD_DDREFGH_CPU0_SDA
                                  CT20     PD_CPU0_TXT_PLTEN       
                                  CT22     JTAG_CPU0_PLD_TDI       
                                  CT61     PU_CPU0_SOCKET_ID2      
                                  CT63     PVCCINFAON_CPU0         
                                  CT65     PVCCINFAON_CPU0         
                                  CT67     PVCCINFAON_CPU0         
                                  CT69     GND                     
                                  CT71     PD_PIROM_CPU0_ADDR1     
                                  CT73     GND                     
                                  CT75     UPI_CPU0_CPU1_P3P3_DN<9>
                                  CT77     PVCCFA_EHV_FIVRA_CPU0   
                                  CT79     UPI_CPU1_CPU0_P3P3_DN<1>
                                  CT81     GND                     
                                  CT83     UPI_CPU1_CPU0_P3P3_DP<5>
                                  CT85     PVCCFA_EHV_FIVRA_CPU0   
                                  CT87     P5E_CPU0_PE3_TX_DN<14>  
                                  CT89     GND                     
                                  CT91     P5E_CPU0_PE3_RX_DP<15>  
                                  CU1      UPI_CPU1_CPU0_P0P1_DP<15>
                                  CU3      PVCCINFAON_CPU0         
                                  CU5      UPI_CPU0_CPU1_P1P0_DP<14>
                                  CU7      PVCCINFAON_CPU0         
                                  CU9      P5E_CPU0_PE2_RX_DN<0>   
                                  CU11     PVCCINFAON_CPU0         
                                  CU13     P5E_CPU0_PE2_TX_DP<0>   
                                  CU15     PVCCINFAON_CPU0         
                                  CU17     I3C_SPD_DDREFGH_CPU0_SCL
                                  CU19     GND                     
                                  CU21     GND                     
                                  CU23     GND                     
                                  CU25     GND                     
                                  CU60     GND                     
                                  CU64     PVCCINFAON_CPU0         
                                  CU66     GND                     
                                  CU68     GND                     
                                  CU70     SMB_CPU0_PIROM_3V3AUX_SCL_R
                                  CU72     GND                     
                                  CU74     UPI_CPU0_CPU1_P3P3_DN<8>
                                  CU76     UPI_CPU0_CPU1_P3P3_DN<10>
                                  CU78     GND                     
                                  CU80     UPI_CPU1_CPU0_P3P3_DP<1>
                                  CU82     UPI_CPU1_CPU0_P3P3_DN<6>
                                  CU84     GND                     
                                  CU86     P5E_CPU0_PE3_TX_DP<14>  
                                  CU88     GND                     
                                  CU90     P5E_CPU0_PE3_RX_DN<15>  
                                  CV2      UPI_CPU1_CPU0_P0P1_DN<15>
                                  CV4      GND                     
                                  CV6      UPI_CPU0_CPU1_P1P0_DN<14>
                                  CV8      GND                     
                                  CV10     P5E_CPU0_PE2_RX_DP<0>   
                                  CV12     GND                     
                                  CV14     P5E_CPU0_PE2_TX_DP<1>   
                                  CV16     GND                     
                                  CV20     PWRGD_PLT_AUX_CPU0_LVT3 
                                  CV22     JTAG_CPU0_PLD_TMS       
                                  CV26     GND                     
                                  CV61     PVCCINFAON_CPU0         
                                  CV63     PVCCINFAON_CPU0         
                                  CV65     PVCCINFAON_CPU0         
                                  CV67     PVCCINFAON_CPU0         
                                  CV73     UPI_CPU0_CPU1_P3P3_DP<1>
                                  CV75     GND                     
                                  CV77     UPI_CPU0_CPU1_P3P3_DP<10>
                                  CV79     GND                     
                                  CV81     UPI_CPU1_CPU0_P3P3_DP<4>
                                  CV83     GND                     
                                  CV85     P5E_CPU0_PE3_TX_DN<13>  
                                  CV87     GND                     
                                  CV89     P5E_CPU0_PE3_RX_DN<14>  
                                  CV91     GND                     
                                  CW1      GND                     
                                  CW3      UPI_CPU1_CPU0_P0P1_DP<14>
                                  CW5      GND                     
                                  CW7      UPI_CPU0_CPU1_P1P0_DN<13>
                                  CW9      GND                     
                                  CW11     P5E_CPU0_PE2_RX_DP<1>   
                                  CW13     GND                     
                                  CW15     P5E_CPU0_PE2_TX_DN<1>   
                                  CW17     GND                     
                                  CW19     PU_CPU0_UPI1_AC_COUPLING
                                  CW27     CLK_100M_DB2000_CPU0_BCLK3_DN
                                  CW29     CLK_100M_DB2000_CPU0_BCLK1_DP
                                  CW31     CLK_25M_NSSC_CPU0_DN    
                                  CW33     GND                     
                                  CW35     PVCCD_HV_CPU0           
                                  CW37     PVCCD_HV_CPU0           
                                  CW39     H_CPU0_PMDOWN_CPU1_R    
                                  CW45     PWRGD_DRAMPWRGD_CPU0_GH_LVC1_R
                                  CW48     M_F_CPU0_ALERT_N        
                                  CW50     M_G_CPU0_ALERT_N        
                                  CW52     PVCCD_HV_CPU0           
                                  CW54     PVCCD_HV_CPU0           
                                  CW56     PVCCD_HV_CPU0           
                                  CW60     PU_CPU0_SOCKET_ID0      
                                  CW62     PVCCINFAON_CPU0         
                                  CW64     PVCCINFAON_CPU0         
                                  CW66     PVCCINFAON_CPU0         
                                  CW70     GND                     
                                  CW72     GND                     
                                  CW74     UPI_CPU0_CPU1_P3P3_DN<1>
                                  CW76     UPI_CPU0_CPU1_P3P3_DN<11>
                                  CW78     GND                     
                                  CW80     UPI_CPU1_CPU0_P3P3_DN<4>
                                  CW82     UPI_CPU1_CPU0_P3P3_DP<6>
                                  CW84     GND                     
                                  CW86     P5E_CPU0_PE3_TX_DP<13>  
                                  CW88     GND                     
                                  CW90     P5E_CPU0_PE3_RX_DP<14>  
                                  CY2      UPI_CPU1_CPU0_P0P1_DN<14>
                                  CY4      GND                     
                                  CY6      UPI_CPU0_CPU1_P1P0_DP<13>
                                  CY8      GND                     
                                  CY10     P5E_CPU0_PE2_RX_DN<1>   
                                  CY12     GND                     
                                  CY14     P5E_CPU0_PE2_TX_DN<2>   
                                  CY16     GND                     
                                  CY18     GND                     
                                  CY20     FM_S3M_CPU0_CPLD_CRC_ERROR
                                  CY22     JTAG_CPU0_PLD_TCK       
                                  CY26     GND                     
                                  CY28     CLK_100M_DB2000_CPU0_BCLK1_DN
                                  CY30     GND                     
                                  CY32     CLK_25M_NSSC_CPU0_DP    
                                  CY34     PVCCD_HV_CPU0           
                                  CY36     PVCCD_HV_CPU0           
                                  CY40     H_CPU0_PMDOWN_PCH_R2    
                                  CY42     RST_CPU0_DRAM_EF_N      
                                  CY44     PWRGD_DRAMPWRGD_CPU0_EF_LVC1_R
                                  CY47     M_E_CPU0_ALERT_N        
                                  CY51     M_H_CPU0_ALERT_N        
                                  CY53     PVCCD_HV_CPU0           
                                  CY55     RST_CPU0_DRAM_GH_N      
                                  CY59     PU_CPU0_LEGACY_SKT      
                                  CY61     PU_CPU0_SOCKET_ID1      
                                  CY63     GND                     
                                  CY65     PVCCINFAON_CPU0         
                                  CY67     PVCCINFAON_CPU0         
                                  CY73     GND                     
                                  CY75     PVCCFA_EHV_FIVRA_CPU0   
                                  CY77     GND                     
                                  CY79     PVCCFA_EHV_FIVRA_CPU0   
                                  CY81     GND                     
                                  CY83     GND                     
                                  CY85     PVCCFA_EHV_FIVRA_CPU0   
                                  CY87     P5E_CPU0_PE3_TX_DN<12>  
                                  CY89     PVCCFA_EHV_FIVRA_CPU0   
                                  CY91     P5E_CPU0_PE3_RX_DP<13>  
                                  D6       GND                     
                                  D8       GND                     
                                  D10      GND                     
                                  D12      GND                     
                                  D14      GND                     
                                  D16      GND                     
                                  D18      GND                     
                                  D20      GND                     
                                  D22      GND                     
                                  D24      GND                     
                                  D26      GND                     
                                  D28      GND                     
                                  D30      GND                     
                                  D32      GND                     
                                  D34      GND                     
                                  D36      GND                     
                                  D38      GND                     
                                  D40      GND                     
                                  D42      GND                     
                                  D44      GND                     
                                  D47      GND                     
                                  D49      GND                     
                                  D51      GND                     
                                  D53      GND                     
                                  D55      GND                     
                                  D57      GND                     
                                  D59      GND                     
                                  D61      GND                     
                                  D63      GND                     
                                  D65      GND                     
                                  D67      GND                     
                                  D69      GND                     
                                  D71      GND                     
                                  D73      M_A_CPU0_SA_DQ<18>      
                                  D75      M_A_CPU0_SA_DQ<5>       
                                  D77      M_A_CPU0_SA_DQS_DP<0>   
                                  D79      GND                     
                                  D81      GND                     
                                  D83      GND                     
                                  D85      UPI_CPU0_CPU1_P2P2_DP<23>
                                  D87      UPI_CPU0_CPU1_P2P2_DN<21>
                                  DA1      UPI_CPU1_CPU0_P0P1_DP<13>
                                  DA3      PVCCINFAON_CPU0         
                                  DA5      UPI_CPU0_CPU1_P1P0_DP<12>
                                  DA7      PVCCINFAON_CPU0         
                                  DA9      P5E_CPU0_PE2_RX_DN<2>   
                                  DA11     PVCCINFAON_CPU0         
                                  DA13     P5E_CPU0_PE2_TX_DP<2>   
                                  DA15     PVCCINFAON_CPU0         
                                  DA17     M_H_CPU0_SB_DQ<29>      
                                  DA19     GND                     
                                  DA21     PVCCINFAON_CPU0         
                                  DA23     GND                     
                                  DA25     GND                     
                                  DA27     CLK_100M_DB2000_CPU0_BCLK3_DP
                                  DA29     GND                     
                                  DA31     GND                     
                                  DA33     GND                     
                                  DA35     GND                     
                                  DA37     GND                     
                                  DA39     H_CPU0_PMSYNC_PCH       
                                  DA41     GND                     
                                  DA43     GND                     
                                  DA48     GND                     
                                  DA50     GND                     
                                  DA54     GND                     
                                  DA56     GND                     
                                  DA58     GND                     
                                  DA60     GND                     
                                  DA62     GND                     
                                  DA64     PVCCINFAON_CPU0         
                                  DA66     GND                     
                                  DA68     GND                     
                                  DA72     GND                     
                                  DA74     GND                     
                                  DA76     UPI_CPU0_CPU1_P3P3_DP<11>
                                  DA78     UPI_CPU1_CPU0_P3P3_DN<0>
                                  DA80     GND                     
                                  DA82     GND                     
                                  DA84     GND                     
                                  DA86     P5E_CPU0_PE3_TX_DP<12>  
                                  DA88     GND                     
                                  DA90     P5E_CPU0_PE3_RX_DN<13>  
                                  DB2      UPI_CPU1_CPU0_P0P1_DN<13>
                                  DB4      GND                     
                                  DB6      UPI_CPU0_CPU1_P1P0_DN<12>
                                  DB8      GND                     
                                  DB10     P5E_CPU0_PE2_RX_DP<2>   
                                  DB12     GND                     
                                  DB14     P5E_CPU0_PE2_TX_DP<3>   
                                  DB16     GND                     
                                  DB18     M_H_CPU0_SB_DQS_DN<3>   
                                  DB20     GND                     
                                  DB22     GND                     
                                  DB24     M_H_CPU0_SB_DQS_DP<1>   
                                  DB26     GND                     
                                  DB28     GND                     
                                  DB30     M_H_CPU0_SB_DQS_DP<0>   
                                  DB32     GND                     
                                  DB34     GND                     
                                  DB36     M_H_CPU0_SB_DQS_DP<9>   
                                  DB38     GND                     
                                  DB40     GND                     
                                  DB42     M_H_CPU0_CLK_DP<1>      
                                  DB44     GND                     
                                  DB47     GND                     
                                  DB49     M_H_CPU0_SA_CA<0>       
                                  DB51     GND                     
                                  DB53     GND                     
                                  DB55     M_H_CPU0_SA_DQS_DP<4>   
                                  DB57     GND                     
                                  DB59     GND                     
                                  DB61     M_H_CPU0_SA_DQS_DP<3>   
                                  DB63     GND                     
                                  DB65     GND                     
                                  DB67     M_H_CPU0_SA_DQS_DP<2>   
                                  DB69     GND                     
                                  DB71     GND                     
                                  DB73     M_H_CPU0_SA_DQS_DN<1>   
                                  DB75     GND                     
                                  DB77     GND                     
                                  DB79     UPI_CPU1_CPU0_P3P3_DP<0>
                                  DB81     UPI_CPU1_CPU0_P3P3_DN<8>
                                  DB83     UPI_CPU1_CPU0_P3P3_DP<9>
                                  DB85     P5E_CPU0_PE3_TX_DN<11>  
                                  DB87     GND                     
                                  DB89     P5E_CPU0_PE3_RX_DN<12>  
                                  DB91     GND                     
                                  DC1      GND                     
                                  DC3      UPI_CPU1_CPU0_P0P1_DN<12>
                                  DC5      GND                     
                                  DC7      UPI_CPU0_CPU1_P1P0_DN<11>
                                  DC9      GND                     
                                  DC11     P5E_CPU0_PE2_RX_DP<3>   
                                  DC13     GND                     
                                  DC15     P5E_CPU0_PE2_TX_DN<3>   
                                  DC17     M_H_CPU0_SB_DQ<31>      
                                  DC19     M_H_CPU0_SB_DQ<25>      
                                  DC21     GND                     
                                  DC23     M_H_CPU0_SB_DQ<12>      
                                  DC25     M_H_CPU0_SB_DQ<9>       
                                  DC27     GND                     
                                  DC29     M_H_CPU0_SB_DQ<4>       
                                  DC31     M_H_CPU0_SB_DQ<1>       
                                  DC33     GND                     
                                  DC35     M_H_CPU0_SB_CB<0>       
                                  DC37     M_H_CPU0_SB_CB<7>       
                                  DC39     GND                     
                                  DC41     M_H_CPU0_SA_CA<6>       
                                  DC43     M_E_CPU0_SA_RSP<1>      
                                  DC45     GND                     
                                  DC48     M_H_CPU0_SA_CA<2>       
                                  DC50     M_H_CPU0_SA_CS_N<3>     
                                  DC52     GND                     
                                  DC54     M_H_CPU0_SA_CB<4>       
                                  DC56     M_H_CPU0_SA_CB<1>       
                                  DC58     GND                     
                                  DC60     M_H_CPU0_SA_DQ<28>      
                                  DC62     M_H_CPU0_SA_DQ<25>      
                                  DC64     GND                     
                                  DC66     M_H_CPU0_SA_DQ<20>      
                                  DC68     M_H_CPU0_SA_DQ<17>      
                                  DC70     GND                     
                                  DC72     M_H_CPU0_SA_DQ<12>      
                                  DC74     M_H_CPU0_SA_DQ<9>       
                                  DC76     GND                     
                                  DC78     GND                     
                                  DC80     GND                     
                                  DC82     UPI_CPU1_CPU0_P3P3_DN<9>
                                  DC84     GND                     
                                  DC86     P5E_CPU0_PE3_TX_DP<11>  
                                  DC88     GND                     
                                  DC90     P5E_CPU0_PE3_RX_DP<12>  
                                  DD2      UPI_CPU1_CPU0_P0P1_DP<12>
                                  DD4      GND                     
                                  DD6      UPI_CPU0_CPU1_P1P0_DP<11>
                                  DD8      GND                     
                                  DD10     P5E_CPU0_PE2_RX_DN<3>   
                                  DD12     GND                     
                                  DD14     P5E_CPU0_PE2_TX_DN<4>   
                                  DD16     GND                     
                                  DD18     M_H_CPU0_SB_DQS_DP<3>   
                                  DD20     M_H_CPU0_SB_DQ<24>      
                                  DD22     M_H_CPU0_SB_DQ<13>      
                                  DD24     M_H_CPU0_SB_DQS_DN<1>   
                                  DD26     M_H_CPU0_SB_DQ<8>       
                                  DD28     M_H_CPU0_SB_DQ<7>       
                                  DD30     M_H_CPU0_SB_DQS_DN<0>   
                                  DD32     M_H_CPU0_SB_DQ<0>       
                                  DD34     M_H_CPU0_SB_CB<1>       
                                  DD36     M_H_CPU0_SB_DQS_DN<9>   
                                  DD38     M_H_CPU0_SB_CB<6>       
                                  DD40     M_H_CPU0_SA_PAR         
                                  DD42     M_H_CPU0_CLK_DN<1>      
                                  DD44     M_E_CPU0_SA_RSP<0>      
                                  DD47     M_H_CPU0_SA_CA<4>       
                                  DD49     GND                     
                                  DD51     M_H_CPU0_SA_CS_N<2>     
                                  DD53     M_H_CPU0_SA_CB<5>       
                                  DD55     M_H_CPU0_SA_DQS_DN<4>   
                                  DD57     M_H_CPU0_SA_CB<0>       
                                  DD59     M_H_CPU0_SA_DQ<29>      
                                  DD61     M_H_CPU0_SA_DQS_DN<3>   
                                  DD63     M_H_CPU0_SA_DQ<24>      
                                  DD65     M_H_CPU0_SA_DQ<21>      
                                  DD67     M_H_CPU0_SA_DQS_DN<2>   
                                  DD69     M_H_CPU0_SA_DQ<16>      
                                  DD71     M_H_CPU0_SA_DQ<13>      
                                  DD73     M_H_CPU0_SA_DQS_DP<1>   
                                  DD75     M_H_CPU0_SA_DQ<8>       
                                  DD77     PVCCFA_EHV_FIVRA_CPU0   
                                  DD79     GND                     
                                  DD81     UPI_CPU1_CPU0_P3P3_DP<8>
                                  DD83     PVCCFA_EHV_FIVRA_CPU0   
                                  DD85     PVCCFA_EHV_FIVRA_CPU0   
                                  DD87     P5E_CPU0_PE3_TX_DN<10>  
                                  DD89     PVCCFA_EHV_FIVRA_CPU0   
                                  DD91     P5E_CPU0_PE3_RX_DN<11>  
                                  DE1      UPI_CPU1_CPU0_P0P1_DN<11>
                                  DE3      PVCCINFAON_CPU0         
                                  DE5      UPI_CPU0_CPU1_P1P0_DP<10>
                                  DE7      PVCCINFAON_CPU0         
                                  DE9      P5E_CPU0_PE2_RX_DN<4>   
                                  DE11     PVCCINFAON_CPU0         
                                  DE13     P5E_CPU0_PE2_TX_DP<4>   
                                  DE15     PVCCINFAON_CPU0         
                                  DE17     GND                     
                                  DE19     GND                     
                                  DE21     GND                     
                                  DE23     GND                     
                                  DE25     GND                     
                                  DE27     GND                     
                                  DE29     GND                     
                                  DE31     GND                     
                                  DE33     GND                     
                                  DE35     GND                     
                                  DE37     GND                     
                                  DE39     GND                     
                                  DE41     GND                     
                                  DE43     GND                     
                                  DE45     GND                     
                                  DE48     GND                     
                                  DE50     GND                     
                                  DE52     GND                     
                                  DE54     GND                     
                                  DE56     GND                     
                                  DE58     GND                     
                                  DE60     GND                     
                                  DE62     GND                     
                                  DE64     GND                     
                                  DE66     GND                     
                                  DE68     GND                     
                                  DE70     GND                     
                                  DE72     GND                     
                                  DE74     GND                     
                                  DE76     GND                     
                                  DE78     UPI_CPU1_CPU0_P3P3_DP<7>
                                  DE80     UPI_CPU1_CPU0_P3P3_DN<10>
                                  DE82     GND                     
                                  DE84     GND                     
                                  DE86     P5E_CPU0_PE3_TX_DP<10>  
                                  DE88     GND                     
                                  DE90     P5E_CPU0_PE3_RX_DP<11>  
                                  DF2      UPI_CPU1_CPU0_P0P1_DP<11>
                                  DF4      GND                     
                                  DF6      UPI_CPU0_CPU1_P1P0_DN<10>
                                  DF8      GND                     
                                  DF10     P5E_CPU0_PE2_RX_DP<4>   
                                  DF12     GND                     
                                  DF14     P5E_CPU0_PE2_TX_DP<5>   
                                  DF16     GND                     
                                  DF18     M_H_CPU0_SB_DQS_DN<8>   
                                  DF20     M_H_CPU0_SB_DQ<26>      
                                  DF22     M_H_CPU0_SB_DQ<15>      
                                  DF24     M_H_CPU0_SB_DQS_DP<6>   
                                  DF26     M_H_CPU0_SB_DQ<10>      
                                  DF28     M_H_CPU0_SB_DQ<5>       
                                  DF30     M_H_CPU0_SB_DQS_DP<5>   
                                  DF32     M_H_CPU0_SB_DQ<2>       
                                  DF34     M_H_CPU0_SB_CB<3>       
                                  DF36     M_H_CPU0_SB_DQS_DP<4>   
                                  DF38     M_H_CPU0_SB_CB<4>       
                                  DF40     M_H_CPU0_SB_CA<0>       
                                  DF42     M_H_CPU0_CLK_DP<0>      
                                  DF44     M_E_CPU0_SB_RSP<0>      
                                  DF47     M_H_CPU0_SA_CA<5>       
                                  DF49     GND                     
                                  DF51     M_H_CPU0_SA_CS_N<0>     
                                  DF53     M_H_CPU0_SA_CB<7>       
                                  DF55     M_H_CPU0_SA_DQS_DP<9>   
                                  DF57     M_H_CPU0_SA_CB<2>       
                                  DF59     M_H_CPU0_SA_DQ<31>      
                                  DF61     M_H_CPU0_SA_DQS_DP<8>   
                                  DF63     M_H_CPU0_SA_DQ<26>      
                                  DF65     M_H_CPU0_SA_DQ<23>      
                                  DF67     M_H_CPU0_SA_DQS_DP<7>   
                                  DF69     M_H_CPU0_SA_DQ<18>      
                                  DF71     M_H_CPU0_SA_DQ<15>      
                                  DF73     M_H_CPU0_SA_DQS_DP<6>   
                                  DF75     M_H_CPU0_SA_DQ<10>      
                                  DF77     UPI_CPU1_CPU0_P3P3_DN<7>
                                  DF79     GND                     
                                  DF81     UPI_CPU1_CPU0_P3P3_DP<10>
                                  DF83     UPI_CPU1_CPU0_P3P3_DN<11>
                                  DF85     P5E_CPU0_PE3_TX_DN<9>   
                                  DF87     GND                     
                                  DF89     P5E_CPU0_PE3_RX_DP<10>  
                                  DF91     GND                     
                                  DG1      GND                     
                                  DG3      UPI_CPU1_CPU0_P0P1_DN<10>
                                  DG5      GND                     
                                  DG7      UPI_CPU0_CPU1_P1P0_DP<9>
                                  DG9      GND                     
                                  DG11     P5E_CPU0_PE2_RX_DP<5>   
                                  DG13     GND                     
                                  DG15     P5E_CPU0_PE2_TX_DN<5>   
                                  DG17     M_H_CPU0_SB_DQ<28>      
                                  DG19     M_H_CPU0_SB_DQ<27>      
                                  DG21     GND                     
                                  DG23     M_H_CPU0_SB_DQ<14>      
                                  DG25     M_H_CPU0_SB_DQ<11>      
                                  DG27     GND                     
                                  DG29     M_H_CPU0_SB_DQ<6>       
                                  DG31     M_H_CPU0_SB_DQ<3>       
                                  DG33     GND                     
                                  DG35     M_H_CPU0_SB_CB<2>       
                                  DG37     M_H_CPU0_SB_CB<5>       
                                  DG39     GND                     
                                  DG41     M_H_CPU0_SB_CA<1>       
                                  DG43     M_E_CPU0_SB_RSP<1>      
                                  DG45     GND                     
                                  DG48     M_H_CPU0_SA_CA<3>       
                                  DG50     M_H_CPU0_SA_CS_N<1>     
                                  DG52     GND                     
                                  DG54     M_H_CPU0_SA_CB<6>       
                                  DG56     M_H_CPU0_SA_CB<3>       
                                  DG58     GND                     
                                  DG60     M_H_CPU0_SA_DQ<30>      
                                  DG62     M_H_CPU0_SA_DQ<27>      
                                  DG64     GND                     
                                  DG66     M_H_CPU0_SA_DQ<22>      
                                  DG68     M_H_CPU0_SA_DQ<19>      
                                  DG70     GND                     
                                  DG72     M_H_CPU0_SA_DQ<14>      
                                  DG74     M_H_CPU0_SA_DQ<11>      
                                  DG76     GND                     
                                  DG78     UPI_CPU1_CPU0_P3P3_DN<13>
                                  DG80     GND                     
                                  DG82     UPI_CPU1_CPU0_P3P3_DP<12>
                                  DG84     GND                     
                                  DG86     P5E_CPU0_PE3_TX_DP<9>   
                                  DG88     GND                     
                                  DG90     P5E_CPU0_PE3_RX_DN<10>  
                                  DH2      UPI_CPU1_CPU0_P0P1_DP<10>
                                  DH4      GND                     
                                  DH6      UPI_CPU0_CPU1_P1P0_DN<9>
                                  DH8      GND                     
                                  DH10     P5E_CPU0_PE2_RX_DN<5>   
                                  DH12     GND                     
                                  DH14     P5E_CPU0_PE2_TX_DN<6>   
                                  DH16     GND                     
                                  DH18     M_H_CPU0_SB_DQS_DP<8>   
                                  DH20     GND                     
                                  DH22     GND                     
                                  DH24     M_H_CPU0_SB_DQS_DN<6>   
                                  DH26     GND                     
                                  DH28     GND                     
                                  DH30     M_H_CPU0_SB_DQS_DN<5>   
                                  DH32     GND                     
                                  DH34     GND                     
                                  DH36     M_H_CPU0_SB_DQS_DN<4>   
                                  DH38     GND                     
                                  DH40     GND                     
                                  DH42     M_H_CPU0_CLK_DN<0>      
                                  DH44     GND                     
                                  DH47     GND                     
                                  DH49     M_H_CPU0_SA_CA<1>       
                                  DH51     GND                     
                                  DH53     GND                     
                                  DH55     M_H_CPU0_SA_DQS_DN<9>   
                                  DH57     GND                     
                                  DH59     GND                     
                                  DH61     M_H_CPU0_SA_DQS_DN<8>   
                                  DH63     GND                     
                                  DH65     GND                     
                                  DH67     M_H_CPU0_SA_DQS_DN<7>   
                                  DH69     GND                     
                                  DH71     GND                     
                                  DH73     M_H_CPU0_SA_DQS_DN<6>   
                                  DH75     GND                     
                                  DH77     GND                     
                                  DH79     UPI_CPU1_CPU0_P3P3_DP<13>
                                  DH81     UPI_CPU1_CPU0_P3P3_DN<12>
                                  DH83     UPI_CPU1_CPU0_P3P3_DP<11>
                                  DH85     GND                     
                                  DH87     P5E_CPU0_PE3_TX_DN<8>   
                                  DH89     PVCCFA_EHV_FIVRA_CPU0   
                                  DH91     P5E_CPU0_PE3_RX_DN<9>   
                                  DJ1      UPI_CPU1_CPU0_P0P1_DN<9>
                                  DJ3      PVCCINFAON_CPU0         
                                  DJ5      UPI_CPU0_CPU1_P1P0_DP<8>
                                  DJ7      PVCCINFAON_CPU0         
                                  DJ9      P5E_CPU0_PE2_RX_DN<6>   
                                  DJ11     PVCCINFAON_CPU0         
                                  DJ13     P5E_CPU0_PE2_TX_DP<6>   
                                  DJ15     PVCCINFAON_CPU0         
                                  DJ17     M_H_CPU0_SB_DQ<30>      
                                  DJ19     GND                     
                                  DJ21     M_H_CPU0_SB_DQS_DP<2>   
                                  DJ23     GND                     
                                  DJ25     GND                     
                                  DJ27     M_G_CPU0_SB_DQS_DN<1>   
                                  DJ29     GND                     
                                  DJ31     GND                     
                                  DJ33     M_G_CPU0_SB_DQS_DN<0>   
                                  DJ35     GND                     
                                  DJ37     GND                     
                                  DJ39     M_H_CPU0_SB_CA<6>       
                                  DJ41     GND                     
                                  DJ43     GND                     
                                  DJ45     M_G_CPU0_CLK_DP<1>      
                                  DJ48     GND                     
                                  DJ50     GND                     
                                  DJ52     M_G_CPU0_SA_CA<0>       
                                  DJ54     GND                     
                                  DJ56     GND                     
                                  DJ58     M_G_CPU0_SA_DQS_DP<4>   
                                  DJ60     GND                     
                                  DJ62     GND                     
                                  DJ64     M_G_CPU0_SA_DQS_DP<3>   
                                  DJ66     GND                     
                                  DJ68     GND                     
                                  DJ70     M_G_CPU0_SA_DQS_DN<1>   
                                  DJ72     GND                     
                                  DJ74     GND                     
                                  DJ76     M_H_CPU0_SA_DQS_DN<0>   
                                  DJ78     UPI_CPU1_CPU0_P3P3_DN<14>
                                  DJ80     GND                     
                                  DJ82     GND                     
                                  DJ84     GND                     
                                  DJ86     P5E_CPU0_PE3_TX_DP<8>   
                                  DJ88     GND                     
                                  DJ90     P5E_CPU0_PE3_RX_DP<9>   
                                  DK2      UPI_CPU1_CPU0_P0P1_DP<9>
                                  DK4      GND                     
                                  DK6      UPI_CPU0_CPU1_P1P0_DN<8>
                                  DK8      GND                     
                                  DK10     P5E_CPU0_PE2_RX_DP<6>   
                                  DK12     GND                     
                                  DK14     P5E_CPU0_PE2_TX_DP<7>   
                                  DK16     GND                     
                                  DK18     GND                     
                                  DK20     M_H_CPU0_SB_DQ<20>      
                                  DK22     M_H_CPU0_SB_DQ<17>      
                                  DK24     GND                     
                                  DK26     M_G_CPU0_SB_DQ<12>      
                                  DK28     M_G_CPU0_SB_DQ<9>       
                                  DK30     GND                     
                                  DK32     M_G_CPU0_SB_DQ<4>       
                                  DK34     M_G_CPU0_SB_DQ<1>       
                                  DK36     GND                     
                                  DK38     M_H_CPU0_SB_CS_N<2>     
                                  DK40     M_H_CPU0_SB_CA<4>       
                                  DK42     GND                     
                                  DK44     M_G_CPU0_SA_CA<6>       
                                  DK47     M_F_CPU0_SB_RSP<1>      
                                  DK49     GND                     
                                  DK51     M_G_CPU0_SA_CA<2>       
                                  DK53     M_G_CPU0_SA_CS_N<3>     
                                  DK55     GND                     
                                  DK57     M_G_CPU0_SA_CB<4>       
                                  DK59     M_G_CPU0_SA_CB<1>       
                                  DK61     GND                     
                                  DK63     M_G_CPU0_SA_DQ<28>      
                                  DK65     M_G_CPU0_SA_DQ<25>      
                                  DK67     GND                     
                                  DK69     M_G_CPU0_SA_DQ<12>      
                                  DK71     M_G_CPU0_SA_DQ<9>       
                                  DK73     GND                     
                                  DK75     M_H_CPU0_SA_DQ<4>       
                                  DK77     GND                     
                                  DK79     GND                     
                                  DK81     GND                     
                                  DK83     GND                     
                                  DK85     P5E_CPU0_PE3_TX_DN<7>   
                                  DK87     GND                     
                                  DK89     P5E_CPU0_PE3_RX_DP<8>   
                                  DK91     GND                     
                                  DL1      GND                     
                                  DL3      UPI_CPU1_CPU0_P0P1_DN<8>
                                  DL5      GND                     
                                  DL7      UPI_CPU0_CPU1_P1P0_DN<7>
                                  DL9      GND                     
                                  DL11     P5E_CPU0_PE2_RX_DP<7>   
                                  DL13     GND                     
                                  DL15     P5E_CPU0_PE2_TX_DN<7>   
                                  DL17     GND                     
                                  DL19     M_H_CPU0_SB_DQ<21>      
                                  DL21     M_H_CPU0_SB_DQS_DN<2>   
                                  DL23     M_H_CPU0_SB_DQ<16>      
                                  DL25     M_G_CPU0_SB_DQ<13>      
                                  DL27     M_G_CPU0_SB_DQS_DP<1>   
                                  DL29     M_G_CPU0_SB_DQ<10>      
                                  DL31     M_G_CPU0_SB_DQ<5>       
                                  DL33     M_G_CPU0_SB_DQS_DP<0>   
                                  DL35     M_G_CPU0_SB_DQ<0>       
                                  DL37     M_H_CPU0_SB_CS_N<0>     
                                  DL39     GND                     
                                  DL41     M_H_CPU0_SB_CA<2>       
                                  DL43     M_G_CPU0_SA_PAR         
                                  DL45     M_G_CPU0_CLK_DN<1>      
                                  DL48     M_F_CPU0_SB_RSP<0>      
                                  DL50     M_G_CPU0_SA_CA<4>       
                                  DL52     GND                     
                                  DL54     M_G_CPU0_SA_CS_N<2>     
                                  DL56     M_G_CPU0_SA_CB<5>       
                                  DL58     M_G_CPU0_SA_DQS_DN<4>   
                                  DL60     M_G_CPU0_SA_CB<0>       
                                  DL62     M_G_CPU0_SA_DQ<29>      
                                  DL64     M_G_CPU0_SA_DQS_DN<3>   
                                  DL66     M_G_CPU0_SA_DQ<24>      
                                  DL68     M_G_CPU0_SA_DQ<13>      
                                  DL70     M_G_CPU0_SA_DQS_DP<1>   
                                  DL72     M_G_CPU0_SA_DQ<8>       
                                  DL74     M_H_CPU0_SA_DQ<5>       
                                  DL76     M_H_CPU0_SA_DQS_DP<0>   
                                  DL78     UPI_CPU1_CPU0_P3P3_DP<14>
                                  DL80     UPI_CPU0_CPU1_P3P3_DP<12>
                                  DL82     UPI_CPU0_CPU1_P3P3_DP<13>
                                  DL84     GND                     
                                  DL86     P5E_CPU0_PE3_TX_DP<7>   
                                  DL88     GND                     
                                  DL90     P5E_CPU0_PE3_RX_DN<8>   
                                  DM2      UPI_CPU1_CPU0_P0P1_DP<8>
                                  DM4      GND                     
                                  DM6      UPI_CPU0_CPU1_P1P0_DP<7>
                                  DM8      GND                     
                                  DM10     P5E_CPU0_PE2_RX_DN<7>   
                                  DM12     GND                     
                                  DM14     P5E_CPU0_PE2_TX_DN<8>   
                                  DM16     GND                     
                                  DM18     GND                     
                                  DM20     GND                     
                                  DM22     GND                     
                                  DM24     GND                     
                                  DM26     GND                     
                                  DM28     GND                     
                                  DM30     GND                     
                                  DM32     GND                     
                                  DM34     GND                     
                                  DM36     GND                     
                                  DM38     GND                     
                                  DM40     GND                     
                                  DM42     GND                     
                                  DM44     GND                     
                                  DM47     GND                     
                                  DM49     GND                     
                                  DM51     GND                     
                                  DM53     GND                     
                                  DM55     GND                     
                                  DM57     GND                     
                                  DM59     GND                     
                                  DM61     GND                     
                                  DM63     GND                     
                                  DM65     GND                     
                                  DM67     GND                     
                                  DM69     GND                     
                                  DM71     GND                     
                                  DM73     GND                     
                                  DM75     GND                     
                                  DM77     GND                     
                                  DM79     GND                     
                                  DM81     UPI_CPU0_CPU1_P3P3_DN<13>
                                  DM83     PVCCFA_EHV_FIVRA_CPU0   
                                  DM85     PVCCFA_EHV_FIVRA_CPU0   
                                  DM87     P5E_CPU0_PE3_TX_DN<6>   
                                  DM89     PVCCFA_EHV_FIVRA_CPU0   
                                  DM91     P5E_CPU0_PE3_RX_DP<7>   
                                  DN1      UPI_CPU1_CPU0_P0P1_DN<7>
                                  DN3      PVCCFA_EHV_FIVRA_CPU0   
                                  DN5      UPI_CPU0_CPU1_P1P0_DP<6>
                                  DN7      PVCCFA_EHV_FIVRA_CPU0   
                                  DN9      P5E_CPU0_PE2_RX_DN<8>   
                                  DN11     PVCCFA_EHV_FIVRA_CPU0   
                                  DN13     P5E_CPU0_PE2_TX_DP<8>   
                                  DN15     PVCCFA_EHV_FIVRA_CPU0   
                                  DN17     GND                     
                                  DN19     M_H_CPU0_SB_DQ<23>      
                                  DN21     M_H_CPU0_SB_DQS_DP<7>   
                                  DN23     M_H_CPU0_SB_DQ<18>      
                                  DN25     M_G_CPU0_SB_DQ<15>      
                                  DN27     M_G_CPU0_SB_DQS_DN<6>   
                                  DN29     M_G_CPU0_SB_DQ<8>       
                                  DN31     M_G_CPU0_SB_DQ<7>       
                                  DN33     M_G_CPU0_SB_DQS_DP<5>   
                                  DN35     M_G_CPU0_SB_DQ<2>       
                                  DN37     M_H_CPU0_SB_CS_N<1>     
                                  DN39     GND                     
                                  DN41     M_H_CPU0_SB_CA<3>       
                                  DN43     M_G_CPU0_SB_CA<0>       
                                  DN45     M_G_CPU0_CLK_DP<0>      
                                  DN48     M_F_CPU0_SA_RSP<0>      
                                  DN50     M_G_CPU0_SA_CA<5>       
                                  DN52     GND                     
                                  DN54     M_G_CPU0_SA_CS_N<0>     
                                  DN56     M_G_CPU0_SA_CB<7>       
                                  DN58     M_G_CPU0_SA_DQS_DP<9>   
                                  DN60     M_G_CPU0_SA_CB<2>       
                                  DN62     M_G_CPU0_SA_DQ<31>      
                                  DN64     M_G_CPU0_SA_DQS_DP<8>   
                                  DN66     M_G_CPU0_SA_DQ<26>      
                                  DN68     M_G_CPU0_SA_DQ<15>      
                                  DN70     M_G_CPU0_SA_DQS_DP<6>   
                                  DN72     M_G_CPU0_SA_DQ<10>      
                                  DN74     M_H_CPU0_SA_DQ<7>       
                                  DN76     M_H_CPU0_SA_DQS_DP<5>   
                                  DN78     GND                     
                                  DN80     UPI_CPU0_CPU1_P3P3_DN<12>
                                  DN82     UPI_CPU0_CPU1_P3P3_DN<14>
                                  DN84     GND                     
                                  DN86     P5E_CPU0_PE3_TX_DP<6>   
                                  DN88     GND                     
                                  DN90     P5E_CPU0_PE3_RX_DN<7>   
                                  DP2      UPI_CPU1_CPU0_P0P1_DP<7>
                                  DP4      GND                     
                                  DP6      UPI_CPU0_CPU1_P1P0_DN<6>
                                  DP8      GND                     
                                  DP10     P5E_CPU0_PE2_RX_DP<8>   
                                  DP12     GND                     
                                  DP14     P5E_CPU0_PE2_TX_DP<9>   
                                  DP16     GND                     
                                  DP18     GND                     
                                  DP20     M_H_CPU0_SB_DQ<22>      
                                  DP22     M_H_CPU0_SB_DQ<19>      
                                  DP24     GND                     
                                  DP26     M_G_CPU0_SB_DQ<14>      
                                  DP28     M_G_CPU0_SB_DQ<11>      
                                  DP30     GND                     
                                  DP32     M_G_CPU0_SB_DQ<6>       
                                  DP34     M_G_CPU0_SB_DQ<3>       
                                  DP36     GND                     
                                  DP38     M_H_CPU0_SB_CS_N<3>     
                                  DP40     M_H_CPU0_SB_CA<5>       
                                  DP42     GND                     
                                  DP44     M_G_CPU0_SB_CA<1>       
                                  DP47     M_F_CPU0_SA_RSP<1>      
                                  DP49     GND                     
                                  DP51     M_G_CPU0_SA_CA<3>       
                                  DP53     M_G_CPU0_SA_CS_N<1>     
                                  DP55     GND                     
                                  DP57     M_G_CPU0_SA_CB<6>       
                                  DP59     M_G_CPU0_SA_CB<3>       
                                  DP61     GND                     
                                  DP63     M_G_CPU0_SA_DQ<30>      
                                  DP65     M_G_CPU0_SA_DQ<27>      
                                  DP67     GND                     
                                  DP69     M_G_CPU0_SA_DQ<14>      
                                  DP71     M_G_CPU0_SA_DQ<11>      
                                  DP73     GND                     
                                  DP75     M_H_CPU0_SA_DQ<6>       
                                  DP77     M_H_CPU0_SA_DQ<3>       
                                  DP79     UPI_CPU0_CPU1_P3P3_DP<15>
                                  DP81     GND                     
                                  DP83     UPI_CPU0_CPU1_P3P3_DP<14>
                                  DP85     P5E_CPU0_PE3_TX_DN<5>   
                                  DP87     GND                     
                                  DP89     P5E_CPU0_PE3_RX_DN<6>   
                                  DP91     GND                     
                                  DR1      GND                     
                                  DR3      UPI_CPU1_CPU0_P0P1_DP<6>
                                  DR5      GND                     
                                  DR7      UPI_CPU0_CPU1_P1P0_DN<5>
                                  DR9      GND                     
                                  DR11     P5E_CPU0_PE2_RX_DP<9>   
                                  DR13     GND                     
                                  DR15     P5E_CPU0_PE2_TX_DN<9>   
                                  DR17     M_F_CPU0_SB_DQ<31>      
                                  DR19     GND                     
                                  DR21     M_H_CPU0_SB_DQS_DN<7>   
                                  DR23     GND                     
                                  DR25     GND                     
                                  DR27     M_G_CPU0_SB_DQS_DP<6>   
                                  DR29     GND                     
                                  DR31     GND                     
                                  DR33     M_G_CPU0_SB_DQS_DN<5>   
                                  DR35     GND                     
                                  DR37     GND                     
                                  DR39     M_H_CPU0_SB_PAR         
                                  DR41     GND                     
                                  DR43     GND                     
                                  DR45     M_G_CPU0_CLK_DN<0>      
                                  DR48     GND                     
                                  DR50     GND                     
                                  DR52     M_G_CPU0_SA_CA<1>       
                                  DR54     GND                     
                                  DR56     GND                     
                                  DR58     M_G_CPU0_SA_DQS_DN<9>   
                                  DR60     GND                     
                                  DR62     GND                     
                                  DR64     M_G_CPU0_SA_DQS_DN<8>   
                                  DR66     GND                     
                                  DR68     GND                     
                                  DR70     M_G_CPU0_SA_DQS_DN<6>   
                                  DR72     GND                     
                                  DR74     GND                     
                                  DR76     M_H_CPU0_SA_DQS_DN<5>   
                                  DR78     GND                     
                                  DR80     UPI_CPU0_CPU1_P3P3_DN<15>
                                  DR82     UPI_CPU0_CPU1_P3P3_DP<16>
                                  DR84     GND                     
                                  DR86     P5E_CPU0_PE3_TX_DP<5>   
                                  DR88     GND                     
                                  DR90     P5E_CPU0_PE3_RX_DP<6>   
                                  DT2      UPI_CPU1_CPU0_P0P1_DN<6>
                                  DT4      GND                     
                                  DT6      UPI_CPU0_CPU1_P1P0_DP<5>
                                  DT8      GND                     
                                  DT10     P5E_CPU0_PE2_RX_DN<9>   
                                  DT12     GND                     
                                  DT14     P5E_CPU0_PE2_TX_DN<10>  
                                  DT16     GND                     
                                  DT18     M_F_CPU0_SB_DQS_DN<3>   
                                  DT20     GND                     
                                  DT22     GND                     
                                  DT24     M_G_CPU0_SB_DQS_DP<2>   
                                  DT26     GND                     
                                  DT28     GND                     
                                  DT30     M_F_CPU0_SB_DQS_DP<0>   
                                  DT32     GND                     
                                  DT34     GND                     
                                  DT36     M_G_CPU0_SB_DQS_DP<9>   
                                  DT38     GND                     
                                  DT40     GND                     
                                  DT42     M_G_CPU0_SB_CA<6>       
                                  DT44     GND                     
                                  DT47     GND                     
                                  DT49     M_F_CPU0_CLK_DP<1>      
                                  DT51     GND                     
                                  DT53     GND                     
                                  DT55     M_F_CPU0_SA_DQS_DP<3>   
                                  DT57     GND                     
                                  DT59     GND                     
                                  DT61     M_G_CPU0_SA_DQS_DN<2>   
                                  DT63     GND                     
                                  DT65     GND                     
                                  DT67     M_F_CPU0_SA_DQS_DN<1>   
                                  DT69     GND                     
                                  DT71     GND                     
                                  DT73     M_G_CPU0_SA_DQS_DP<0>   
                                  DT75     GND                     
                                  DT77     M_H_CPU0_SA_DQ<1>       
                                  DT79     PVCCFA_EHV_FIVRA_CPU0   
                                  DT81     UPI_CPU0_CPU1_P3P3_DP<17>
                                  DT83     GND                     
                                  DT85     PVCCFA_EHV_FIVRA_CPU0   
                                  DT87     P5E_CPU0_PE3_TX_DN<4>   
                                  DT89     PVCCFA_EHV_FIVRA_CPU0   
                                  DT91     P5E_CPU0_PE3_RX_DP<5>   
                                  DU1      UPI_CPU1_CPU0_P0P1_DN<5>
                                  DU3      PVCCFA_EHV_FIVRA_CPU0   
                                  DU5      UPI_CPU0_CPU1_P1P0_DP<4>
                                  DU7      PVCCFA_EHV_FIVRA_CPU0   
                                  DU9      P5E_CPU0_PE2_RX_DN<10>  
                                  DU11     PVCCFA_EHV_FIVRA_CPU0   
                                  DU13     P5E_CPU0_PE2_TX_DP<10>  
                                  DU15     PVCCFA_EHV_FIVRA_CPU0   
                                  DU17     M_F_CPU0_SB_DQ<29>      
                                  DU19     M_F_CPU0_SB_DQ<25>      
                                  DU21     GND                     
                                  DU23     M_G_CPU0_SB_DQ<20>      
                                  DU25     M_G_CPU0_SB_DQ<17>      
                                  DU27     GND                     
                                  DU29     M_F_CPU0_SB_DQ<4>       
                                  DU31     M_F_CPU0_SB_DQ<1>       
                                  DU33     GND                     
                                  DU35     M_G_CPU0_SB_CB<0>       
                                  DU37     M_G_CPU0_SB_CB<5>       
                                  DU39     GND                     
                                  DU41     M_G_CPU0_SB_CS_N<2>     
                                  DU43     M_G_CPU0_SB_CA<4>       
                                  DU45     GND                     
                                  DU48     M_G_CPU0_SB_RSP<0>      
                                  DU50     M_F_CPU0_SB_CA<1>       
                                  DU52     GND                     
                                  DU54     M_F_CPU0_SA_DQ<28>      
                                  DU56     M_F_CPU0_SA_DQ<25>      
                                  DU58     GND                     
                                  DU60     M_G_CPU0_SA_DQ<20>      
                                  DU62     M_G_CPU0_SA_DQ<17>      
                                  DU64     GND                     
                                  DU66     M_F_CPU0_SA_DQ<12>      
                                  DU68     M_F_CPU0_SA_DQ<9>       
                                  DU70     GND                     
                                  DU72     M_G_CPU0_SA_DQ<4>       
                                  DU74     M_G_CPU0_SA_DQ<1>       
                                  DU76     GND                     
                                  DU78     GND                     
                                  DU80     UPI_CPU0_CPU1_P3P3_DN<17>
                                  DU82     UPI_CPU0_CPU1_P3P3_DN<16>
                                  DU84     GND                     
                                  DU86     P5E_CPU0_PE3_TX_DP<4>   
                                  DU88     GND                     
                                  DU90     P5E_CPU0_PE3_RX_DN<5>   
                                  DV2      UPI_CPU1_CPU0_P0P1_DP<5>
                                  DV4      GND                     
                                  DV6      UPI_CPU0_CPU1_P1P0_DN<4>
                                  DV8      GND                     
                                  DV10     P5E_CPU0_PE2_RX_DP<10>  
                                  DV12     GND                     
                                  DV14     P5E_CPU0_PE2_TX_DP<11>  
                                  DV16     GND                     
                                  DV18     M_F_CPU0_SB_DQS_DP<3>   
                                  DV20     M_F_CPU0_SB_DQ<24>      
                                  DV22     M_G_CPU0_SB_DQ<21>      
                                  DV24     M_G_CPU0_SB_DQS_DN<2>   
                                  DV26     M_G_CPU0_SB_DQ<16>      
                                  DV28     M_F_CPU0_SB_DQ<5>       
                                  DV30     M_F_CPU0_SB_DQS_DN<0>   
                                  DV32     M_F_CPU0_SB_DQ<0>       
                                  DV34     M_G_CPU0_SB_CB<1>       
                                  DV36     M_G_CPU0_SB_DQS_DN<9>   
                                  DV38     M_G_CPU0_SB_CB<4>       
                                  DV40     M_G_CPU0_SB_CS_N<3>     
                                  DV42     GND                     
                                  DV44     M_G_CPU0_SB_CA<2>       
                                  DV47     M_G_CPU0_SB_RSP<1>      
                                  DV49     M_F_CPU0_CLK_DN<1>      
                                  DV51     M_F_CPU0_SB_CA<0>       
                                  DV53     M_F_CPU0_SA_DQ<29>      
                                  DV55     M_F_CPU0_SA_DQS_DN<3>   
                                  DV57     M_F_CPU0_SA_DQ<24>      
                                  DV59     M_G_CPU0_SA_DQ<21>      
                                  DV61     M_G_CPU0_SA_DQS_DP<2>   
                                  DV63     M_G_CPU0_SA_DQ<16>      
                                  DV65     M_F_CPU0_SA_DQ<13>      
                                  DV67     M_F_CPU0_SA_DQS_DP<1>   
                                  DV69     M_F_CPU0_SA_DQ<8>       
                                  DV71     M_G_CPU0_SA_DQ<5>       
                                  DV73     M_G_CPU0_SA_DQS_DN<0>   
                                  DV75     M_G_CPU0_SA_DQ<0>       
                                  DV77     GND                     
                                  DV79     GND                     
                                  DV81     GND                     
                                  DV83     GND                     
                                  DV85     P5E_CPU0_PE3_TX_DN<3>   
                                  DV87     GND                     
                                  DV89     P5E_CPU0_PE3_RX_DN<4>   
                                  DV91     GND                     
                                  DW1      GND                     
                                  DW3      UPI_CPU1_CPU0_P0P1_DP<4>
                                  DW5      GND                     
                                  DW7      UPI_CPU0_CPU1_P1P0_DN<3>
                                  DW9      GND                     
                                  DW11     P5E_CPU0_PE2_RX_DP<11>  
                                  DW13     GND                     
                                  DW15     P5E_CPU0_PE2_TX_DN<11>  
                                  DW17     GND                     
                                  DW19     GND                     
                                  DW21     GND                     
                                  DW23     GND                     
                                  DW25     GND                     
                                  DW27     GND                     
                                  DW29     GND                     
                                  DW31     GND                     
                                  DW33     GND                     
                                  DW35     GND                     
                                  DW37     GND                     
                                  DW39     GND                     
                                  DW41     GND                     
                                  DW43     GND                     
                                  DW45     GND                     
                                  DW48     GND                     
                                  DW50     GND                     
                                  DW52     GND                     
                                  DW54     GND                     
                                  DW56     GND                     
                                  DW58     GND                     
                                  DW60     GND                     
                                  DW62     GND                     
                                  DW64     GND                     
                                  DW66     GND                     
                                  DW68     GND                     
                                  DW70     GND                     
                                  DW72     GND                     
                                  DW74     GND                     
                                  DW76     GND                     
                                  DW78     M_H_CPU0_SA_DQ<2>       
                                  DW80     GND                     
                                  DW82     GND                     
                                  DW84     GND                     
                                  DW86     P5E_CPU0_PE3_TX_DP<3>   
                                  DW88     GND                     
                                  DW90     P5E_CPU0_PE3_RX_DP<4>   
                                  DY2      UPI_CPU1_CPU0_P0P1_DN<4>
                                  DY4      GND                     
                                  DY6      UPI_CPU0_CPU1_P1P0_DP<3>
                                  DY8      GND                     
                                  DY10     P5E_CPU0_PE2_RX_DN<11>  
                                  DY12     GND                     
                                  DY14     P5E_CPU0_PE2_TX_DN<12>  
                                  DY16     GND                     
                                  DY18     M_F_CPU0_SB_DQS_DN<8>   
                                  DY20     M_F_CPU0_SB_DQ<26>      
                                  DY22     M_G_CPU0_SB_DQ<23>      
                                  DY24     M_G_CPU0_SB_DQS_DP<7>   
                                  DY26     M_G_CPU0_SB_DQ<18>      
                                  DY28     M_F_CPU0_SB_DQ<7>       
                                  DY30     M_F_CPU0_SB_DQS_DP<5>   
                                  DY32     M_F_CPU0_SB_DQ<2>       
                                  DY34     M_G_CPU0_SB_CB<3>       
                                  DY36     M_G_CPU0_SB_DQS_DP<4>   
                                  DY38     M_G_CPU0_SB_CB<6>       
                                  DY40     M_G_CPU0_SB_CS_N<1>     
                                  DY42     GND                     
                                  DY44     M_G_CPU0_SB_CA<3>       
                                  DY47     M_G_CPU0_SA_RSP<1>      
                                  DY49     M_F_CPU0_CLK_DN<0>      
                                  DY51     M_F_CPU0_SA_CA<6>       
                                  DY53     M_F_CPU0_SA_DQ<31>      
                                  DY55     M_F_CPU0_SA_DQS_DP<8>   
                                  DY57     M_F_CPU0_SA_DQ<26>      
                                  DY59     M_G_CPU0_SA_DQ<23>      
                                  DY61     M_G_CPU0_SA_DQS_DP<7>   
                                  DY63     M_G_CPU0_SA_DQ<18>      
                                  DY65     M_F_CPU0_SA_DQ<15>      
                                  DY67     M_F_CPU0_SA_DQS_DP<6>   
                                  DY69     M_F_CPU0_SA_DQ<10>      
                                  DY71     M_G_CPU0_SA_DQ<7>       
                                  DY73     M_G_CPU0_SA_DQS_DP<5>   
                                  DY75     M_G_CPU0_SA_DQ<2>       
                                  DY77     GND                     
                                  DY79     M_H_CPU0_SA_DQ<0>       
                                  DY81     UPI_CPU1_CPU0_P3P3_DN<15>
                                  DY83     UPI_CPU1_CPU0_P3P3_DP<16>
                                  DY85     PVCCFA_EHV_FIVRA_CPU0   
                                  DY87     P5E_CPU0_PE3_TX_DN<2>   
                                  DY89     PVCCFA_EHV_FIVRA_CPU0   
                                  DY91     P5E_CPU0_PE3_RX_DN<3>   
                                  E5       GND                     
                                  E7       M_A_CPU0_SB_DQ<31>      
                                  E9       M_A_CPU0_SB_DQS_DP<8>   
                                  E11      M_A_CPU0_SB_DQ<26>      
                                  E13      M_B_CPU0_SB_DQ<29>      
                                  E15      M_B_CPU0_SB_DQS_DN<8>   
                                  E17      M_B_CPU0_SB_DQ<26>      
                                  E19      M_A_CPU0_SB_DQ<23>      
                                  E21      M_A_CPU0_SB_DQS_DP<7>   
                                  E23      M_A_CPU0_SB_DQ<18>      
                                  E25      M_A_CPU0_SB_DQ<15>      
                                  E27      M_A_CPU0_SB_DQS_DP<6>   
                                  E29      M_A_CPU0_SB_DQ<10>      
                                  E31      M_A_CPU0_SB_CB<3>       
                                  E33      M_A_CPU0_SB_DQS_DP<4>   
                                  E35      M_A_CPU0_SB_CB<6>       
                                  E37      M_A_CPU0_SB_CS_N<3>     
                                  E39      GND                     
                                  E41      M_A_CPU0_SB_CA<3>       
                                  E43      M_A_CPU0_SB_CA<0>       
                                  E45      M_A_CPU0_CLK_DP<1>      
                                  E48      M_A_CPU0_SA_PAR         
                                  E50      M_A_CPU0_SA_CA<5>       
                                  E52      GND                     
                                  E54      M_A_CPU0_SA_CS_N<2>     
                                  E56      M_A_CPU0_SA_CB<7>       
                                  E58      M_A_CPU0_SA_DQS_DP<9>   
                                  E60      M_A_CPU0_SA_CB<2>       
                                  E62      M_A_CPU0_SA_DQ<31>      
                                  E64      M_A_CPU0_SA_DQS_DP<8>   
                                  E66      M_A_CPU0_SA_DQ<26>      
                                  E68      M_A_CPU0_SA_DQ<23>      
                                  E70      M_A_CPU0_SA_DQS_DP<7>   
                                  E72      M_A_CPU0_SA_DQ<17>      
                                  E74      GND                     
                                  E76      GND                     
                                  E78      GND                     
                                  E80      UPI_CPU1_CPU0_P2P2_DN<23>
                                  E82      UPI_CPU1_CPU0_P2P2_DN<22>
                                  E84      UPI_CPU0_CPU1_P2P2_DN<22>
                                  E86      GND                     
                                  E88      UPI_CPU0_CPU1_P2P2_DP<21>
                                  EA1      UPI_CPU1_CPU0_P0P1_DN<3>
                                  EA3      PVCCFA_EHV_FIVRA_CPU0   
                                  EA5      UPI_CPU0_CPU1_P1P0_DP<2>
                                  EA7      PVCCFA_EHV_FIVRA_CPU0   
                                  EA9      P5E_CPU0_PE2_RX_DN<12>  
                                  EA11     PVCCFA_EHV_FIVRA_CPU0   
                                  EA13     P5E_CPU0_PE2_TX_DP<12>  
                                  EA15     PVCCFA_EHV_FIVRA_CPU0   
                                  EA17     M_F_CPU0_SB_DQ<28>      
                                  EA19     M_F_CPU0_SB_DQ<27>      
                                  EA21     GND                     
                                  EA23     M_G_CPU0_SB_DQ<22>      
                                  EA25     M_G_CPU0_SB_DQ<19>      
                                  EA27     GND                     
                                  EA29     M_F_CPU0_SB_DQ<6>       
                                  EA31     M_F_CPU0_SB_DQ<3>       
                                  EA33     GND                     
                                  EA35     M_G_CPU0_SB_CB<2>       
                                  EA37     M_G_CPU0_SB_CB<7>       
                                  EA39     GND                     
                                  EA41     M_G_CPU0_SB_CS_N<0>     
                                  EA43     M_G_CPU0_SB_CA<5>       
                                  EA45     GND                     
                                  EA48     M_G_CPU0_SA_RSP<0>      
                                  EA50     M_F_CPU0_SA_PAR         
                                  EA52     GND                     
                                  EA54     M_F_CPU0_SA_DQ<30>      
                                  EA56     M_F_CPU0_SA_DQ<27>      
                                  EA58     GND                     
                                  EA60     M_G_CPU0_SA_DQ<22>      
                                  EA62     M_G_CPU0_SA_DQ<19>      
                                  EA64     GND                     
                                  EA66     M_F_CPU0_SA_DQ<14>      
                                  EA68     M_F_CPU0_SA_DQ<11>      
                                  EA70     GND                     
                                  EA72     M_G_CPU0_SA_DQ<6>       
                                  EA74     M_G_CPU0_SA_DQ<3>       
                                  EA76     GND                     
                                  EA78     GND                     
                                  EA80     GND                     
                                  EA82     UPI_CPU1_CPU0_P3P3_DN<16>
                                  EA84     GND                     
                                  EA86     P5E_CPU0_PE3_TX_DP<2>   
                                  EA88     GND                     
                                  EA90     P5E_CPU0_PE3_RX_DP<3>   
                                  EB2      UPI_CPU1_CPU0_P0P1_DP<3>
                                  EB4      GND                     
                                  EB6      UPI_CPU0_CPU1_P1P0_DN<2>
                                  EB8      GND                     
                                  EB10     P5E_CPU0_PE2_RX_DP<12>  
                                  EB12     GND                     
                                  EB14     P5E_CPU0_PE2_TX_DP<13>  
                                  EB16     GND                     
                                  EB18     M_F_CPU0_SB_DQS_DP<8>   
                                  EB20     GND                     
                                  EB22     GND                     
                                  EB24     M_G_CPU0_SB_DQS_DN<7>   
                                  EB26     GND                     
                                  EB28     GND                     
                                  EB30     M_F_CPU0_SB_DQS_DN<5>   
                                  EB32     GND                     
                                  EB34     GND                     
                                  EB36     M_G_CPU0_SB_DQS_DN<4>   
                                  EB38     GND                     
                                  EB40     GND                     
                                  EB42     M_G_CPU0_SB_PAR         
                                  EB44     GND                     
                                  EB47     GND                     
                                  EB49     M_F_CPU0_CLK_DP<0>      
                                  EB51     GND                     
                                  EB53     GND                     
                                  EB55     M_F_CPU0_SA_DQS_DN<8>   
                                  EB57     GND                     
                                  EB59     GND                     
                                  EB61     M_G_CPU0_SA_DQS_DN<7>   
                                  EB63     GND                     
                                  EB65     GND                     
                                  EB67     M_F_CPU0_SA_DQS_DN<6>   
                                  EB69     GND                     
                                  EB71     GND                     
                                  EB73     M_G_CPU0_SA_DQS_DN<5>   
                                  EB75     GND                     
                                  EB77     M_F_CPU0_SA_DQ<0>       
                                  EB79     GND                     
                                  EB81     UPI_CPU1_CPU0_P3P3_DP<15>
                                  EB83     GND                     
                                  EB85     P5E_CPU0_PE3_TX_DN<1>   
                                  EB87     GND                     
                                  EB89     P5E_CPU0_PE3_RX_DP<2>   
                                  EB91     GND                     
                                  EC1      GND                     
                                  EC3      UPI_CPU1_CPU0_P0P1_DN<2>
                                  EC5      GND                     
                                  EC7      UPI_CPU0_CPU1_P1P0_DN<1>
                                  EC9      GND                     
                                  EC11     P5E_CPU0_PE2_RX_DP<13>  
                                  EC13     GND                     
                                  EC15     P5E_CPU0_PE2_TX_DN<13>  
                                  EC17     M_F_CPU0_SB_DQ<30>      
                                  EC19     GND                     
                                  EC21     M_F_CPU0_SB_DQS_DP<1>   
                                  EC23     GND                     
                                  EC25     GND                     
                                  EC27     M_E_CPU0_SB_DQS_DP<0>   
                                  EC29     GND                     
                                  EC31     GND                     
                                  EC33     M_F_CPU0_SB_DQS_DP<9>   
                                  EC35     GND                     
                                  EC37     GND                     
                                  EC39     M_F_CPU0_SB_CA<6>       
                                  EC41     GND                     
                                  EC43     GND                     
                                  EC45     M_E_CPU0_CLK_DP<1>      
                                  EC48     GND                     
                                  EC50     GND                     
                                  EC52     M_F_CPU0_SA_CA<0>       
                                  EC54     GND                     
                                  EC56     GND                     
                                  EC58     M_F_CPU0_SA_DQS_DP<4>   
                                  EC60     GND                     
                                  EC62     GND                     
                                  EC64     M_F_CPU0_SA_DQS_DN<2>   
                                  EC66     GND                     
                                  EC68     GND                     
                                  EC70     M_E_CPU0_SA_DQS_DN<1>   
                                  EC72     GND                     
                                  EC74     GND                     
                                  EC76     M_F_CPU0_SA_DQS_DP<0>   
                                  EC78     PVCCFA_EHV_FIVRA_CPU0   
                                  EC80     UPI_CPU1_CPU0_P3P3_DN<17>
                                  EC82     GND                     
                                  EC84     GND                     
                                  EC86     P5E_CPU0_PE3_TX_DP<1>   
                                  EC88     GND                     
                                  EC90     P5E_CPU0_PE3_RX_DN<2>   
                                  ED2      UPI_CPU1_CPU0_P0P1_DP<2>
                                  ED4      GND                     
                                  ED6      UPI_CPU0_CPU1_P1P0_DP<1>
                                  ED8      GND                     
                                  ED10     P5E_CPU0_PE2_RX_DN<13>  
                                  ED12     GND                     
                                  ED14     P5E_CPU0_PE2_TX_DN<14>  
                                  ED16     GND                     
                                  ED18     GND                     
                                  ED20     M_F_CPU0_SB_DQ<12>      
                                  ED22     M_F_CPU0_SB_DQ<9>       
                                  ED24     GND                     
                                  ED26     M_E_CPU0_SB_DQ<4>       
                                  ED28     M_E_CPU0_SB_DQ<1>       
                                  ED30     GND                     
                                  ED32     M_F_CPU0_SB_CB<0>       
                                  ED34     M_F_CPU0_SB_CB<5>       
                                  ED36     GND                     
                                  ED38     M_F_CPU0_SB_CS_N<2>     
                                  ED40     M_F_CPU0_SB_CA<4>       
                                  ED42     GND                     
                                  ED44     M_E_CPU0_SA_CA<6>       
                                  ED47     M_H_CPU0_SB_RSP<1>      
                                  ED49     GND                     
                                  ED51     M_F_CPU0_SA_CA<2>       
                                  ED53     M_F_CPU0_SA_CS_N<3>     
                                  ED55     GND                     
                                  ED57     M_F_CPU0_SA_CB<4>       
                                  ED59     M_F_CPU0_SA_CB<1>       
                                  ED61     GND                     
                                  ED63     M_F_CPU0_SA_DQ<20>      
                                  ED65     M_F_CPU0_SA_DQ<17>      
                                  ED67     GND                     
                                  ED69     M_E_CPU0_SA_DQ<12>      
                                  ED71     M_E_CPU0_SA_DQ<9>       
                                  ED73     GND                     
                                  ED75     M_F_CPU0_SA_DQ<4>       
                                  ED77     M_F_CPU0_SA_DQ<2>       
                                  ED79     PVCCFA_EHV_FIVRA_CPU0   
                                  ED81     UPI_CPU1_CPU0_P3P3_DP<17>
                                  ED83     UPI_CPU1_CPU0_P3P3_DN<18>
                                  ED85     PVCCFA_EHV_FIVRA_CPU0   
                                  ED87     P5E_CPU0_PE3_TX_DP<0>   
                                  ED89     PVCCFA_EHV_FIVRA_CPU0   
                                  ED91     P5E_CPU0_PE3_RX_DN<1>   
                                  EE3      UPI_CPU1_CPU0_P0P1_DN<1>
                                  EE5      UPI_CPU0_CPU1_P1P0_DP<0>
                                  EE7      PVCCFA_EHV_FIVRA_CPU0   
                                  EE9      P5E_CPU0_PE2_RX_DN<14>  
                                  EE11     PVCCFA_EHV_FIVRA_CPU0   
                                  EE13     P5E_CPU0_PE2_TX_DP<14>  
                                  EE15     PVCCFA_EHV_FIVRA_CPU0   
                                  EE17     GND                     
                                  EE19     M_F_CPU0_SB_DQ<13>      
                                  EE21     M_F_CPU0_SB_DQS_DN<1>   
                                  EE23     M_F_CPU0_SB_DQ<8>       
                                  EE25     M_E_CPU0_SB_DQ<5>       
                                  EE27     M_E_CPU0_SB_DQS_DN<0>   
                                  EE29     M_E_CPU0_SB_DQ<0>       
                                  EE31     M_F_CPU0_SB_CB<1>       
                                  EE33     M_F_CPU0_SB_DQS_DN<9>   
                                  EE35     M_F_CPU0_SB_CB<4>       
                                  EE37     M_F_CPU0_SB_CS_N<3>     
                                  EE39     GND                     
                                  EE41     M_F_CPU0_SB_CA<2>       
                                  EE43     M_E_CPU0_SA_PAR         
                                  EE45     M_E_CPU0_CLK_DN<1>      
                                  EE48     M_H_CPU0_SB_RSP<0>      
                                  EE50     M_F_CPU0_SA_CA<4>       
                                  EE52     GND                     
                                  EE54     M_F_CPU0_SA_CS_N<2>     
                                  EE56     M_F_CPU0_SA_CB<5>       
                                  EE58     M_F_CPU0_SA_DQS_DN<4>   
                                  EE60     M_F_CPU0_SA_CB<0>       
                                  EE62     M_F_CPU0_SA_DQ<21>      
                                  EE64     M_F_CPU0_SA_DQS_DP<2>   
                                  EE66     M_F_CPU0_SA_DQ<16>      
                                  EE68     M_E_CPU0_SA_DQ<13>      
                                  EE70     M_E_CPU0_SA_DQS_DP<1>   
                                  EE72     M_E_CPU0_SA_DQ<8>       
                                  EE74     M_F_CPU0_SA_DQ<5>       
                                  EE76     M_F_CPU0_SA_DQS_DN<0>   
                                  EE78     GND                     
                                  EE80     GND                     
                                  EE82     UPI_CPU1_CPU0_P3P3_DP<19>
                                  EE84     PVCCFA_EHV_FIVRA_CPU0   
                                  EE86     P5E_CPU0_PE3_TX_DN<0>   
                                  EE88     GND                     
                                  EE90     P5E_CPU0_PE3_RX_DP<1>   
                                  EF2      GND                     
                                  EF4      GND                     
                                  EF6      UPI_CPU0_CPU1_P1P0_DN<0>
                                  EF8      GND                     
                                  EF10     P5E_CPU0_PE2_RX_DP<14>  
                                  EF12     GND                     
                                  EF14     P5E_CPU0_PE2_TX_DP<15>  
                                  EF16     GND                     
                                  EF18     GND                     
                                  EF20     GND                     
                                  EF22     GND                     
                                  EF24     GND                     
                                  EF26     GND                     
                                  EF28     GND                     
                                  EF30     GND                     
                                  EF32     GND                     
                                  EF34     GND                     
                                  EF36     GND                     
                                  EF38     GND                     
                                  EF40     GND                     
                                  EF42     GND                     
                                  EF44     GND                     
                                  EF47     GND                     
                                  EF49     GND                     
                                  EF51     GND                     
                                  EF53     GND                     
                                  EF55     GND                     
                                  EF57     GND                     
                                  EF59     GND                     
                                  EF61     GND                     
                                  EF63     GND                     
                                  EF65     GND                     
                                  EF67     GND                     
                                  EF69     GND                     
                                  EF71     GND                     
                                  EF73     GND                     
                                  EF75     GND                     
                                  EF77     GND                     
                                  EF79     PVCCFA_EHV_FIVRA_CPU0   
                                  EF81     UPI_CPU1_CPU0_P3P3_DN<19>
                                  EF83     UPI_CPU1_CPU0_P3P3_DP<18>
                                  EF85     GND                     
                                  EF87     GND                     
                                  EF89     GND                     
                                  EG3      UPI_CPU1_CPU0_P0P1_DP<1>
                                  EG5      GND                     
                                  EG7      GND                     
                                  EG9      GND                     
                                  EG11     P5E_CPU0_PE2_RX_DP<15>  
                                  EG13     GND                     
                                  EG15     P5E_CPU0_PE2_TX_DN<15>  
                                  EG19     M_F_CPU0_SB_DQ<15>      
                                  EG21     M_F_CPU0_SB_DQS_DP<6>   
                                  EG23     M_F_CPU0_SB_DQ<10>      
                                  EG25     M_E_CPU0_SB_DQ<7>       
                                  EG27     M_E_CPU0_SB_DQS_DP<5>   
                                  EG29     M_E_CPU0_SB_DQ<2>       
                                  EG31     M_F_CPU0_SB_CB<3>       
                                  EG33     M_F_CPU0_SB_DQS_DP<4>   
                                  EG35     M_F_CPU0_SB_CB<6>       
                                  EG37     M_F_CPU0_SB_CS_N<1>     
                                  EG39     GND                     
                                  EG41     M_F_CPU0_SB_CA<3>       
                                  EG43     M_E_CPU0_SB_CA<0>       
                                  EG45     M_E_CPU0_CLK_DP<0>      
                                  EG48     M_H_CPU0_SA_RSP<0>      
                                  EG50     M_F_CPU0_SA_CA<5>       
                                  EG52     GND                     
                                  EG54     M_F_CPU0_SA_CS_N<0>     
                                  EG56     M_F_CPU0_SA_CB<7>       
                                  EG58     M_F_CPU0_SA_DQS_DP<9>   
                                  EG60     M_F_CPU0_SA_CB<2>       
                                  EG62     M_F_CPU0_SA_DQ<23>      
                                  EG64     M_F_CPU0_SA_DQS_DP<7>   
                                  EG66     M_F_CPU0_SA_DQ<18>      
                                  EG68     M_E_CPU0_SA_DQ<15>      
                                  EG70     M_E_CPU0_SA_DQS_DP<6>   
                                  EG72     M_E_CPU0_SA_DQ<10>      
                                  EG74     M_F_CPU0_SA_DQ<7>       
                                  EG76     M_F_CPU0_SA_DQS_DP<5>   
                                  EG78     M_F_CPU0_SA_DQ<3>       
                                  EG80     PVCCFA_EHV_FIVRA_CPU0   
                                  EG82     GND                     
                                  EG84     GND                     
                                  EG86     GND                     
                                  EG88     GND                     
                                  EG90     GND                     
                                  EH2      UPI_CPU1_CPU0_P0P1_DN<0>
                                  EH4      GND                     
                                  EH6      GND                     
                                  EH8      M_G_CPU0_SB_DQ<25>      
                                  EH10     P5E_CPU0_PE2_RX_DN<15>  
                                  EH12     GND                     
                                  EH14     GND                     
                                  EH16     GND                     
                                  EH18     GND                     
                                  EH20     M_F_CPU0_SB_DQ<14>      
                                  EH22     M_F_CPU0_SB_DQ<11>      
                                  EH24     GND                     
                                  EH26     M_E_CPU0_SB_DQ<6>       
                                  EH28     M_E_CPU0_SB_DQ<3>       
                                  EH30     GND                     
                                  EH32     M_F_CPU0_SB_CB<2>       
                                  EH34     M_F_CPU0_SB_CB<7>       
                                  EH36     GND                     
                                  EH38     M_F_CPU0_SB_CS_N<0>     
                                  EH40     M_F_CPU0_SB_CA<5>       
                                  EH42     GND                     
                                  EH44     M_E_CPU0_SB_CA<1>       
                                  EH47     M_H_CPU0_SA_RSP<1>      
                                  EH49     GND                     
                                  EH51     M_F_CPU0_SA_CA<3>       
                                  EH53     M_F_CPU0_SA_CS_N<1>     
                                  EH55     GND                     
                                  EH57     M_F_CPU0_SA_CB<6>       
                                  EH59     M_F_CPU0_SA_CB<3>       
                                  EH61     GND                     
                                  EH63     M_F_CPU0_SA_DQ<22>      
                                  EH65     M_F_CPU0_SA_DQ<19>      
                                  EH67     GND                     
                                  EH69     M_E_CPU0_SA_DQ<14>      
                                  EH71     M_E_CPU0_SA_DQ<11>      
                                  EH73     GND                     
                                  EH75     M_F_CPU0_SA_DQ<6>       
                                  EH77     M_F_CPU0_SA_DQ<1>       
                                  EH79     GND                     
                                  EH81     GND                     
                                  EH83     GND                     
                                  EH85     UPI_CPU0_CPU1_P3P3_DN<23>
                                  EH87     UPI_CPU0_CPU1_P3P3_DP<19>
                                  EH89     P5E_CPU0_PE3_RX_DN<0>   
                                  EJ3      UPI_CPU1_CPU0_P0P1_DP<0>
                                  EJ5      M_G_CPU0_SB_DQ<29>      
                                  EJ7      GND                     
                                  EJ9      GND                     
                                  EJ11     GND                     
                                  EJ13     GND                     
                                  EJ15     PVCCFA_EHV_FIVRA_CPU0   
                                  EJ17     GND                     
                                  EJ19     GND                     
                                  EJ21     M_F_CPU0_SB_DQS_DN<6>   
                                  EJ23     GND                     
                                  EJ25     GND                     
                                  EJ27     M_E_CPU0_SB_DQS_DN<5>   
                                  EJ29     GND                     
                                  EJ31     GND                     
                                  EJ33     M_F_CPU0_SB_DQS_DN<4>   
                                  EJ35     GND                     
                                  EJ37     GND                     
                                  EJ39     M_F_CPU0_SB_PAR         
                                  EJ41     GND                     
                                  EJ43     GND                     
                                  EJ45     M_E_CPU0_CLK_DN<0>      
                                  EJ48     GND                     
                                  EJ50     GND                     
                                  EJ52     M_F_CPU0_SA_CA<1>       
                                  EJ54     GND                     
                                  EJ56     GND                     
                                  EJ58     M_F_CPU0_SA_DQS_DN<9>   
                                  EJ60     GND                     
                                  EJ62     GND                     
                                  EJ64     M_F_CPU0_SA_DQS_DN<7>   
                                  EJ66     GND                     
                                  EJ68     GND                     
                                  EJ70     M_E_CPU0_SA_DQS_DN<6>   
                                  EJ72     GND                     
                                  EJ74     GND                     
                                  EJ76     M_F_CPU0_SA_DQS_DN<5>   
                                  EJ78     GND                     
                                  EJ80     UPI_CPU1_CPU0_P3P3_DN<23>
                                  EJ82     UPI_CPU1_CPU0_P3P3_DP<20>
                                  EJ84     PVCCFA_EHV_FIVRA_CPU0   
                                  EJ86     UPI_CPU0_CPU1_P3P3_DN<19>
                                  EJ88     GND                     
                                  EJ90     P5E_CPU0_PE3_RX_DP<0>   
                                  EK2      GND                     
                                  EK4      GND                     
                                  EK6      M_G_CPU0_SB_DQ<28>      
                                  EK8      M_G_CPU0_SB_DQ<24>      
                                  EK10     GND                     
                                  EK12     M_F_CPU0_SB_DQS_DP<2>   
                                  EK14     GND                     
                                  EK16     GND                     
                                  EK18     M_E_CPU0_SB_DQS_DN<3>   
                                  EK20     GND                     
                                  EK22     GND                     
                                  EK24     M_E_CPU0_SB_DQS_DN<2>   
                                  EK26     GND                     
                                  EK28     GND                     
                                  EK30     M_E_CPU0_SB_DQS_DN<1>   
                                  EK32     GND                     
                                  EK34     GND                     
                                  EK36     M_E_CPU0_SB_DQS_DN<9>   
                                  EK38     GND                     
                                  EK40     GND                     
                                  EK42     M_E_CPU0_SB_CA<6>       
                                  EK44     GND                     
                                  EK47     GND                     
                                  EK49     M_E_CPU0_SA_CA<2>       
                                  EK51     GND                     
                                  EK53     GND                     
                                  EK55     M_E_CPU0_SA_DQS_DP<4>   
                                  EK57     GND                     
                                  EK59     GND                     
                                  EK61     M_E_CPU0_SA_DQS_DN<3>   
                                  EK63     GND                     
                                  EK65     GND                     
                                  EK67     M_E_CPU0_SA_DQS_DN<2>   
                                  EK69     GND                     
                                  EK71     GND                     
                                  EK73     M_E_CPU0_SA_DQ<5>       
                                  EK75     GND                     
                                  EK77     GND                     
                                  EK79     GND                     
                                  EK81     UPI_CPU1_CPU0_P3P3_DN<20>
                                  EK83     GND                     
                                  EK85     UPI_CPU0_CPU1_P3P3_DP<23>
                                  EK87     UPI_CPU0_CPU1_P3P3_DP<18>
                                  EK89     GND                     
                                  EL3      GND                     
                                  EL5      GND                     
                                  EL7      GND                     
                                  EL9      GND                     
                                  EL11     M_F_CPU0_SB_DQ<20>      
                                  EL13     M_F_CPU0_SB_DQ<17>      
                                  EL15     GND                     
                                  EL17     M_E_CPU0_SB_DQ<28>      
                                  EL19     M_E_CPU0_SB_DQ<25>      
                                  EL21     GND                     
                                  EL23     M_E_CPU0_SB_DQ<20>      
                                  EL25     M_E_CPU0_SB_DQ<17>      
                                  EL27     GND                     
                                  EL29     M_E_CPU0_SB_DQ<12>      
                                  EL31     M_E_CPU0_SB_DQ<9>       
                                  EL33     GND                     
                                  EL35     M_E_CPU0_SB_CB<0>       
                                  EL37     M_E_CPU0_SB_CB<5>       
                                  EL39     GND                     
                                  EL41     M_E_CPU0_SB_CS_N<3>     
                                  EL43     M_E_CPU0_SB_CA<4>       
                                  EL45     GND                     
                                  EL48     M_E_CPU0_SA_CA<3>       
                                  EL50     M_E_CPU0_SA_CS_N<3>     
                                  EL52     GND                     
                                  EL54     M_E_CPU0_SA_CB<4>       
                                  EL56     M_E_CPU0_SA_CB<1>       
                                  EL58     GND                     
                                  EL60     M_E_CPU0_SA_DQ<28>      
                                  EL62     M_E_CPU0_SA_DQ<25>      
                                  EL64     GND                     
                                  EL66     M_E_CPU0_SA_DQ<22>      
                                  EL68     M_E_CPU0_SA_DQS_DP<2>   
                                  EL70     GND                     
                                  EL72     GND                     
                                  EL74     M_E_CPU0_SA_DQ<4>       
                                  EL76     GND                     
                                  EL78     M_E_CPU0_SA_DQ<0>       
                                  EL80     UPI_CPU1_CPU0_P3P3_DP<23>
                                  EL82     UPI_CPU1_CPU0_P3P3_DN<21>
                                  EL84     UPI_CPU0_CPU1_P3P3_DN<22>
                                  EL86     GND                     
                                  EL88     UPI_CPU0_CPU1_P3P3_DN<18>
                                  EM4      M_G_CPU0_SB_DQ<31>      
                                  EM6      M_G_CPU0_SB_DQS_DN<8>   
                                  EM8      GND                     
                                  EM10     M_F_CPU0_SB_DQ<21>      
                                  EM12     M_F_CPU0_SB_DQS_DN<2>   
                                  EM14     M_F_CPU0_SB_DQ<16>      
                                  EM16     M_E_CPU0_SB_DQ<29>      
                                  EM18     M_E_CPU0_SB_DQS_DP<3>   
                                  EM20     M_E_CPU0_SB_DQ<24>      
                                  EM22     M_E_CPU0_SB_DQ<21>      
                                  EM24     M_E_CPU0_SB_DQS_DP<2>   
                                  EM26     M_E_CPU0_SB_DQ<16>      
                                  EM28     M_E_CPU0_SB_DQ<13>      
                                  EM30     M_E_CPU0_SB_DQS_DP<1>   
                                  EM32     M_E_CPU0_SB_DQ<8>       
                                  EM34     M_E_CPU0_SB_CB<1>       
                                  EM36     M_E_CPU0_SB_DQS_DP<9>   
                                  EM38     M_E_CPU0_SB_CB<4>       
                                  EM40     M_E_CPU0_SB_CS_N<2>     
                                  EM42     GND                     
                                  EM44     M_E_CPU0_SB_CA<2>       
                                  EM47     M_E_CPU0_SA_CA<4>       
                                  EM49     GND                     
                                  EM51     M_E_CPU0_SA_CS_N<2>     
                                  EM53     M_E_CPU0_SA_CB<5>       
                                  EM55     M_E_CPU0_SA_DQS_DN<4>   
                                  EM57     M_E_CPU0_SA_CB<0>       
                                  EM59     M_E_CPU0_SA_DQ<29>      
                                  EM61     M_E_CPU0_SA_DQS_DP<3>   
                                  EM63     M_E_CPU0_SA_DQ<24>      
                                  EM65     M_E_CPU0_SA_DQ<21>      
                                  EM67     M_E_CPU0_SA_DQS_DP<7>   
                                  EM69     M_E_CPU0_SA_DQ<17>      
                                  EM71     M_E_CPU0_SA_DQ<16>      
                                  EM73     GND                     
                                  EM75     M_E_CPU0_SA_DQS_DN<5>   
                                  EM77     M_E_CPU0_SA_DQ<1>       
                                  EM79     GND                     
                                  EM81     GND                     
                                  EM83     GND                     
                                  EM85     UPI_CPU0_CPU1_P3P3_DP<22>
                                  EM87     UPI_CPU0_CPU1_P3P3_DP<20>
                                  EN5      M_G_CPU0_SB_DQS_DP<8>   
                                  EN7      M_G_CPU0_SB_DQS_DP<3>   
                                  EN9      GND                     
                                  EN11     GND                     
                                  EN13     GND                     
                                  EN15     GND                     
                                  EN17     GND                     
                                  EN19     GND                     
                                  EN21     GND                     
                                  EN23     GND                     
                                  EN25     GND                     
                                  EN27     GND                     
                                  EN29     GND                     
                                  EN31     GND                     
                                  EN33     GND                     
                                  EN35     GND                     
                                  EN37     GND                     
                                  EN39     GND                     
                                  EN41     GND                     
                                  EN43     GND                     
                                  EN45     GND                     
                                  EN48     GND                     
                                  EN50     GND                     
                                  EN52     GND                     
                                  EN54     GND                     
                                  EN56     GND                     
                                  EN58     GND                     
                                  EN60     GND                     
                                  EN62     GND                     
                                  EN64     GND                     
                                  EN66     GND                     
                                  EN68     M_E_CPU0_SA_DQS_DN<7>   
                                  EN70     M_E_CPU0_SA_DQ<18>      
                                  EN72     GND                     
                                  EN74     M_E_CPU0_SA_DQS_DP<5>   
                                  EN76     M_E_CPU0_SA_DQS_DP<0>   
                                  EN78     GND                     
                                  EN80     GND                     
                                  EN82     UPI_CPU1_CPU0_P3P3_DP<21>
                                  EN84     PVCCFA_EHV_FIVRA_CPU0   
                                  EN86     UPI_CPU0_CPU1_P3P3_DP<21>
                                  EN88     GND                     
                                  EP4      M_G_CPU0_SB_DQ<30>      
                                  EP6      M_G_CPU0_SB_DQS_DN<3>   
                                  EP8      M_G_CPU0_SB_DQ<26>      
                                  EP10     M_F_CPU0_SB_DQ<23>      
                                  EP12     M_F_CPU0_SB_DQS_DP<7>   
                                  EP14     M_F_CPU0_SB_DQ<18>      
                                  EP16     M_E_CPU0_SB_DQ<31>      
                                  EP18     M_E_CPU0_SB_DQS_DP<8>   
                                  EP20     M_E_CPU0_SB_DQ<26>      
                                  EP22     M_E_CPU0_SB_DQ<23>      
                                  EP24     M_E_CPU0_SB_DQS_DP<7>   
                                  EP26     M_E_CPU0_SB_DQ<18>      
                                  EP28     M_E_CPU0_SB_DQ<15>      
                                  EP30     M_E_CPU0_SB_DQS_DP<6>   
                                  EP32     M_E_CPU0_SB_DQ<10>      
                                  EP34     M_E_CPU0_SB_CB<3>       
                                  EP36     M_E_CPU0_SB_DQS_DP<4>   
                                  EP38     M_E_CPU0_SB_CB<6>       
                                  EP40     M_E_CPU0_SB_CS_N<0>     
                                  EP42     M_E_CPU0_SB_PAR         
                                  EP44     M_E_CPU0_SB_CA<3>       
                                  EP47     M_E_CPU0_SA_CA<5>       
                                  EP49     M_E_CPU0_SA_CA<0>       
                                  EP51     M_E_CPU0_SA_CS_N<0>     
                                  EP53     M_E_CPU0_SA_CB<7>       
                                  EP55     M_E_CPU0_SA_DQS_DP<9>   
                                  EP57     M_E_CPU0_SA_CB<2>       
                                  EP59     M_E_CPU0_SA_DQ<31>      
                                  EP61     M_E_CPU0_SA_DQS_DP<8>   
                                  EP63     M_E_CPU0_SA_DQ<26>      
                                  EP65     M_E_CPU0_SA_DQ<23>      
                                  EP67     GND                     
                                  EP69     GND                     
                                  EP71     GND                     
                                  EP73     M_E_CPU0_SA_DQ<6>       
                                  EP75     M_E_CPU0_SA_DQS_DN<0>   
                                  EP77     GND                     
                                  EP79     M_E_CPU0_SA_DQ<2>       
                                  EP81     UPI_CPU1_CPU0_P3P3_DN<22>
                                  EP83     GND                     
                                  EP85     UPI_CPU0_CPU1_P3P3_DN<21>
                                  EP87     UPI_CPU0_CPU1_P3P3_DN<20>
                                  ER5      GND                     
                                  ER7      GND                     
                                  ER9      GND                     
                                  ER11     M_F_CPU0_SB_DQ<22>      
                                  ER13     M_F_CPU0_SB_DQ<19>      
                                  ER15     GND                     
                                  ER17     M_E_CPU0_SB_DQ<30>      
                                  ER19     M_E_CPU0_SB_DQ<27>      
                                  ER21     GND                     
                                  ER23     M_E_CPU0_SB_DQ<22>      
                                  ER25     M_E_CPU0_SB_DQ<19>      
                                  ER27     GND                     
                                  ER29     M_E_CPU0_SB_DQ<14>      
                                  ER31     M_E_CPU0_SB_DQ<11>      
                                  ER33     GND                     
                                  ER35     M_E_CPU0_SB_CB<2>       
                                  ER37     M_E_CPU0_SB_CB<7>       
                                  ER39     GND                     
                                  ER41     GND                     
                                  ER43     GND                     
                                  ER48     GND                     
                                  ER50     GND                     
                                  ER52     GND                     
                                  ER54     M_E_CPU0_SA_CB<6>       
                                  ER56     M_E_CPU0_SA_CB<3>       
                                  ER58     GND                     
                                  ER60     M_E_CPU0_SA_DQ<30>      
                                  ER62     M_E_CPU0_SA_DQ<27>      
                                  ER64     GND                     
                                  ER66     M_E_CPU0_SA_DQ<20>      
                                  ER68     M_E_CPU0_SA_DQ<19>      
                                  ER70     GND                     
                                  ER72     M_E_CPU0_SA_DQ<7>       
                                  ER74     GND                     
                                  ER76     M_E_CPU0_SA_DQ<3>       
                                  ER78     GND                     
                                  ER80     GND                     
                                  ER82     UPI_CPU1_CPU0_P3P3_DP<22>
                                  ER84     GND                     
                                  ER86     GND                     
                                  ET8      M_G_CPU0_SB_DQ<27>      
                                  ET10     GND                     
                                  ET12     M_F_CPU0_SB_DQS_DN<7>   
                                  ET14     GND                     
                                  ET16     GND                     
                                  ET18     M_E_CPU0_SB_DQS_DN<8>   
                                  ET20     GND                     
                                  ET22     GND                     
                                  ET24     M_E_CPU0_SB_DQS_DN<7>   
                                  ET26     GND                     
                                  ET28     GND                     
                                  ET30     M_E_CPU0_SB_DQS_DN<6>   
                                  ET32     GND                     
                                  ET34     GND                     
                                  ET36     M_E_CPU0_SB_DQS_DN<4>   
                                  ET38     GND                     
                                  ET40     M_E_CPU0_SB_CS_N<1>     
                                  ET42     M_E_CPU0_SB_CA<5>       
                                  ET49     M_E_CPU0_SA_CA<1>       
                                  ET51     M_E_CPU0_SA_CS_N<1>     
                                  ET53     GND                     
                                  ET55     M_E_CPU0_SA_DQS_DN<9>   
                                  ET57     GND                     
                                  ET59     GND                     
                                  ET61     M_E_CPU0_SA_DQS_DN<8>   
                                  F4       GND                     
                                  F6       GND                     
                                  F8       M_A_CPU0_SB_DQ<30>      
                                  F10      M_A_CPU0_SB_DQ<27>      
                                  F12      GND                     
                                  F14      M_B_CPU0_SB_DQ<31>      
                                  F16      M_B_CPU0_SB_DQ<27>      
                                  F18      GND                     
                                  F20      M_A_CPU0_SB_DQ<22>      
                                  F22      M_A_CPU0_SB_DQ<19>      
                                  F24      GND                     
                                  F26      M_A_CPU0_SB_DQ<14>      
                                  F28      M_A_CPU0_SB_DQ<11>      
                                  F30      GND                     
                                  F32      M_A_CPU0_SB_CB<2>       
                                  F34      M_A_CPU0_SB_CB<7>       
                                  F36      GND                     
                                  F38      M_A_CPU0_SB_CS_N<2>     
                                  F40      M_A_CPU0_SB_CA<5>       
                                  F42      GND                     
                                  F44      M_A_CPU0_SB_CA<1>       
                                  F47      PWRGD_DRAMPWRGD_CPU0_CD_LVC1_R
                                  F49      GND                     
                                  F51      M_A_CPU0_SA_CA<3>       
                                  F53      M_A_CPU0_SA_CS_N<3>     
                                  F55      GND                     
                                  F57      M_A_CPU0_SA_CB<6>       
                                  F59      M_A_CPU0_SA_CB<3>       
                                  F61      GND                     
                                  F63      M_A_CPU0_SA_DQ<30>      
                                  F65      M_A_CPU0_SA_DQ<27>      
                                  F67      GND                     
                                  F69      M_A_CPU0_SA_DQ<22>      
                                  F71      M_A_CPU0_SA_DQ<19>      
                                  F73      GND                     
                                  F75      M_A_CPU0_SA_DQ<7>       
                                  F77      M_A_CPU0_SA_DQS_DP<5>   
                                  F79      GND                     
                                  F81      UPI_CPU1_CPU0_P2P2_DP<22>
                                  F83      GND                     
                                  F85      UPI_CPU0_CPU1_P2P2_DP<22>
                                  F87      UPI_CPU0_CPU1_P2P2_DN<20>
                                  F89      GND                     
                                  G3       GND                     
                                  G7       GND                     
                                  G9       M_A_CPU0_SB_DQS_DN<8>   
                                  G11      GND                     
                                  G13      GND                     
                                  G15      M_B_CPU0_SB_DQS_DP<8>   
                                  G17      GND                     
                                  G19      GND                     
                                  G21      M_A_CPU0_SB_DQS_DN<7>   
                                  G23      GND                     
                                  G25      GND                     
                                  G27      M_A_CPU0_SB_DQS_DN<6>   
                                  G29      GND                     
                                  G31      GND                     
                                  G33      M_A_CPU0_SB_DQS_DN<4>   
                                  G35      GND                     
                                  G37      GND                     
                                  G39      M_A_CPU0_SB_PAR         
                                  G41      GND                     
                                  G43      GND                     
                                  G45      M_A_CPU0_CLK_DN<1>      
                                  G48      GND                     
                                  G50      GND                     
                                  G52      M_A_CPU0_SA_CA<1>       
                                  G54      GND                     
                                  G56      GND                     
                                  G58      M_A_CPU0_SA_DQS_DN<9>   
                                  G60      GND                     
                                  G62      GND                     
                                  G64      M_A_CPU0_SA_DQS_DN<8>   
                                  G66      GND                     
                                  G68      GND                     
                                  G70      M_A_CPU0_SA_DQS_DN<7>   
                                  G72      GND                     
                                  G74      GND                     
                                  G76      M_A_CPU0_SA_DQ<6>       
                                  G78      M_A_CPU0_SA_DQ<3>       
                                  G80      UPI_CPU1_CPU0_P2P2_DP<23>
                                  G82      UPI_CPU1_CPU0_P2P2_DN<21>
                                  G84      GND                     
                                  G86      UPI_CPU0_CPU1_P2P2_DP<19>
                                  G88      GND                     
                                  G90      GND                     
                                  H2       GND                     
                                  H4       GND                     
                                  H6       GND                     
                                  H8       GND                     
                                  H10      GND                     
                                  H14      GND                     
                                  H16      GND                     
                                  H18      M_B_CPU0_SB_DQS_DN<2>   
                                  H20      GND                     
                                  H22      GND                     
                                  H24      M_B_CPU0_SB_DQS_DN<1>   
                                  H26      GND                     
                                  H28      GND                     
                                  H30      M_A_CPU0_SB_DQS_DN<0>   
                                  H32      GND                     
                                  H34      GND                     
                                  H36      M_B_CPU0_SB_DQS_DP<9>   
                                  H38      GND                     
                                  H40      GND                     
                                  H42      M_B_CPU0_SB_CA<6>       
                                  H44      GND                     
                                  H47      GND                     
                                  H49      M_B_CPU0_SA_CA<0>       
                                  H51      GND                     
                                  H53      GND                     
                                  H55      M_B_CPU0_SA_DQS_DN<4>   
                                  H57      GND                     
                                  H59      GND                     
                                  H61      M_B_CPU0_SA_DQS_DN<2>   
                                  H63      GND                     
                                  H65      GND                     
                                  H67      M_A_CPU0_SA_DQS_DN<1>   
                                  H69      GND                     
                                  H71      GND                     
                                  H73      M_B_CPU0_SA_DQS_DN<0>   
                                  H75      GND                     
                                  H77      M_A_CPU0_SA_DQS_DN<5>   
                                  H79      GND                     
                                  H81      GND                     
                                  H83      UPI_CPU1_CPU0_P2P2_DP<21>
                                  H85      UPI_CPU0_CPU1_P2P2_DN<19>
                                  H87      UPI_CPU0_CPU1_P2P2_DP<20>
                                  H89      PVCCFA_EHV_FIVRA_CPU0   
                                  J3       UPI_CPU0_CPU1_P0P1_DP<0>
                                  J5       GND                     
                                  J7       PVCCFA_EHV_FIVRA_CPU0   
                                  J9       GND                     
                                  J11      PVCCFA_EHV_FIVRA_CPU0   
                                  J15      GND                     
                                  J17      M_B_CPU0_SB_DQ<20>      
                                  J19      M_B_CPU0_SB_DQ<17>      
                                  J21      GND                     
                                  J23      M_B_CPU0_SB_DQ<12>      
                                  J25      M_B_CPU0_SB_DQ<9>       
                                  J27      GND                     
                                  J29      M_A_CPU0_SB_DQ<4>       
                                  J31      M_A_CPU0_SB_DQ<1>       
                                  J33      GND                     
                                  J35      M_B_CPU0_SB_CB<0>       
                                  J37      M_B_CPU0_SB_CB<5>       
                                  J39      GND                     
                                  J41      M_B_CPU0_SB_CS_N<0>     
                                  J43      M_B_CPU0_SB_CA<4>       
                                  J45      GND                     
                                  J48      M_B_CPU0_SA_CA<2>       
                                  J50      M_B_CPU0_SA_CS_N<1>     
                                  J52      GND                     
                                  J54      M_B_CPU0_SA_CB<4>       
                                  J56      M_B_CPU0_SA_CB<1>       
                                  J58      GND                     
                                  J60      M_B_CPU0_SA_DQ<20>      
                                  J62      M_B_CPU0_SA_DQ<17>      
                                  J64      GND                     
                                  J66      M_A_CPU0_SA_DQ<12>      
                                  J68      M_A_CPU0_SA_DQ<9>       
                                  J70      GND                     
                                  J72      M_B_CPU0_SA_DQ<4>       
                                  J74      M_B_CPU0_SA_DQ<1>       
                                  J76      GND                     
                                  J78      GND                     
                                  J80      PVCCFA_EHV_FIVRA_CPU0   
                                  J82      UPI_CPU1_CPU0_P2P2_DN<19>
                                  J84      GND                     
                                  J86      GND                     
                                  J88      GND                     
                                  J90      P5E_CPU0_PE4_RX_DN<15>  
                                  K2       GND                     
                                  K4       UPI_CPU0_CPU1_P0P1_DN<0>
                                  K6       UPI_CPU1_CPU0_P1P0_DN<0>
                                  K8       GND                     
                                  K10      P5E_CPU0_PE0_RX_DN<15>  
                                  K12      GND                     
                                  K14      GND                     
                                  K16      M_B_CPU0_SB_DQ<21>      
                                  K18      M_B_CPU0_SB_DQS_DP<2>   
                                  K20      M_B_CPU0_SB_DQ<16>      
                                  K22      M_B_CPU0_SB_DQ<13>      
                                  K24      M_B_CPU0_SB_DQS_DP<1>   
                                  K26      M_B_CPU0_SB_DQ<8>       
                                  K28      M_A_CPU0_SB_DQ<5>       
                                  K30      M_A_CPU0_SB_DQS_DP<0>   
                                  K32      M_A_CPU0_SB_DQ<0>       
                                  K34      M_B_CPU0_SB_CB<1>       
                                  K36      M_B_CPU0_SB_DQS_DN<9>   
                                  K38      M_B_CPU0_SB_CB<4>       
                                  K40      M_B_CPU0_SB_CS_N<1>     
                                  K42      GND                     
                                  K44      M_B_CPU0_SB_CA<2>       
                                  K47      M_B_CPU0_SA_CA<4>       
                                  K49      GND                     
                                  K51      M_B_CPU0_SA_CS_N<0>     
                                  K53      M_B_CPU0_SA_CB<5>       
                                  K55      M_B_CPU0_SA_DQS_DP<4>   
                                  K57      M_B_CPU0_SA_CB<0>       
                                  K59      M_B_CPU0_SA_DQ<21>      
                                  K61      M_B_CPU0_SA_DQS_DP<2>   
                                  K63      M_B_CPU0_SA_DQ<16>      
                                  K65      M_A_CPU0_SA_DQ<13>      
                                  K67      M_A_CPU0_SA_DQS_DP<1>   
                                  K69      M_A_CPU0_SA_DQ<8>       
                                  K71      M_B_CPU0_SA_DQ<5>       
                                  K73      M_B_CPU0_SA_DQS_DP<0>   
                                  K75      M_B_CPU0_SA_DQ<0>       
                                  K77      GND                     
                                  K79      UPI_CPU1_CPU0_P2P2_DN<20>
                                  K81      UPI_CPU1_CPU0_P2P2_DP<18>
                                  K83      GND                     
                                  K85      GND                     
                                  K87      PVCCFA_EHV_FIVRA_CPU0   
                                  K89      P5E_CPU0_PE4_RX_DP<15>  
                                  L3       UPI_CPU0_CPU1_P0P1_DP<1>
                                  L5       GND                     
                                  L7       UPI_CPU1_CPU0_P1P0_DP<0>
                                  L9       GND                     
                                  L11      P5E_CPU0_PE0_RX_DP<15>  
                                  L13      GND                     
                                  L15      GND                     
                                  L17      GND                     
                                  L19      GND                     
                                  L21      GND                     
                                  L23      GND                     
                                  L25      GND                     
                                  L27      GND                     
                                  L29      GND                     
                                  L31      GND                     
                                  L33      GND                     
                                  L35      GND                     
                                  L37      GND                     
                                  L39      GND                     
                                  L41      GND                     
                                  L43      GND                     
                                  L45      GND                     
                                  L48      GND                     
                                  L50      GND                     
                                  L52      GND                     
                                  L54      GND                     
                                  L56      GND                     
                                  L58      GND                     
                                  L60      GND                     
                                  L62      GND                     
                                  L64      GND                     
                                  L66      GND                     
                                  L68      GND                     
                                  L70      GND                     
                                  L72      GND                     
                                  L74      GND                     
                                  L76      GND                     
                                  L78      GND                     
                                  L80      UPI_CPU1_CPU0_P2P2_DN<18>
                                  L82      UPI_CPU1_CPU0_P2P2_DP<19>
                                  L84      PVCCFA_EHV_FIVRA_CPU0   
                                  L86      P5E_CPU0_PE4_TX_DN<15>  
                                  L88      GND                     
                                  L90      GND                     
                                  M2       UPI_CPU0_CPU1_P0P1_DN<1>
                                  M4       GND                     
                                  M6       UPI_CPU1_CPU0_P1P0_DP<1>
                                  M8       GND                     
                                  M10      P5E_CPU0_PE0_RX_DN<14>  
                                  M12      GND                     
                                  M14      P5E_CPU0_PE0_TX_DP<15>  
                                  M16      M_B_CPU0_SB_DQ<23>      
                                  M18      M_B_CPU0_SB_DQS_DN<7>   
                                  M20      M_B_CPU0_SB_DQ<18>      
                                  M22      M_B_CPU0_SB_DQ<15>      
                                  M24      M_B_CPU0_SB_DQS_DN<6>   
                                  M26      M_B_CPU0_SB_DQ<10>      
                                  M28      M_A_CPU0_SB_DQ<7>       
                                  M30      M_A_CPU0_SB_DQS_DN<5>   
                                  M32      M_A_CPU0_SB_DQ<2>       
                                  M34      M_B_CPU0_SB_CB<3>       
                                  M36      M_B_CPU0_SB_DQS_DP<4>   
                                  M38      M_B_CPU0_SB_CB<6>       
                                  M40      M_B_CPU0_SB_CS_N<3>     
                                  M42      GND                     
                                  M44      M_B_CPU0_SB_CA<3>       
                                  M47      M_B_CPU0_SA_CA<5>       
                                  M49      GND                     
                                  M51      M_B_CPU0_SA_CS_N<2>     
                                  M53      M_B_CPU0_SA_CB<7>       
                                  M55      M_B_CPU0_SA_DQS_DN<9>   
                                  M57      M_B_CPU0_SA_CB<2>       
                                  M59      M_B_CPU0_SA_DQ<23>      
                                  M61      M_B_CPU0_SA_DQS_DN<7>   
                                  M63      M_B_CPU0_SA_DQ<18>      
                                  M65      M_A_CPU0_SA_DQ<15>      
                                  M67      M_A_CPU0_SA_DQS_DP<6>   
                                  M69      M_A_CPU0_SA_DQ<10>      
                                  M71      M_B_CPU0_SA_DQ<7>       
                                  M73      M_B_CPU0_SA_DQS_DN<5>   
                                  M75      M_B_CPU0_SA_DQ<2>       
                                  M77      M_A_CPU0_SA_DQ<2>       
                                  M79      UPI_CPU1_CPU0_P2P2_DP<20>
                                  M81      GND                     
                                  M83      GND                     
                                  M85      PVCCFA_EHV_FIVRA_CPU0   
                                  M87      P5E_CPU0_PE4_TX_DP<15>  
                                  M89      PVCCFA_EHV_FIVRA_CPU0   
                                  N1       UPI_CPU0_CPU1_P0P1_DN<2>
                                  N3       PVCCFA_EHV_CPU0         
                                  N5       UPI_CPU1_CPU0_P1P0_DN<1>
                                  N7       PVCCFA_EHV_FIVRA_CPU0   
                                  N9       P5E_CPU0_PE0_RX_DP<14>  
                                  N11      PVCCFA_EHV_FIVRA_CPU0   
                                  N13      P5E_CPU0_PE0_TX_DN<15>  
                                  N15      GND                     
                                  N17      M_B_CPU0_SB_DQ<22>      
                                  N19      M_B_CPU0_SB_DQ<19>      
                                  N21      GND                     
                                  N23      M_B_CPU0_SB_DQ<14>      
                                  N25      M_B_CPU0_SB_DQ<11>      
                                  N27      GND                     
                                  N29      M_A_CPU0_SB_DQ<6>       
                                  N31      M_A_CPU0_SB_DQ<3>       
                                  N33      GND                     
                                  N35      M_B_CPU0_SB_CB<2>       
                                  N37      M_B_CPU0_SB_CB<7>       
                                  N39      GND                     
                                  N41      M_B_CPU0_SB_CS_N<2>     
                                  N43      M_B_CPU0_SB_CA<5>       
                                  N45      GND                     
                                  N48      M_B_CPU0_SA_CA<3>       
                                  N50      M_B_CPU0_SA_CS_N<3>     
                                  N52      GND                     
                                  N54      M_B_CPU0_SA_CB<6>       
                                  N56      M_B_CPU0_SA_CB<3>       
                                  N58      GND                     
                                  N60      M_B_CPU0_SA_DQ<22>      
                                  N62      M_B_CPU0_SA_DQ<19>      
                                  N64      GND                     
                                  N66      M_A_CPU0_SA_DQ<14>      
                                  N68      M_A_CPU0_SA_DQ<11>      
                                  N70      GND                     
                                  N72      M_B_CPU0_SA_DQ<6>       
                                  N74      M_B_CPU0_SA_DQ<3>       
                                  N76      GND                     
                                  N78      GND                     
                                  N80      GND                     
                                  N82      GND                     
                                  N84      GND                     
                                  N86      P5E_CPU0_PE4_TX_DP<14>  
                                  N88      GND                     
                                  N90      P5E_CPU0_PE4_RX_DP<14>  
                                  P2       UPI_CPU0_CPU1_P0P1_DP<2>
                                  P4       GND                     
                                  P6       UPI_CPU1_CPU0_P1P0_DN<2>
                                  P8       GND                     
                                  P10      P5E_CPU0_PE0_RX_DN<13>  
                                  P12      GND                     
                                  P14      P5E_CPU0_PE0_TX_DN<14>  
                                  P16      GND                     
                                  P18      M_B_CPU0_SB_DQS_DP<7>   
                                  P20      GND                     
                                  P22      GND                     
                                  P24      M_B_CPU0_SB_DQS_DP<6>   
                                  P26      GND                     
                                  P28      GND                     
                                  P30      M_A_CPU0_SB_DQS_DP<5>   
                                  P32      GND                     
                                  P34      GND                     
                                  P36      M_B_CPU0_SB_DQS_DN<4>   
                                  P38      GND                     
                                  P40      GND                     
                                  P42      M_B_CPU0_SB_PAR         
                                  P44      GND                     
                                  P47      GND                     
                                  P49      M_B_CPU0_SA_CA<1>       
                                  P51      GND                     
                                  P53      GND                     
                                  P55      M_B_CPU0_SA_DQS_DP<9>   
                                  P57      GND                     
                                  P59      GND                     
                                  P61      M_B_CPU0_SA_DQS_DP<7>   
                                  P63      GND                     
                                  P65      GND                     
                                  P67      M_A_CPU0_SA_DQS_DN<6>   
                                  P69      GND                     
                                  P71      GND                     
                                  P73      M_B_CPU0_SA_DQS_DP<5>   
                                  P75      GND                     
                                  P77      GND                     
                                  P79      PVCCFA_EHV_FIVRA_CPU0   
                                  P81      UPI_CPU0_CPU1_P2P2_DN<18>
                                  P83      UPI_CPU0_CPU1_P2P2_DP<17>
                                  P85      P5E_CPU0_PE4_TX_DN<14>  
                                  P87      GND                     
                                  P89      P5E_CPU0_PE4_RX_DN<14>  
                                  P91      GND                     
                                  R1       GND                     
                                  R3       UPI_CPU0_CPU1_P0P1_DP<3>
                                  R5       GND                     
                                  R7       UPI_CPU1_CPU0_P1P0_DP<2>
                                  R9       GND                     
                                  R11      P5E_CPU0_PE0_RX_DP<13>  
                                  R13      GND                     
                                  R15      P5E_CPU0_PE0_TX_DP<14>  
                                  R17      GND                     
                                  R19      GND                     
                                  R21      M_C_CPU0_SB_DQS_DN<2>   
                                  R23      GND                     
                                  R25      GND                     
                                  R27      M_B_CPU0_SB_DQS_DN<0>   
                                  R29      GND                     
                                  R31      GND                     
                                  R33      M_C_CPU0_SB_DQS_DN<9>   
                                  R35      GND                     
                                  R37      GND                     
                                  R39      M_C_CPU0_SB_CA<6>       
                                  R41      GND                     
                                  R43      GND                     
                                  R45      M_B_CPU0_CLK_DN<0>      
                                  R48      GND                     
                                  R50      GND                     
                                  R52      M_C_CPU0_SA_CA<0>       
                                  R54      GND                     
                                  R56      GND                     
                                  R58      M_B_CPU0_SA_DQS_DN<3>   
                                  R60      GND                     
                                  R62      GND                     
                                  R64      M_C_CPU0_SA_DQS_DN<2>   
                                  R66      GND                     
                                  R68      GND                     
                                  R70      M_B_CPU0_SA_DQS_DN<1>   
                                  R72      GND                     
                                  R74      GND                     
                                  R76      M_C_CPU0_SA_DQS_DN<0>   
                                  R78      GND                     
                                  R80      PVCCFA_EHV_FIVRA_CPU0   
                                  R82      UPI_CPU0_CPU1_P2P2_DN<17>
                                  R84      GND                     
                                  R86      P5E_CPU0_PE4_TX_DN<13>  
                                  R88      GND                     
                                  R90      P5E_CPU0_PE4_RX_DP<13>  
                                  T2       UPI_CPU0_CPU1_P0P1_DN<3>
                                  T4       GND                     
                                  T6       UPI_CPU1_CPU0_P1P0_DN<3>
                                  T8       GND                     
                                  T10      P5E_CPU0_PE0_RX_DN<12>  
                                  T12      GND                     
                                  T14      P5E_CPU0_PE0_TX_DP<13>  
                                  T16      GND                     
                                  T18      GND                     
                                  T20      M_C_CPU0_SB_DQ<20>      
                                  T22      M_C_CPU0_SB_DQ<17>      
                                  T24      GND                     
                                  T26      M_B_CPU0_SB_DQ<4>       
                                  T28      M_B_CPU0_SB_DQ<1>       
                                  T30      GND                     
                                  T32      M_C_CPU0_SB_CB<0>       
                                  T34      M_C_CPU0_SB_CB<5>       
                                  T36      GND                     
                                  T38      M_C_CPU0_SB_CS_N<0>     
                                  T40      M_C_CPU0_SB_CA<4>       
                                  T42      GND                     
                                  T44      M_B_CPU0_SB_CA<0>       
                                  T47      M_C_CPU0_SA_PAR         
                                  T49      GND                     
                                  T51      M_C_CPU0_SA_CA<2>       
                                  T53      M_C_CPU0_SA_CS_N<1>     
                                  T55      GND                     
                                  T57      M_B_CPU0_SA_DQ<28>      
                                  T59      M_B_CPU0_SA_DQ<25>      
                                  T61      GND                     
                                  T63      M_C_CPU0_SA_DQ<20>      
                                  T65      M_C_CPU0_SA_DQ<17>      
                                  T67      GND                     
                                  T69      M_B_CPU0_SA_DQ<12>      
                                  T71      M_B_CPU0_SA_DQ<9>       
                                  T73      GND                     
                                  T75      M_C_CPU0_SA_DQ<4>       
                                  T77      M_C_CPU0_SA_DQ<1>       
                                  T79      GND                     
                                  T81      UPI_CPU0_CPU1_P2P2_DP<18>
                                  T83      GND                     
                                  T85      PVCCFA_EHV_FIVRA_CPU0   
                                  T87      P5E_CPU0_PE4_TX_DP<13>  
                                  T89      PVCCFA_EHV_FIVRA_CPU0   
                                  T91      P5E_CPU0_PE4_RX_DN<13>  
                                  U1       UPI_CPU0_CPU1_P0P1_DN<4>
                                  U3       PVCCFA_EHV_CPU0         
                                  U5       UPI_CPU1_CPU0_P1P0_DP<3>
                                  U7       PVCCFA_EHV_FIVRA_CPU0   
                                  U9       P5E_CPU0_PE0_RX_DP<12>  
                                  U11      PVCCFA_EHV_FIVRA_CPU0   
                                  U13      P5E_CPU0_PE0_TX_DN<13>  
                                  U15      PVCCFA_EHV_FIVRA_CPU0   
                                  U19      M_C_CPU0_SB_DQ<21>      
                                  U21      M_C_CPU0_SB_DQS_DP<2>   
                                  U23      M_C_CPU0_SB_DQ<16>      
                                  U25      M_B_CPU0_SB_DQ<5>       
                                  U27      M_B_CPU0_SB_DQS_DP<0>   
                                  U29      M_B_CPU0_SB_DQ<0>       
                                  U31      M_C_CPU0_SB_CB<1>       
                                  U33      M_C_CPU0_SB_DQS_DP<9>   
                                  U35      M_C_CPU0_SB_CB<4>       
                                  U37      M_C_CPU0_SB_CS_N<1>     
                                  U39      GND                     
                                  U41      M_C_CPU0_SB_CA<2>       
                                  U43      M_B_CPU0_SB_CA<1>       
                                  U45      M_B_CPU0_CLK_DP<0>      
                                  U48      M_C_CPU0_SA_CA<6>       
                                  U50      M_C_CPU0_SA_CA<4>       
                                  U52      GND                     
                                  U54      M_C_CPU0_SA_CS_N<0>     
                                  U56      M_B_CPU0_SA_DQ<29>      
                                  U58      M_B_CPU0_SA_DQS_DP<3>   
                                  U60      M_B_CPU0_SA_DQ<24>      
                                  U62      M_C_CPU0_SA_DQ<21>      
                                  U64      M_C_CPU0_SA_DQS_DP<2>   
                                  U66      M_C_CPU0_SA_DQ<16>      
                                  U68      M_B_CPU0_SA_DQ<13>      
                                  U70      M_B_CPU0_SA_DQS_DP<1>   
                                  U72      M_B_CPU0_SA_DQ<8>       
                                  U74      M_C_CPU0_SA_DQ<5>       
                                  U76      M_C_CPU0_SA_DQS_DP<0>   
                                  U78      M_C_CPU0_SA_DQ<0>       
                                  U80      UPI_CPU0_CPU1_P2P2_DN<16>
                                  U82      GND                     
                                  U84      GND                     
                                  U86      P5E_CPU0_PE4_TX_DN<12>  
                                  U88      GND                     
                                  U90      P5E_CPU0_PE4_RX_DP<12>  
                                  V2       UPI_CPU0_CPU1_P0P1_DP<4>
                                  V4       GND                     
                                  V6       UPI_CPU1_CPU0_P1P0_DN<4>
                                  V8       GND                     
                                  V10      P5E_CPU0_PE0_RX_DN<11>  
                                  V12      GND                     
                                  V14      P5E_CPU0_PE0_TX_DN<12>  
                                  V16      GND                     
                                  V18      GND                     
                                  V20      GND                     
                                  V22      GND                     
                                  V24      GND                     
                                  V26      GND                     
                                  V28      GND                     
                                  V30      GND                     
                                  V32      GND                     
                                  V34      GND                     
                                  V36      GND                     
                                  V38      GND                     
                                  V40      GND                     
                                  V42      GND                     
                                  V44      GND                     
                                  V47      GND                     
                                  V49      GND                     
                                  V51      GND                     
                                  V53      GND                     
                                  V55      GND                     
                                  V57      GND                     
                                  V59      GND                     
                                  V61      GND                     
                                  V63      GND                     
                                  V65      GND                     
                                  V67      GND                     
                                  V69      GND                     
                                  V71      GND                     
                                  V73      GND                     
                                  V75      GND                     
                                  V77      GND                     
                                  V79      GND                     
                                  V81      UPI_CPU0_CPU1_P2P2_DP<16>
                                  V83      UPI_CPU0_CPU1_P2P2_DN<15>
                                  V85      P5E_CPU0_PE4_TX_DP<12>  
                                  V87      GND                     
                                  V89      P5E_CPU0_PE4_RX_DN<12>  
                                  V91      GND                     
                                  W1       GND                     
                                  W3       UPI_CPU0_CPU1_P0P1_DP<5>
                                  W5       GND                     
                                  W7       UPI_CPU1_CPU0_P1P0_DP<4>
                                  W9       GND                     
                                  W11      P5E_CPU0_PE0_RX_DP<11>  
                                  W13      GND                     
                                  W15      P5E_CPU0_PE0_TX_DP<12>  
                                  W19      M_C_CPU0_SB_DQ<23>      
                                  W21      M_C_CPU0_SB_DQS_DN<7>   
                                  W23      M_C_CPU0_SB_DQ<18>      
                                  W25      M_B_CPU0_SB_DQ<7>       
                                  W27      M_B_CPU0_SB_DQS_DN<5>   
                                  W29      M_B_CPU0_SB_DQ<2>       
                                  W31      M_C_CPU0_SB_CB<3>       
                                  W33      M_C_CPU0_SB_DQS_DN<4>   
                                  W35      M_C_CPU0_SB_CB<6>       
                                  W37      M_C_CPU0_SB_CS_N<3>     
                                  W39      GND                     
                                  W41      M_C_CPU0_SB_CA<3>       
                                  W43      M_B_CPU0_SA_PAR         
                                  W45      M_B_CPU0_CLK_DN<1>      
                                  W48      M_C_CPU0_SB_CA<0>       
                                  W50      M_C_CPU0_SA_CA<5>       
                                  W52      GND                     
                                  W54      M_C_CPU0_SA_CS_N<2>     
                                  W56      M_B_CPU0_SA_DQ<31>      
                                  W58      M_B_CPU0_SA_DQS_DP<8>   
                                  W60      M_B_CPU0_SA_DQ<26>      
                                  W62      M_C_CPU0_SA_DQ<23>      
                                  W64      M_C_CPU0_SA_DQS_DP<7>   
                                  W66      M_C_CPU0_SA_DQ<18>      
                                  W68      M_B_CPU0_SA_DQ<15>      
                                  W70      M_B_CPU0_SA_DQS_DP<6>   
                                  W72      M_B_CPU0_SA_DQ<10>      
                                  W74      M_C_CPU0_SA_DQ<7>       
                                  W76      M_C_CPU0_SA_DQS_DN<5>   
                                  W78      M_C_CPU0_SA_DQ<2>       
                                  W80      PVCCFA_EHV_FIVRA_CPU0   
                                  W82      UPI_CPU0_CPU1_P2P2_DP<14>
                                  W84      GND                     
                                  W86      P5E_CPU0_PE4_TX_DN<11>  
                                  W88      GND                     
                                  W90      P5E_CPU0_PE4_RX_DP<11>  
                                  Y2       UPI_CPU0_CPU1_P0P1_DN<5>
                                  Y4       GND                     
                                  Y6       UPI_CPU1_CPU0_P1P0_DN<5>
                                  Y8       GND                     
                                  Y10      P5E_CPU0_PE0_RX_DP<10>  
                                  Y12      GND                     
                                  Y14      P5E_CPU0_PE0_TX_DP<11>  
                                  Y16      GND                     
                                  Y18      GND                     
                                  Y20      M_C_CPU0_SB_DQ<22>      
                                  Y22      M_C_CPU0_SB_DQ<19>      
                                  Y24      GND                     
                                  Y26      M_B_CPU0_SB_DQ<6>       
                                  Y28      M_B_CPU0_SB_DQ<3>       
                                  Y30      GND                     
                                  Y32      M_C_CPU0_SB_CB<2>       
                                  Y34      M_C_CPU0_SB_CB<7>       
                                  Y36      GND                     
                                  Y38      M_C_CPU0_SB_CS_N<2>     
                                  Y40      M_C_CPU0_SB_CA<5>       
                                  Y42      GND                     
                                  Y44      M_B_CPU0_SA_CA<6>       
                                  Y47      M_C_CPU0_SB_CA<1>       
                                  Y49      GND                     
                                  Y51      M_C_CPU0_SA_CA<3>       
                                  Y53      M_C_CPU0_SA_CS_N<3>     
                                  Y55      GND                     
                                  Y57      M_B_CPU0_SA_DQ<30>      
                                  Y59      M_B_CPU0_SA_DQ<27>      
                                  Y61      GND                     
                                  Y63      M_C_CPU0_SA_DQ<22>      
                                  Y65      M_C_CPU0_SA_DQ<19>      
                                  Y67      GND                     
                                  Y69      M_B_CPU0_SA_DQ<14>      
                                  Y71      M_B_CPU0_SA_DQ<11>      
                                  Y73      GND                     
                                  Y75      M_C_CPU0_SA_DQ<6>       
                                  Y77      M_C_CPU0_SA_DQ<3>       
                                  Y79      PVCCFA_EHV_FIVRA_CPU0   
                                  Y81      UPI_CPU0_CPU1_P2P2_DN<14>
                                  Y83      UPI_CPU0_CPU1_P2P2_DP<15>
                                  Y85      PVCCFA_EHV_FIVRA_CPU0   
                                  Y87      P5E_CPU0_PE4_TX_DP<11>  
                                  Y89      PVCCFA_EHV_FIVRA_CPU0   
                                  Y91      P5E_CPU0_PE4_RX_DN<11>  
U4               EMMITSBURG_REV0P9-GFNOCPU04302A A6       GND                     
                                  A20      GND                     
                                  A22      GND                     
                                  A24      GND                     
                                  A26      GND                     
                                  A28      CLK_25M_PCH_CPU1_DP     
                                  A30      DMI_CPU0_PCH_TX_C_DN<0> 
                                  A32      DMI_CPU0_PCH_TX_C_DN<2> 
                                  A34      DMI_CPU0_PCH_TX_C_DN<4> 
                                  A36      DMI_CPU0_PCH_TX_C_DN<6> 
                                  A38      GND                     
                                  A40      GND                     
                                  A41      FM_PCH_PRSNT_N          
                                  AA1      FM_PCH_GLB_RST_WARN_N   
                                  AA3      FM_BIOS_DEBUG_EN_R_N    
                                  AA5      GND                     
                                  AA7      RISER2_TYPE_ID          
                                  AA17     GND                     
                                  AA19     GND                     
                                  AA20     GND                     
                                  AA22     GND                     
                                  AA24     GND                     
                                  AA25     GND                     
                                  AA27     GND                     
                                  AA29     P1V05_PCH_PLL_AUX       
                                  AA32     GND                     
                                  AA36     GND                     
                                  AA39     GND                     
                                  AA41     P3E_PCH_M2_RX_DN<4>     
                                  AA43     P3E_PCH_M2_RX_DP<4>     
                                  AB2      IRQ_PCH_SCI_WHEA_N      
                                  AB4      RST_PLTRST_N            
                                  AB8      FM_PASSWORD_CLEAR_N     
                                  AB15     GND                     
                                  AB17     GND                     
                                  AB19     P1V05_PCH_AUX           
                                  AB20     P1V05_PCH_AUX           
                                  AB22     P1V05_PCH_AUX           
                                  AB24     P1V05_PCH_AUX           
                                  AB25     GND                     
                                  AB27     P1V05_PCH_PLL_AUX       
                                  AB31     P1V8_PCH_PLL_AUX        
                                  AB34     P1V8_PCH_PLL_AUX        
                                  AB37     GND                     
                                  AB40     P3E_PCH_M2_RX_DN<3>     
                                  AB42     P3E_PCH_M2_RX_DP<3>     
                                  AC1      FM_ADR_COMPLETE         
                                  AC3      PU_PCH_VRALERT_N        
                                  AC5      GND                     
                                  AC7      FM_PCIE_EDSFF2B_PRSNT_1_N
                                  AC10     FM_PCIE_EDSFF1B_PRSNT_1_N
                                  AC13     PD_RCOMP_1P8_3P3        
                                  AC29     GND                     
                                  AC32     GND                     
                                  AC36     GND                     
                                  AC39     GND                     
                                  AC41     P3E_PCH_M2_RX_DN<2>     
                                  AC43     P3E_PCH_M2_RX_DP<2>     
                                  AD4      FM_ADR_ACK              
                                  AD8      GND                     
                                  AD11     GND                     
                                  AD15     P3V3_AUX                
                                  AD17     P3V3_AUX                
                                  AD19     GND                     
                                  AD20     GND                     
                                  AD22     GND                     
                                  AD24     GND                     
                                  AD25     P1V05_PCH_AUX           
                                  AD27     P1V05_PCH_AUX           
                                  AD31     GND                     
                                  AD34     GND                     
                                  AD40     P3E_PCH_M2_RX_DN<1>     
                                  AD42     P3E_PCH_M2_RX_DP<1>     
                                  AE1      SMB_HOST_BMC_3V3AUX_SDA 
                                  AE3      FM_PCH_CRASHLOG_TRIG_N  
                                  AE5      GND                     
                                  AE7      H_CPU0_PMDOWN_PCH       
                                  AE10     FM_PCIE_EDSFF4B_PRSNT_1_N
                                  AE13     GND                     
                                  AE29     P1V05_PCH_PLL_AUX       
                                  AE32     USB3_9_TX_DN            
                                  AE39     GND                     
                                  AE41     P3E_PCH_M2_RX_DN<0>     
                                  AE43     P3E_PCH_M2_RX_DP<0>     
                                  AF2      SMB_HOST_BMC_3V3AUX_SCL 
                                  AF4      FM_CPU_RMCA_CATERR_DLY_N
                                  AF8      H_CPU0_PMSYNC_PCH_R2    
                                  AF11     FM_BIOS_ADV_FUNCTIONS   
                                  AF17     P3V3_AUX                
                                  AF19     GND                     
                                  AF20     P1V05_PCH_AUX           
                                  AF22     P1V05_PCH_AUX           
                                  AF24     GND                     
                                  AF25     P1V05_PCH_AUX           
                                  AF27     P1V05_PCH_AUX           
                                  AF31     GND                     
                                  AF40     GND                     
                                  AF42     GND                     
                                  AG1      FM_ESPI_FLASH_MODE      
                                  AG5      GND                     
                                  AG7      FM_ME_RCVR_N            
                                  AG10     FM_MFG_MODE             
                                  AG13     GND                     
                                  AG17     P3V3_AUX                
                                  AG19     GND                     
                                  AG20     P1V05_PCH_AUX           
                                  AG22     P1V05_PCH_AUX           
                                  AG24     GND                     
                                  AG25     P1V05_PCH_AUX           
                                  AG27     P1V05_PCH_AUX           
                                  AG29     P1V05_PCH_PLL_AUX       
                                  AG32     USB3_9_TX_DP            
                                  AG39     GND                     
                                  AH2      FM_PCHHOT_N             
                                  AH4      FM_ADR_TRIGGER_R_N      
                                  AH8      GND                     
                                  AH11     IRQ_LVC3_WAKE_N         
                                  AH15     P3V3_RTC_AUX            
                                  AH31     GND                     
                                  AJ1      FM_FLASH_SECURITY_STRAP 
                                  AJ3      PU_LPC_PME_N            
                                  AJ5      GND                     
                                  AJ10     RST_PCH_RSTBTN_R_N      
                                  AJ17     P3V3_AUX                
                                  AJ19     GND                     
                                  AJ20     P1V05_PCH_AUX           
                                  AJ22     P1V05_PCH_AUX           
                                  AJ24     GND                     
                                  AJ25     P1V05_PCH_AUX           
                                  AJ27     P1V05_PCH_AUX           
                                  AJ29     GND                     
                                  AJ36     GND                     
                                  AJ39     GND                     
                                  AJ41     USB2_9_DP               
                                  AJ43     USB2_9_DN               
                                  AK2      GND                     
                                  AK4      GND                     
                                  AK11     GND                     
                                  AK15     P3V3_AUX                
                                  AK31     P3E_PCH_M2_TX_DP<0>     
                                  AK34     P3E_PCH_M2_TX_DN<3>     
                                  AK37     GND                     
                                  AL1      PU_SMB_PCH_PLD_3V3AUX_SCL
                                  AL3      FM_BIOS_POST_CMPLT_N    
                                  AL5      FM_ADR_MODE1            
                                  AL7      FM_PCH_SLP_SUS_N        
                                  AL10     PWRGD_SYS_PWROK         
                                  AL13     FM_PCH_SLP_S4_N         
                                  AL17     P3V3_AUX                
                                  AL19     GND                     
                                  AL20     P1V05_PCH_AUX           
                                  AL22     P1V05_PCH_AUX           
                                  AL24     GND                     
                                  AL25     P1V05_PCH_PLL_AUX       
                                  AL27     GND                     
                                  AL29     GND                     
                                  AL32     P3E_PCH_M2_TX_DN<0>     
                                  AL36     P3E_PCH_M2_TX_DN<4>     
                                  AL39     GND                     
                                  AL41     USB2_5_DP               
                                  AL43     USB2_5_DN               
                                  AM8      GND                     
                                  AM15     GND                     
                                  AM31     GND                     
                                  AM34     P3E_PCH_M2_TX_DP<3>     
                                  AM37     P3E_PCH_M2_TX_DP<4>     
                                  AN2      PU_PCH_PLD_3V3AUX_ALERT_N
                                  AN4      PU_SMB_SML3_3V3AUX_PCH_SCL
                                  AN7      PU_ACPRESENT            
                                  AN10     FM_PCH_SPARE0           
                                  AN13     GND                     
                                  AN16     GND                     
                                  AN20     P3V3_AUX                
                                  AN23     P1V05_PCH_AUX           
                                  AN29     GND                     
                                  AN32     GND                     
                                  AN36     P3E_PCH_M2_TX_DN<1>     
                                  AN40     USB2_3_DP               
                                  AN42     USB2_3_DN               
                                  AP1      SMB_SML1_PMBUS_3V3AUX_PCH_SCL
                                  AP5      GND                     
                                  AP8      FM_PCH_SLP_S3_N         
                                  AP11     GND                     
                                  AP15     IRQ_PCH_CPU_NMI_EVENT_R_N
                                  AP18     GND                     
                                  AP21     P1V05_PCH_AUX           
                                  AP24     GND                     
                                  AP28     GND                     
                                  AP31     PCH_PCIEUP_RCOMPN       
                                  AP34     P3E_PCH_M2_TX_DP<1>     
                                  AP37     GND                     
                                  AP39     GND                     
                                  AP41     USB2_1_DP               
                                  AP43     USB2_1_DN               
                                  AR4      IRQ_SML1_PMBUS_ALERT_N  
                                  AR7      PD_SUSCLK               
                                  AR10     FM_BMC_PWRBTN_N         
                                  AR13     FM_EUP_LOT6_N           
                                  AR16     FM_XTAL_INPUT_FREQUENCY_1_MGPIO
                                  AR20     GND                     
                                  AR23     P1V05_PCH_AUX           
                                  AR26     P1V05_PCH_AUX           
                                  AR29     PCH_PCIEUP_RCOMPP       
                                  AR32     GND                     
                                  AR36     P3E_PCH_M2_TX_DN<2>     
                                  AR40     USB2_0_DP               
                                  AR42     USB2_0_DN               
                                  AT1      PU_SMB_PCH_PLD_3V3AUX_SDA
                                  AT5      GND                     
                                  AT8      GND                     
                                  AT11     GND                     
                                  AT15     GND                     
                                  AT18     FM_PCH_CONSENT_STRAP_N  
                                  AT21     GND                     
                                  AT24     GND                     
                                  AT28     GND                     
                                  AT31     GND                     
                                  AT34     GND                     
                                  AT37     P3E_PCH_M2_TX_DP<2>     
                                  AT39     GND                     
                                  AU2      IRQ_SML0_ALERT_N        
                                  AU4      SMB_SML0B_3V3AUX_SDA    
                                  AU7      PU_LAN_WAKE_N           
                                  AU10     FM_PCH_SKIP_RTC_CLOCK   
                                  AU13     FM_SPI_3V3_1V8_VOLTAGE  
                                  AU16     PU_NO_REBOOT_STRAP      
                                  AU20     GND                     
                                  AU23     GND                     
                                  AU26     GND                     
                                  AU29     GND                     
                                  AU32     GND                     
                                  AU36     GND                     
                                  AU40     USB2_4_DP               
                                  AU42     USB2_4_DN               
                                  AV1      PU_SMB_SML4_3V3AUX_PCH_SDA
                                  AV3      FM_PMBUS_ALERT_B_EN     
                                  AV5      GND                     
                                  AV8      GND                     
                                  AV11     FM_ADR_MODE0            
                                  AV15     SPI_PCH_IO2             
                                  AV18     IRQ_SMI_ACTIVE_N        
                                  AV24     FM_EDSFF1A_TYPE_ID      
                                  AV28     FM_EDSFF1B_TYPE_ID      
                                  AV31     FM_EDSFF4B_TYPE_ID      
                                  AV37     GND                     
                                  AV39     GND                     
                                  AW2      FM_THROTTLE_N           
                                  AW4      SMB_SML1_PMBUS_3V3AUX_PCH_SDA
                                  AW7      GND                     
                                  AW10     FM_JTAG_ODT_DISABLE     
                                  AW13     SPI_PCH_CS0_R_N         
                                  AW16     SPI_PCH_IO1             
                                  AW20     FM_ME_AUTHN_FAIL        
                                  AW23     FM_M2_SSD_1_PEDET       
                                  AW29     FM_ME_BT_DONE           
                                  AW32     FM_EDSFF2B_TYPE_ID      
                                  AW36     FM_EDSFF3_TYPE_ID       
                                  AW40     USB2_8_DP               
                                  AW42     USB2_8_DN               
                                  AY1      PU_SMB_SML3_3V3AUX_PCH_SDA
                                  AY3      GND                     
                                  AY5      GND                     
                                  AY8      GND                     
                                  AY11     GND                     
                                  AY15     GND                     
                                  AY18     GND                     
                                  AY21     GND                     
                                  AY24     GND                     
                                  AY28     GND                     
                                  AY31     GND                     
                                  AY34     GND                     
                                  AY37     GND                     
                                  AY39     GND                     
                                  B9       GND                     
                                  B11      CLK_100M_BMC_P3E_DN     
                                  B13      GND                     
                                  B21      CLK_100M_CK440_PCH_EXTCLK_DP
                                  B23      XTAL_PCH_25M_IN         
                                  B25      CLK_25M_PCH_REF_NS_DP   
                                  B27      CLK_25M_PCH_CPU0_DP     
                                  B29      GND                     
                                  B31      DMI_CPU0_PCH_TX_C_DN<1> 
                                  B33      DMI_CPU0_PCH_TX_C_DN<3> 
                                  B35      DMI_CPU0_PCH_TX_C_DN<5> 
                                  B37      DMI_CPU0_PCH_TX_C_DN<7> 
                                  B39      GND                     
                                  BA2      PU_SMB_SML4_3V3AUX_PCH_SCL
                                  BA4      SMB_SML0_3V3AUX_PCH_SDA 
                                  BA7      FM_SUSACK_N             
                                  BA10     SPI_PCH_CS1_R_N         
                                  BA13     SPI_PCH_IO0             
                                  BA16     SPI_PCH_IO3             
                                  BA20     FM_PS_PWROK_DLY_R_SEL   
                                  BA23     FM_M2_SSD_1_PEDET       
                                  BA26     FM_M2_SSD_1_PEDET       
                                  BA29     FM_EDSFF4A_TYPE_ID      
                                  BB1      GND                     
                                  BB3      SMB_SML0B_3V3AUX_SCL    
                                  BB5      GND                     
                                  BB8      FM_ESPI_CS_SWIZZLE      
                                  BB11     SPI_PCH_TPM_CS_N        
                                  BB15     SPI_PCH_CLK             
                                  BB18     FM_XTAL_INPUT_FREQUENCY_0_MGPIO
                                  BB21     FM_M2_SSD_1_PEDET       
                                  BB24     FM_EDSFF2A_TYPE_ID      
                                  BB31     FM_TPM_PRSNT_N          
                                  BB37     H_DBP_PRDY_N_PCH        
                                  BB39     GND                     
                                  BB41     PD_PCH_USB2_COMP        
                                  BC2      GND                     
                                  BC4      SMB_SML0_3V3AUX_PCH_SCL 
                                  BC6      GND                     
                                  BC8      GND                     
                                  BC10     GND                     
                                  BC12     GND                     
                                  BC14     GND                     
                                  BC16     GND                     
                                  BC18     GND                     
                                  BC20     GND                     
                                  BC22     GND                     
                                  BC24     GND                     
                                  BC26     GND                     
                                  BC28     GND                     
                                  BC30     GND                     
                                  BC32     GND                     
                                  BC34     GND                     
                                  BC36     GND                     
                                  BC38     GND                     
                                  BC42     GND                     
                                  BD1      GND                     
                                  BD3      GND                     
                                  BD5      GND                     
                                  BD7      RST_RTCRST_N            
                                  BD9      RST_RSMRST_PCH_N        
                                  BD11     FM_PCH_SATA_RAID_KEY    
                                  BD13     CLK_24M_66M_LPC0_ESPI   
                                  BD15     ESPI_ALERT1_N_LPC_RCIN_N
                                  BD19     ESPI_LAD0_DATA_IO3      
                                  BD21     GND                     
                                  BD23     JTAG_TRC_PCH_PTI1_CLK   
                                  BD25     JTAG_TRC_PCH_PTI<11>    
                                  BD27     JTAG_TRC_PCH_PTI<8>     
                                  BD29     JTAG_TRC_PCH_PTI<5>     
                                  BD31     JTAG_TRC_PCH_PTI<2>     
                                  BD33     JTAG_TRC_PCH_PTI0_CLK   
                                  BD35     JTAG_DBP_CPU_GTL_TCK    
                                  BD37     JTAG_DBP_TMS_PCH        
                                  BD39     GND                     
                                  BD41     GND                     
                                  BD43     GND                     
                                  BE1      GND                     
                                  BE3      GND                     
                                  BE4      PWRGD_PCH_PWROK         
                                  BE6      XTAL_PCH_RTC1           
                                  BE8      PWRGD_DSW_PWROK         
                                  BE10     GND                     
                                  BE16     IRQ_LPC_SERIRQ_ESPI_CS1_N
                                  BE18     ESPI_LAD0_DATA_IO2      
                                  BE20     ESPI_LFRAME_N_BMC_CS0_N 
                                  BE22     JTAG_TRC_PCH_PTI<15>    
                                  BE24     JTAG_TRC_PCH_PTI<13>    
                                  BE26     JTAG_TRC_PCH_PTI<9>     
                                  BE28     JTAG_TRC_PCH_PTI<6>     
                                  BE30     JTAG_TRC_PCH_PTI<3>     
                                  BE32     JTAG_TRC_PCH_PTI<0>     
                                  BE34     GND                     
                                  BE36     JTAG_DBP_TDO_PCH        
                                  BE38     JTAG_DBP_TDI_PCH        
                                  BE40     JTAG_DBP_PMODE          
                                  BE41     GND                     
                                  BE43     GND                     
                                  BF5      RTC_EXT_CAP             
                                  BF7      XTAL_PCH_RTC2           
                                  BF9      RST_SRTCRST_N           
                                  BF13     IRQ_BMC_PCH_NMI         
                                  BF17     RST_ESPI_RESET_N        
                                  BF19     ESPI_LAD0_DATA_IO1      
                                  BF21     GND                     
                                  BF23     JTAG_TRC_PCH_PTI<14>    
                                  BF25     JTAG_TRC_PCH_PTI<12>    
                                  BF27     JTAG_TRC_PCH_PTI<10>    
                                  BF29     JTAG_TRC_PCH_PTI<7>     
                                  BF31     JTAG_TRC_PCH_PTI<4>     
                                  BF33     JTAG_TRC_PCH_PTI<1>     
                                  BF35     JTAG_DBP_TCK_PCH        
                                  BF37     H_DBP_PREQ_N_PCH        
                                  BG4      GND                     
                                  BG6      GND                     
                                  BG8      FM_INTRUDER_HDR_PCH_N   
                                  BG10     GND                     
                                  BG12     ESPI_LAD0_DATA_IO0      
                                  BG16     M2_SSD0_CLKREQ_LV_EN_N  
                                  BG20     IRQ_LPC_PIRQA_N_ESPI_ALERT0_N
                                  BG22     PU_OC6_USB_N            
                                  BG24     PU_OC5_USB_N            
                                  BG26     PU_OC4_USB_N            
                                  BG28     PU_OC3_USB_N            
                                  BG30     USB_OC2_INT_R_N         
                                  BG32     USB_OC1_REAR_R_N        
                                  BG34     GND                     
                                  BG38     GND                     
                                  BG40     GND                     
                                  BG41     GND                     
                                  C3       GND                     
                                  C4       GND                     
                                  C20      GND                     
                                  C22      GND                     
                                  C24      GND                     
                                  C26      GND                     
                                  C28      CLK_25M_PCH_CPU1_DN     
                                  C30      DMI_CPU0_PCH_TX_C_DP<0> 
                                  C32      DMI_CPU0_PCH_TX_C_DP<2> 
                                  C34      DMI_CPU0_PCH_TX_C_DP<4> 
                                  C36      DMI_CPU0_PCH_TX_C_DP<6> 
                                  C38      GND                     
                                  C41      GND                     
                                  C43      GND                     
                                  D1       GND                     
                                  D3       GND                     
                                  D5       GND                     
                                  D9       GND                     
                                  D11      CLK_100M_BMC_P3E_DP     
                                  D13      GND                     
                                  D21      CLK_100M_CK440_PCH_EXTCLK_DN
                                  D23      XTAL_PCH_25M_OUT        
                                  D25      CLK_25M_PCH_REF_NS_DN   
                                  D27      CLK_25M_PCH_CPU0_DN     
                                  D29      GND                     
                                  D31      DMI_CPU0_PCH_TX_C_DP<1> 
                                  D33      DMI_CPU0_PCH_TX_C_DP<3> 
                                  D35      DMI_CPU0_PCH_TX_C_DP<5> 
                                  D37      DMI_CPU0_PCH_TX_C_DP<7> 
                                  D41      GND                     
                                  D43      GND                     
                                  E2       GND                     
                                  E6       GND                     
                                  E8       GND                     
                                  E10      GND                     
                                  E12      GND                     
                                  E14      GND                     
                                  E16      GND                     
                                  E18      GND                     
                                  E20      GND                     
                                  E22      GND                     
                                  E24      GND                     
                                  E26      GND                     
                                  E28      GND                     
                                  E30      GND                     
                                  E32      GND                     
                                  E34      GND                     
                                  E36      GND                     
                                  E38      GND                     
                                  E40      GND                     
                                  E42      GND                     
                                  F3       H_THERMTRIP_LVC1_N      
                                  F5       FM_PCH_CPU_PWR_DEBUG_N  
                                  F8       FM_PCIE_EV_BIF_EN       
                                  F15      GND                     
                                  F24      GND                     
                                  F28      DMI_CPU0_PCH_RX_DP<1>   
                                  F31      GND                     
                                  F34      GND                     
                                  F37      DMI_CPU0_PCH_RX_DN<7>   
                                  F39      GND                     
                                  F41      GND                     
                                  F43      GND                     
                                  G2       FM_PCH_RING_OSC_BYPASS_MGPIO_TE
                                  G4       FM_PCH_VISA_DEFAULT     
                                  G7       H_CPU_ERR1_PCH_R_N      
                                  G10      PWRGD_CPUPWRGD_GTL      
                                  G13      GND                     
                                  G20      GND                     
                                  G26      GND                     
                                  G29      DMI_CPU0_PCH_RX_DN<1>   
                                  G32      DMI_CPU0_PCH_RX_DP<4>   
                                  G36      DMI_CPU0_PCH_RX_DN<5>   
                                  H3       FM_PCH_XTAL_INPUT_MODE_MGPIO_TE
                                  H5       GND                     
                                  H8       GND                     
                                  H11      FM_PCH_TRIGGER0_R_N     
                                  H21      CLK_100M_PE_M2_0_DN     
                                  H28      DMI_CPU0_PCH_RX_DP<0>   
                                  H31      DMI_CPU0_PCH_RX_DP<2>   
                                  H34      DMI_CPU0_PCH_RX_DP<5>   
                                  H37      DMI_CPU0_PCH_RX_DP<7>   
                                  H39      GND                     
                                  J4       PU_PCH_PMCALERT_N       
                                  J7       H_CPU_ERR0_PCH_R_N      
                                  J10      PECI_PCH                
                                  J13      GND                     
                                  J20      GND                     
                                  J26      GND                     
                                  J29      DMI_CPU0_PCH_RX_DN<2>   
                                  J32      DMI_CPU0_PCH_RX_DN<4>   
                                  J36      DMI_CPU0_PCH_RX_DP<6>   
                                  K1       FM_PCH_IO_EXPANDER      
                                  K3       FM_PCH_MCRO_LDO         
                                  K5       GND                     
                                  K8       FM_PCH_TRIGGER1_R_N     
                                  K11      GND                     
                                  K15      GND                     
                                  K21      CLK_100M_PE_M2_0_DP     
                                  K24      GND                     
                                  K28      DMI_CPU0_PCH_RX_DN<0>   
                                  K31      DMI_CPU0_PCH_RX_DP<3>   
                                  K34      GND                     
                                  K37      DMI_CPU0_PCH_RX_DN<6>   
                                  K39      GND                     
                                  L2       FM_PCH_EXTERNALCLKMODE  
                                  L4       FM_LT_KEY_DOWNGRADE_N   
                                  L7       H_CPU_ERR2_PCH_R_N      
                                  L10      GND                     
                                  L16      GND                     
                                  L20      GND                     
                                  L23      GND                     
                                  L26      GND                     
                                  L29      GND                     
                                  L32      DMI_CPU0_PCH_RX_DN<3>   
                                  L36      GND                     
                                  L40      SATA_P11_RX_DN          
                                  L42      SATA_P11_RX_DP          
                                  M1       GND                     
                                  M3       GND                     
                                  M5       GND                     
                                  M11      GND                     
                                  M15      GND                     
                                  M18      GND                     
                                  M21      GND                     
                                  M24      P1V05_PCH_AUX           
                                  M28      GND                     
                                  M31      GND                     
                                  M34      GND                     
                                  M37      GND                     
                                  M39      GND                     
                                  M41      P3E_PCH_BMC_RX_DN       
                                  M43      P3E_PCH_BMC_RX_DP       
                                  N2       OCP_SFF_BIF1_N          
                                  N4       IRQ_TPM_SPI_N           
                                  N10      FM_PCIE_EDSFF3_PRSNT_1_N
                                  N16      GND                     
                                  N20      P1V8_PCH_AUX            
                                  N23      P1V05_PCH_AUX           
                                  N26      P1V05_PCH_AUX           
                                  N29      PD_PCH_XCLK_BIASREF     
                                  N32      GND                     
                                  P1       OCP_SFF_BIF2_N          
                                  P3       FM_PCH_DFXTESTMODE      
                                  P5       GND                     
                                  P8       GND                     
                                  P11      GND                     
                                  P15      P1V05_PCH_AUX           
                                  P21      P3V3_AUX                
                                  P24      GND                     
                                  P28      GND                     
                                  P31      GND                     
                                  P37      GND                     
                                  P39      GND                     
                                  P41      GND                     
                                  P43      GND                     
                                  R4       FM_PCH_XTALSEL          
                                  R7       FM_PCH_BIOS_RCVR_MODE   
                                  R13      GND                     
                                  R16      GND                     
                                  R20      GND                     
                                  R23      P1V05_PCH_PLL_AUX       
                                  R26      P1V05_PCH_PLL_AUX       
                                  R29      P1V05_PCH_PLL_AUX       
                                  R36      GND                     
                                  R40      USB3_9_RX_DN            
                                  R42      USB3_9_RX_DP            
                                  T8       FM_PCIE_EDSFF2A_PRSNT_1_N
                                  T15      P3V3_AUX                
                                  T31      GND                     
                                  T37      SATA_P11_TX_DN          
                                  U3       OCP_SFF_BIF0_N          
                                  U5       GND                     
                                  U7       FM_PCIE_EDSFF1A_PRSNT_1_N
                                  U10      GND                     
                                  U13      GND                     
                                  U17      P1V8_PCH_AUX            
                                  U19      P1V8_PCH_AUX            
                                  U20      P1V8_PCH_AUX            
                                  U22      P1V8_PCH_AUX            
                                  U24      P1V8_PCH_AUX            
                                  U25      GND                     
                                  U27      P1V05_PCH_PLL_AUX       
                                  U29      P1V8_PCH_PLL_AUX        
                                  U39      GND                     
                                  V2       GND                     
                                  V8       PCIE_RISER3_PRSNT2_N    
                                  V15      P3V3_AUX                
                                  V31      GND                     
                                  V37      SATA_P11_TX_DP          
                                  W1       FM_PCH_BOOT_BIOS_STRAP  
                                  W3       GND                     
                                  W5       GND                     
                                  W7       RISER3_TYPE_ID          
                                  W10      FM_BMC_READY_R_N        
                                  W13      FM_PCIE_EDSFF4A_PRSNT_1_N
                                  W17      P1V05_PCH_AUX           
                                  W19      P1V05_PCH_AUX           
                                  W20      P1V05_PCH_AUX           
                                  W22      P1V05_PCH_AUX           
                                  W24      P1V05_PCH_AUX           
                                  W25      GND                     
                                  W27      P1V8_PCH_PLL_AUX        
                                  W29      P1V8_PCH_PLL_AUX        
                                  W36      P3E_PCH_BMC_TX_DN       
                                  W39      GND                     
                                  Y2       FM_PLT_BMC_THERMTRIP_R_N
                                  Y4       FM_BIOS_IMAGE_SWAP_N    
                                  Y8       GND                     
                                  Y11      GND                     
                                  Y15      GND                     
                                  Y31      GND                     
                                  Y34      GND                     
                                  Y37      P3E_PCH_BMC_TX_DP       
U10              PCA9546APWR-PCA9546APWR,SMLF,IA 1        PCA9546_PCIE1_ADDR0     
                                  2        PCA9546_PCIE1_ADDR1     
                                  3        PU_RST_SMB_PCIE3_N      
                                  4        SMB_PCIE1_3V3AUX_SDA_R0 
                                  5        SMB_PCIE1_3V3AUX_SCL_R0 
                                  6        SMB_PCIE1_3V3AUX_SDA_R1 
                                  7        SMB_PCIE1_3V3AUX_SCL_R1 
                                  8        GND                     
                                  9        SMB_PCIE1_3V3AUX_SDA_R2 
                                  10       SMB_PCIE1_3V3AUX_SCL_R2 
                                  11       SMB_PCIE1_3V3AUX_SDA_R3 
                                  12       SMB_PCIE1_3V3AUX_SCL_R3 
                                  13       PCA9546_PCIE1_ADDR2     
                                  14       SMB_PCIE1_3V3AUX_SCL_R  
                                  15       SMB_PCIE1_3V3AUX_SDA_R  
                                  16       P3V3_AUX                
U13              9SQ440NQQI8-9SQ440NQQI8,SMLF,IA A1       FM_CK440Q_DEV_25M_EN    
                                  A2       CLK_25M_CK440_CPU1_DN   
                                  A3       CLK_25M_CK440_CPU1_DP   
                                  A4       CLK_25M_CK440_CPU0_DN   
                                  A5       CLK_25M_CK440_CPU0_DP   
                                  A10      SMB_HOST_CLK_3V3AUX_SCL 
                                  A11      CLK_CK440_SMB_ADDR0     
                                  A12      P3V3_AUX_CLK_GEN_VDDXTAL_CK440
                                  A13      XTAL_CLK_GEN1_25M_X1    
                                  A14      GND                     
                                  A16      FM_CLK_CK440_SS_EN      
                                  A17      FM_PLD_CLKS_DEV_EN      
                                  A18      CLK_100M_PE_5_R_DN      
                                  A19      CLK_100M_PE_5_R_DP      
                                  A20      CLK_100M_PE_4_R_DN      
                                  A21      CLK_100M_PE_4_R_DP      
                                  A22      CLK_100M_PE_3_R_DN      
                                  A23      CLK_100M_PE_3_R_DP      
                                  A24      CLK_100M_PE_2_R_DN      
                                  A25      CLK_100M_PE_2_R_DP      
                                  A26      RISER2_CLK2_EN_N        
                                  A27      CLK_100M_PE_1_R_DN      
                                  A28      CLK_100M_PE_1_R_DP      
                                  A30      EDSFF3_CLK_EN_N         
                                  A31      CLK_100M_PE_0_R_DN      
                                  A32      CLK_100M_PE_0_R_DP      
                                  A33      CLK_100M_DB2000_DN      
                                  A34      CLK_100M_DB2000_DP      
                                  A37      CLK_100M_EDSFF3_R_DN    
                                  A38      CLK_100M_EDSFF3_R_DP    
                                  A41      CLK_100M_E1S_3_R_DN     
                                  A42      CLK_100M_E1S_3_R_DP     
                                  A43      CLK_100M_E1S_2_R_DN     
                                  A44      CLK_100M_E1S_2_R_DP     
                                  A47      CLK_100M_CK440_PCH_EXTCLK_R_DN
                                  A48      CLK_100M_CK440_PCH_EXTCLK_R_DP
                                  A49      CLK_100M_E1S_1_R_DN     
                                  A50      CLK_100M_E1S_1_R_DP     
                                  A51      CLK_100M_E1S_0_R_DN     
                                  A52      CLK_100M_E1S_0_R_DP     
                                  A54      PD_CK440_SBI_CLK        
                                  A55      CLK_25M_CK440_ISCLK_REF_DN
                                  A56      CLK_25M_CK440_ISCLK_REF_DP
                                  B1       P3V3_AUX_CLK_GEN_VDDA25M_CK440
                                  B4       PU_CLK_PFT_LOST_N       
                                  B6       P3V3_AUX_CLK_GEN_VDDPT_CK440
                                  B8       SMB_HOST_CLK_3V3AUX_SDA 
                                  B9       CLK_CK440_SMB_ADDR1     
                                  B10      GND                     
                                  B11      XTAL_CLK_GEN1_25M_X2    
                                  B12      GND                     
                                  B14      RISER3_CLK5_EN_N        
                                  B15      RISER3_CLK4_EN_N        
                                  B17      P3V3_AUX_CLK_GEN_VDDA100M_CK440
                                  B19      RISER2_CLK3_EN_N        
                                  B21      P3V3_AUX_CLK_GEN_VDD_CK440
                                  B23      P3V3_AUX_CLK_GEN_VDD_CK440
                                  B27      FM_CLK_GEN1_OE0_N       
                                  B29      P3V3_AUX_CLK_GEN_VDDMXCK_CK440
                                  B32      P3V3_AUX_CLK_GEN_VDDMXCK_CK440
                                  B35      P3V3_AUX_CLK_GEN_VDDMXCK_CK440
                                  B38      FM_CK440_MXCK_25M_100M  
                                  B40      P3V3_AUX_CLK_GEN_VDDMXCK_CK440
                                  B42      PU_CK440_SHFT_LD_N      
                                  B43      PD_CK440_SBI_DATA_IN    
                                  C1       GND                     
U14              IDTQS3VH257QG_SMLF-IDTQS3VH257A 1        FM_SPD_REMOTE_EN        
                                  2        I3C_SPD_DDRABCD_CPU1_R_SCL
                                  3        I3C_SPD_DDRABCD_CPU1_BMC_SCL
                                  4        I3C_SPD_DDRABCD_CPU1_LVC1_R_SCL
                                  5        I3C_SPD_DDRABCD_CPU1_R_SDA
                                  6        I3C_SPD_DDRABCD_CPU1_BMC_SDA
                                  7        I3C_SPD_DDRABCD_CPU1_LVC1_R_SDA
                                  8        GND                     
                                  9        I3C_SPD_DDREFGH_CPU1_LVC1_R_SCL
                                  10       I3C_SPD_DDREFGH_CPU1_BMC_SCL
                                  11       I3C_SPD_DDREFGH_CPU1_R_SCL
                                  12       I3C_SPD_DDREFGH_CPU1_LVC1_R_SDA
                                  13       I3C_SPD_DDREFGH_CPU1_BMC_SDA
                                  14       I3C_SPD_DDREFGH_CPU1_R_SDA
                                  15       PD_I3C_SPD_DDR_CPU1_OE_N
                                  16       P3V3_AUX                
U15              IDTQS3VH257QG_SMLF-IDTQS3VH257A 1        FM_SPD_REMOTE_EN        
                                  2        I3C_SPD_DDRABCD_CPU0_R_SCL
                                  3        I3C_SPD_DDRABCD_CPU0_BMC_SCL
                                  4        I3C_SPD_DDRABCD_CPU0_LVC1_R_SCL
                                  5        I3C_SPD_DDRABCD_CPU0_R_SDA
                                  6        I3C_SPD_DDRABCD_CPU0_BMC_SDA
                                  7        I3C_SPD_DDRABCD_CPU0_LVC1_R_SDA
                                  8        GND                     
                                  9        I3C_SPD_DDREFGH_CPU0_LVC1_R_SCL
                                  10       I3C_SPD_DDREFGH_CPU0_BMC_SCL
                                  11       I3C_SPD_DDREFGH_CPU0_R_SCL
                                  12       I3C_SPD_DDREFGH_CPU0_LVC1_R_SDA
                                  13       I3C_SPD_DDREFGH_CPU0_BMC_SDA
                                  14       I3C_SPD_DDREFGH_CPU0_R_SDA
                                  15       PD_I3C_SPD_DDR_CPU0_OE_N
                                  16       P3V3_AUX                
U16              NC7SZ66M5X_SMLF-NC7SZ66M5X,NC7A 1        JTAG_CPU0_MUX_GTL_TDO   
                                  2        JTAG_MUX_CPU1_GTL_TDI   
                                  3        GND                     
                                  4        FM_CPU_EN_R             
                                  5        P3V3_AUX                
U17              74CBTLV3126PW-74CBTLV3126PW,SMA 1        PWRGD_PVNN_MAIN_CPU0    
                                  2        JTAG_DBP_TMS            
                                  3        JTAG_DBP_CPU_QS_GTL_TMS 
                                  4        PWRGD_PVNN_MAIN_CPU0    
                                  5        JTAG_DBP_TDI            
                                  6        JTAG_QS_MUX_GTL_TDI     
                                  7        GND                     
                                  9        PD_74CB_A9              
                                  10       PWRGD_PVNN_MAIN_CPU0    
                                  11       JTAG_MUX_QS_GTL_TDO     
                                  12       JTAG_DBP_TDO            
                                  13       PWRGD_PVNN_MAIN_CPU0    
                                  14       P3V3_AUX                
U18              74CBTLV3126PW-74CBTLV3126PW,SMA 1        PWRGD_PVNN_MAIN_CPU0    
                                  2        JTAG_DBP_CPU_HOOK9_MBP3_GTL_N
                                  3        DBP_CPU_HOOK9_MBP3_GTL_QS_N
                                  4        PWRGD_PVNN_MAIN_CPU0    
                                  5        JTAG_DBP_CPU_HOOK8_MBP2_GTL_N
                                  6        DBP_CPU_HOOK8_MBP2_GTL_QS_N
                                  7        GND                     
                                  8        H_CPU_PRDY_QS_GTL_N     
                                  9        JTAG_DBP_PRDY_N         
                                  10       PWRGD_PVNN_MAIN_CPU0    
                                  11       H_CPU_PREQ_QS_GTL_N     
                                  12       JTAG_DBP_PREQ_N         
                                  13       PWRGD_PVNN_MAIN_CPU0    
                                  14       P3V3_AUX                
U19              MOSFET_N_SMLF-BSS138K,BSS138K,A D        FM_PSU_THROTTLE_N       
                                  G        FM_PSU_THROTTLE_L       
                                  S        GND                     
U21              NC7SB3157_SMLF-NC7SB3157P6X,NCA 1        JTAG_MUX_CPU1_GTL_TDI   
                                  2        GND                     
                                  3        JTAG_MUX_CPU0_GTL_TDI   
                                  4        JTAG_QS_MUX_GTL_TDI     
                                  5        P3V3_AUX                
                                  6        FM_CPU0_SKTOCC_N        
U22              NC7SB3157_SMLF-NC7SB3157P6X,NCA 1        JTAG_CPU0_MUX_GTL_TDO   
                                  2        GND                     
                                  3        JTAG_CPU1_MUX_GTL_TDO   
                                  4        JTAG_MUX_QS_GTL_TDO     
                                  5        P3V3_AUX                
                                  6        FM_CPU1_SKTOCC_N        
U23              74LVC1G02GW_SMLF-74LVC1G02GW,IA 1        FM_CPU1_SKTOCC_N        
                                  2        FM_CPU0_SKTOCC_N        
                                  3        GND                     
                                  4        FM_CPU_EN               
                                  5        P3V3_AUX                
U24              PCA9548APW-PCA9548APW,SMLF,IC,A 1        PCA9548_PCIE2_ADDR0     
                                  2        PCA9548_PCIE2_ADDR1     
                                  3        PU_RST_SMB_EDSFF_N      
                                  4        SMB_EDSFF1A_3V3AUX_SDA_R1
                                  5        SMB_EDSFF1A_3V3AUX_SCL_R1
                                  6        SMB_EDSFF1B_3V3AUX_SDA_R1
                                  7        SMB_EDSFF1B_3V3AUX_SCL_R1
                                  8        SMB_EDSFF2A_3V3AUX_SDA_R1
                                  9        SMB_EDSFF2A_3V3AUX_SCL_R1
                                  10       SMB_EDSFF2B_3V3AUX_SDA_R1
                                  11       SMB_EDSFF2B_3V3AUX_SCL_R1
                                  12       GND                     
                                  13       SMB_EDSFF3_3V3AUX_SDA_R1
                                  14       SMB_EDSFF3_3V3AUX_SCL_R1
                                  15       SMB_EDSFF4A_3V3AUX_SDA_R1
                                  16       SMB_EDSFF4A_3V3AUX_SCL_R1
                                  17       SMB_EDSFF4B_3V3AUX_SDA_R1
                                  18       SMB_EDSFF4B_3V3AUX_SCL_R1
                                  19       SMB_EDSFF_3V3AUX_SDA_R8 
                                  20       SMB_EDSFF_3V3AUX_SCL_R8 
                                  21       PCA9548_PCIE2_ADDR2     
                                  22       SMB_PCIE2_3V3AUX_SCL    
                                  23       SMB_PCIE2_3V3AUX_SDA    
                                  24       P3V3_AUX                
U27              TPS2553DBVR1-TPS2553DBVR-1,SMLA 1        P5V                     
                                  2        GND                     
                                  3        PU_USB_INT_P5V_EN_N     
                                  4        USB_OC2_INT_N           
                                  5        PD_USB_INT_ILIM         
                                  6        P5V_USB_INT             
U28              PCA9617ADP-PCA9617ADP,SMLF,IC,A 1        PVNN_TERM_CPU0          
                                  2        SMB_PEHPCPU0_GTL_R_SCL  
                                  3        SMB_PEHPCPU0_GTL_R_SDA  
                                  4        GND                     
                                  6        SMB_PEHPCPU0_LVC3_SDA   
                                  7        SMB_PEHPCPU0_LVC3_SCL   
                                  8        P3V3_AUX                
U29              PCA9617ADP-PCA9617ADP,SMLF,IC,A 1        PVNN_TERM_CPU1          
                                  2        SMB_PEHPCPU1_GTL_R_SCL  
                                  3        SMB_PEHPCPU1_GTL_R_SDA  
                                  4        GND                     
                                  6        SMB_PEHPCPU1_LVC3_SDA   
                                  7        SMB_PEHPCPU1_LVC3_SCL   
                                  8        P3V3_AUX                
U30              PCA9617ADP-PCA9617ADP,SMLF,IC,A 1        PVNN_TERM_CPU0          
                                  2        SMB_S3M_CPU0_R_SCL      
                                  3        SMB_S3M_CPU0_R_SDA      
                                  4        GND                     
                                  6        SMB_S3M_CPU0_3V3AUX_SDA 
                                  7        SMB_S3M_CPU0_3V3AUX_SCL 
                                  8        P3V3_AUX                
U31              PCA9617ADP-PCA9617ADP,SMLF,IC,A 1        PVNN_TERM_CPU1          
                                  2        SMB_S3M_CPU1_R_SCL      
                                  3        SMB_S3M_CPU1_R_SDA      
                                  4        GND                     
                                  6        SMB_S3M_CPU1_3V3AUX_SDA 
                                  7        SMB_S3M_CPU1_3V3AUX_SCL 
                                  8        P3V3_AUX                
U36              PCA9546APWR-PCA9546APWR,SMLF,IA 1        PCA9546_PCIE0_ADDR0     
                                  2        PCA9546_PCIE0_ADDR1     
                                  3        PU_RST_SMB_PCIE3_N      
                                  4        SMB_PCIE0_3V3AUX_SDA_R0 
                                  5        SMB_PCIE0_3V3AUX_SCL_R0 
                                  6        SMB_PCIE0_3V3AUX_SDA_R1 
                                  7        SMB_PCIE0_3V3AUX_SCL_R1 
                                  8        GND                     
                                  9        SMB_PCIE0_3V3AUX_SDA_R2 
                                  10       SMB_PCIE0_3V3AUX_SCL_R2 
                                  11       SMB_PCIE0_3V3AUX_SDA_R3 
                                  12       SMB_PCIE0_3V3AUX_SCL_R3 
                                  13       PCA9546_PCIE0_ADDR2     
                                  14       SMB_PCIE0_3V3AUX_SCL_R  
                                  15       SMB_PCIE0_3V3AUX_SDA_R  
                                  16       P3V3_AUX                
U38              9QXL2001BNHGI8-9QXL2001BNHGI8,A A1       CLK_100M_EDSFF2B_R_DP   
                                  A2       CLK_100M_EDSFF2A_R_DN   
                                  A3       CLK_100M_EDSFF2A_R_DP   
                                  A4       CLK_100M_EDSFF1B_1_R_DN 
                                  A5       CLK_100M_EDSFF1B_1_R_DP 
                                  A6       CLK_100M_EDSFF1B_R_DN   
                                  A7       CLK_100M_EDSFF1B_R_DP   
                                  A8       CLK_100M_EDSFF1A_1_R_DN 
                                  A9       CLK_100M_EDSFF1A_1_R_DP 
                                  A10      CLK_100M_EDSFF1A_R_DN   
                                  A11      CLK_100M_EDSFF1A_R_DP   
                                  A12      CLK_100M_OCP_SFF_3_R_DN 
                                  B1       CLK_100M_EDSFF2B_R_DN   
                                  B2       P3V3_DB2000_VDD         
                                  B4       PD_DB2000_SMB_SA0       
                                  B6       P3V3_DB2000_VDDA        
                                  B8       PD_DB2000_SMB_SA1       
                                  B10      FM_DB2000_12_OE_N       
                                  B11      P3V3_DB2000_VDD         
                                  B12      CLK_100M_OCP_SFF_3_R_DP 
                                  C1       CLK_100M_EDSFF4A_R_DP   
                                  C11      FM_DB2000_8_OE_N        
                                  C12      CLK_100M_OCP_SFF_2_R_DN 
                                  D1       CLK_100M_EDSFF4A_R_DN   
                                  D12      CLK_100M_OCP_SFF_2_R_DP 
                                  E1       CLK_100M_EDSFF4B_R_DP   
                                  E2       FM_DB2000_VSBEN         
                                  E11      FM_DB2000_8_OE_N        
                                  E12      FM_DB2000_8_OE_N        
                                  F1       CLK_100M_EDSFF4B_R_DN   
                                  F12      CLK_100M_OCP_SFF_1_R_DN 
                                  G1       CLK_100M_DB2000_DP      
                                  G12      CLK_100M_OCP_SFF_1_R_DP 
                                  H1       CLK_100M_DB2000_DN      
                                  H2       P3V3_DB2000_VDDR        
                                  H11      FM_DB2000_8_OE_N        
                                  H12      CLK_100M_OCP_SFF_0_R_DN 
                                  J1       CLK_100M_DB2000_CPU0_BCLK0_DP
                                  J12      CLK_100M_OCP_SFF_0_R_DP 
                                  K1       CLK_100M_DB2000_CPU0_BCLK0_DN
                                  K11      FM_DB2000_1_OE_N        
                                  K12      CLK_100M_DB2000_CPU1_BCLK3_DN
                                  L1       CLK_100M_DB2000_CPU0_BCLK1_DP
                                  L2       P3V3_DB2000_VDD         
                                  L4       SMB_HOST_DB2000_3V3AUX_SDA
                                  L5       SMB_HOST_DB2000_3V3AUX_SCL
                                  L8       FM_DB2000_1_OE_N        
                                  L10      FM_DB2000_1_OE_N        
                                  L11      P3V3_DB2000_VDD         
                                  L12      CLK_100M_DB2000_CPU1_BCLK3_DP
                                  M1       CLK_100M_DB2000_CPU0_BCLK1_DN
                                  M2       CLK_100M_DB2000_CPU0_BCLK2_DP
                                  M3       CLK_100M_DB2000_CPU0_BCLK2_DN
                                  M4       CLK_100M_DB2000_CPU0_BCLK3_DP
                                  M5       CLK_100M_DB2000_CPU0_BCLK3_DN
                                  M6       FM_DB2000_DEV_EN        
                                  M7       CLK_100M_DB2000_CPU1_BCLK0_DP
                                  M8       CLK_100M_DB2000_CPU1_BCLK0_DN
                                  M9       CLK_100M_DB2000_CPU1_BCLK1_DP
                                  M10      CLK_100M_DB2000_CPU1_BCLK1_DN
                                  M11      CLK_100M_DB2000_CPU1_BCLK2_DP
                                  M12      CLK_100M_DB2000_CPU1_BCLK2_DN
                                  TH       GND                     
U40              TPS259520DSGR-TPS259520DSGR,SMA 1        P3V3_E1S_0_DVDT         
                                  2        FM_P3V3_E1S_0_EN        
                                  3        P3V3_AUX                
                                  4        P3V3_AUX                
                                  5        P3V3_E1S_0              
                                  6        P3V3_E1S_0_FLT_N        
                                  7        P3V3_E1S_0_ILM          
                                  8        GND                     
                                  TH       GND                     
U49              MOSFET_N_SMLF-BSS138K,BSS138K,A D        HP_LVC3_OCP_V3_1_PRSNT2 
                                  G        HP_LVC3_OCP_V3_1_PRSNT2_N
                                  S        GND                     
U50              SN74LVC1G08DBVR_SMLF-SN74LVC1GA 1        HP_OCP_V3_1_EN          
                                  2        HP_LVC3_OCP_V3_1_PRSNT2 
                                  3        GND                     
                                  4        HP_LVC3_OCP_V3_1_EN     
                                  5        P3V3_AUX                
U51              PCA9555PW_SMLF-PCA9555PW,IC,TMA 1        FM_SMB_CPU0_ALERT       
                                  2        PD_SMB_OCP1_HP_ADD1     
                                  3        PD_SMB_OCP1_HP_ADD2     
                                  6        HP_OCP_V3_1_EN          
                                  7        HP_LVC3_OCP_V3_1_ATTN_OUT_SW_N
                                  8        HP_LVC3_OCP_V3_1_PRSNT2_N
                                  9        HP_LVC3_OCP_V3_1_FAULT_N
                                  12       GND                     
                                  21       PD_SMB_OCP1_HP_ADD0     
                                  22       SMB_PEHPCPU0_LVC3_R_SCL 
                                  23       SMB_PEHPCPU0_LVC3_R_SDA 
                                  24       P3V3_AUX                
U52              APX80929SAG7-APX809-29SAG-7,SMA 1        GND                     
                                  2        HP_LVC3_OCP_V3_1_PWRGD  
                                  3        P3V3_AUX                
U53              SN74LVC1G08DBVR_SMLF-SN74LVC1GA 1        HP_LVC3_OCP_V3_1_PWRGD  
                                  2        RST_OCP_V3_1_N          
                                  3        GND                     
                                  4        RST_HP_OCP_V3_1_N       
                                  5        P3V3_AUX                
U54              74LVC1G07GV-74LVC1G07GV,SMLF,IA 2        M2_SSD0_CLKREQ_EN_N     
                                  3        GND                     
                                  4        M2_SSD0_CLKREQ_LV_EN_N  
                                  5        PGPPA_AUX               
U56              TPS259520DSGR-TPS259520DSGR,SMA 1        P3V3_OCP_DVDT_1         
                                  2        HP_LVC3_OCP_V3_1_EN     
                                  3        P3V3_AUX                
                                  4        P3V3_AUX                
                                  5        P3V3_OCP_SFF            
                                  6        HP_LVC3_OCP_V3_1_FAULT_N
                                  7        P3V3_OCP_ILM1           
                                  8        GND                     
                                  TH       GND                     
U57              TPS259824ONRGER-TPS259824ONRGEA 1        P12V_AUX                
                                  2        P12V_AUX                
                                  3        P12V_AUX                
                                  4        GND                     
                                  5        GND                     
                                  6        HP_LVC3_OCP_V3_1_EN     
                                  7        P12V_OCP_ITIMER_1       
                                  8        P12V_OCP_ILIM1          
                                  9        P12V_OCP_IMON_1         
                                  10       P12V_OCP_RETRY1         
                                  11       P12V_OCP_NRETRY1        
                                  12       P12V_OCP_LDSTRT11       
                                  13       HP_LVC3_OCP_V3_1_HSC_PWRGD
                                  14       GND                     
                                  15       P12V_OCP_DVDT_1         
                                  16       P12V_AUX                
                                  17       P12V_OCP_SFF            
                                  18       P12V_OCP_SFF            
                                  19       P12V_OCP_SFF            
                                  20       P12V_OCP_SFF            
                                  21       P12V_OCP_SFF            
                                  22       P12V_OCP_SFF            
                                  23       P12V_OCP_SFF            
                                  24       P12V_OCP_SFF            
                                  25       P12V_AUX                
                                  26       GND                     
U58              SN74LVC2G07DCKR_SMLF-SN74LVC2GA 1        OCP_SFF_PRSNT0_R_N      
                                  2        GND                     
                                  3        OCP_SFF_PRSNT1_R_N      
                                  4        HP_LVC3_OCP_V3_1_PRSNT2_N_R
                                  5        P3V3_AUX                
                                  6        HP_LVC3_OCP_V3_1_PRSNT2_N_R
U59              SN74LVC2G07DCKR_SMLF-SN74LVC2GA 1        OCP_SFF_PRSNT2_R_N      
                                  2        GND                     
                                  3        OCP_SFF_PRSNT3_R_N      
                                  4        HP_LVC3_OCP_V3_1_PRSNT2_N_R
                                  5        P3V3_AUX                
                                  6        HP_LVC3_OCP_V3_1_PRSNT2_N_R
U60              NC7SB3157_SMLF-NC7SB3157P6X,NCA 1        IRQ_LPC_PIRQA_N_ESPI_ALERT0_R_N
                                  2        GND                     
                                  3        IRQ_LPC_SERIRQ_ESPI_CS1_N
                                  4        IRQ_ESPI_LPC_SERIRQ_ALERT_N
                                  5        PGPPA_AUX               
                                  6        FM_ESPI_PLD_EN          
U61              NC7SB3157_SMLF-NC7SB3157P6X,NCA 1        RST_ESPI_RESET_N        
                                  2        GND                     
                                  3        RST_PLTRST_B_MUX_N      
                                  4        ESPI_BMC_LPC_RST_N      
                                  5        PGPPA_AUX               
                                  6        FM_ESPI_PLD_EN          
U62              BAS70057F-BAS70-05-7-F,SMLF,ICA 1        P3V_BAT_R               
                                  2        P3V3_AUX                
                                  3        P3V3_RTC_AUX            
U63              TMP75AIDR-TMP75AIDR,SMLF,IC,ALA 1        SMB_TMP75_1_3V3AUX_SDA_R
                                  2        SMB_TMP75_1_3V3AUX_SCL_R
                                  4        GND                     
                                  5        TMP75_1_ADDR2           
                                  6        TMP75_1_ADDR1           
                                  7        TMP75_1_ADDR0           
                                  8        P3V3_AUX                
U64              M24128BWDW6TP-M24128-BWDW6TP,SA 1        MB_FRU_ADDR0            
                                  2        MB_FRU_ADDR1            
                                  3        MB_FRU_ADDR2            
                                  4        GND                     
                                  5        SMB_FRU_3V3AUX_SDA_R    
                                  6        SMB_FRU_3V3AUX_SCL_R    
                                  7        PD_MB_FRU_WP            
                                  8        P3V3_AUX                
U65              TMP75AIDR-TMP75AIDR,SMLF,IC,ALA 1        SMB_TMP75_2_3V3AUX_SDA_R
                                  2        SMB_TMP75_2_3V3AUX_SCL_R
                                  4        GND                     
                                  5        TMP75_2_ADDR2           
                                  6        TMP75_2_ADDR1           
                                  7        TMP75_2_ADDR0           
                                  8        P3V3_AUX                
U66              74HC1G126GW-74HC1G126GW,SMLF,IA 1        OCP_SFF_AUX_PWR_EN_R1   
                                  2        FM_OCP_SFF_PWR_GOOD     
                                  3        GND                     
                                  4        FB_BMC_ISOLATE          
                                  5        P3V3_AUX                
U67              74CBTLV3126PW-74CBTLV3126PW,SMA 1        FB_BMC_ISOLATE          
                                  2        NCSI_BMC_RXD1_R         
                                  3        NCSI_OCP_SFF_RXD1       
                                  4        FB_BMC_ISOLATE          
                                  5        NCSI_BMC_RXD0_R         
                                  6        NCSI_OCP_SFF_RXD0       
                                  7        GND                     
                                  8        NCSI_OCP_SFF_CRS_DV     
                                  9        NCSI_BMC_CRS_DV_R       
                                  10       FB_BMC_ISOLATE          
                                  11       OCP_SFF_RBT_ARB_IN      
                                  12       OCP_SFF_RBT_ARB_IN      
                                  13       FB_BMC_ISOLATE          
                                  14       P3V3_AUX                
U68              74CBTLV3126PW-74CBTLV3126PW,SMA 1        FB_BMC_ISOLATE          
                                  2        NCSI_BMC_TXD1_R         
                                  3        NCSI_OCP_SFF_TXD1       
                                  4        FB_BMC_ISOLATE          
                                  5        NCSI_BMC_TXD0_R         
                                  6        NCSI_OCP_SFF_TXD0       
                                  7        GND                     
                                  8        NCSI_OCP_SFF_TX_EN      
                                  9        NCSI_BMC_TX_EN_R        
                                  10       FB_BMC_ISOLATE          
                                  11       OCP_SFF_RBT_ARB_OUT     
                                  12       OCP_SFF_RBT_ARB_OUT     
                                  13       FB_BMC_ISOLATE          
                                  14       P3V3_AUX                
U70              MOSFET_N_SMLF-BSS138K,BSS138K,A D        FM_PLD_CLKS_OE_R_N      
                                  G        FM_PLD_CLKS_DEV_EN      
                                  S        GND                     
U73              MOSFET_N_SMLF-BSS138K,BSS138K,B D        FM_HBM_VPP_SEL_CPU0_D   
                                  G        FM_HBM2_HBM3_VPP_SEL    
                                  S        SH_PVPP_HBM_CPU0_N      
U74              MOSFET_N_SMLF-BSS138K,BSS138K,A D        FM_HBM_VPP_SEL_CPU1_D   
                                  G        FM_HBM2_HBM3_VPP_SEL    
                                  S        SH_PVPP_HBM_CPU1_N      
U75              SN74LVC1G17DCKR-SN74LVC1G17DCKA 2        RST_HP_OCP_V3_1_N       
                                  3        GND                     
                                  4        RST_OCP_V3_1_BUF_N      
                                  5        P3V3_AUX                
U77              74CBTLV3126PW-74CBTLV3126PW,SMB 1        OCP_SFF_AUX_PWR_EN_R2   
                                  2        OCP_SFF_BIF2_N          
                                  3        OCP_SFF_ISO_BIF2_EN     
                                  4        OCP_SFF_AUX_PWR_EN_R2   
                                  5        OCP_SFF_BIF1_N          
                                  6        OCP_SFF_ISO_BIF1_EN     
                                  7        GND                     
                                  8        OCP_SFF_ISO_BIF0_EN     
                                  9        OCP_SFF_BIF0_N          
                                  10       OCP_SFF_AUX_PWR_EN_R2   
                                  14       P3V3_AUX                
U79              SLG55221120010VTR-SLG55221-120A 1        P5V_AUX                 
                                  2        PWRGD_P5V               
                                  3        P3V3                    
                                  4        GND                     
                                  5        P3V3_AUX                
                                  6        P3V3                    
                                  7        VR_P3V3_EN_D_R          
                                  8        PWRGD_P3V3_R            
                                  TH       GND                     
U81              MP5981GLUZ-MP5981GLU-Z,SMLF,ICA 1        P12V_FRONT_CPU          
                                  2        P12V_FRONT_CPU          
                                  3        PU_MP5981_1_D_OC        
                                  4        MP5981_1_ON_PD          
                                  5        PU_MP5981_1_GOK         
                                  6        GND                     
                                  7        GND                     
                                  8        PD_MP5981_1_MODE        
                                  9        P12V_AUX                
                                  10       P12V_AUX                
                                  11       P12V_AUX                
                                  12       P12V_AUX                
                                  13       P12V_AUX                
                                  14       P12V_AUX                
                                  15       P12V_AUX                
                                  16       P12V_AUX                
                                  17       GND                     
                                  19       MPS5981_1_SS            
                                  20       GND                     
                                  21       VDD3                    
                                  22       TP_MP5981_1_IMON        
                                  23       MP5981_1_CS             
                                  24       MP5981_1_CLREF          
                                  25       P12V_FRONT_CPU          
                                  26       P12V_FRONT_CPU          
                                  27       P12V_FRONT_CPU          
                                  28       P12V_FRONT_CPU          
                                  29       P12V_FRONT_CPU          
                                  30       P12V_FRONT_CPU          
                                  31       P12V_FRONT_CPU          
                                  32       P12V_FRONT_CPU          
                                  TH       GND                     
U82              74LVC1G126GW_SMLF-74LVC1G126GWA 1        PU_OCP_SFF_WAKE_OE      
                                  2        IRQ_LVC3_OCP_SFF_WAKE_N 
                                  3        GND                     
                                  4        OCP_SFF_WAKE_BUFF_N     
                                  5        P3V3_AUX                
U83              GTL2014PW-GTL2014PW,SMLF,IC,ALA 1        PU_GTL2014_BMC_JTAG_DIR_2
                                  2        PD_JTAG_DBP_B0          
                                  3        JTAG_DBP_PRDY_R_N       
                                  4        PD_GTL2014_BMC_JTAG_VREF_2
                                  5        PD_JTAG_DBP_B2          
                                  6        JTAG_DBP_FB_TDO         
                                  7        GND                     
                                  8        GND                     
                                  9        JTAG_BMC_DBP_TDO_R      
                                  11       GND                     
                                  12       JTAG_DBP_BMC_PRDY_R1_N  
                                  14       P3V3_AUX                
U84              GTL2014PW-GTL2014PW,SMLF,IC,ALA 1        PU_GTL2014_BMC_JTAG_DIR_1
                                  2        JTAG_DBP_PREQ_R_N       
                                  3        FM_CPU_FBRK_DEBUG_N     
                                  4        PD_GTL2014_BMC_JTAG_VREF_1
                                  5        JTAG_DBP_FB_TDI         
                                  6        JTAG_DBP_FB_TMS         
                                  7        GND                     
                                  8        GND                     
                                  9        JTAG_BMC_DBP_TMS_R      
                                  10       JTAG_BMC_DBP_TDI_R      
                                  11       GND                     
                                  12       FM_BMC_CPU_FBRK_OUT_N   
                                  13       JTAG_DBP_BMC_PREQ_R1_N  
                                  14       P3V3_AUX                
U85              NC7SB3157_SMLF-NC7SB3157P6X,NCA 1        JTAG_BMC_PCH_TCK        
                                  2        GND                     
                                  3        JTAG_BMC_CPU_TCK        
                                  4        JTAG_BMC_DBP_TCK        
                                  5        P3V3_AUX                
                                  6        FM_JTAG_TCK_MUX_SEL     
U86              74CBTLV3126PW-74CBTLV3126PW,SMA 1        PD_JTAG_BMC_NTRST_N     
                                  2        FM_BMC_EN_DET           
                                  4        JTAG_BMC_CPU_TCK        
                                  5        FM_BMC_EN_DET           
                                  6        JTAG_DBP_CPU_GTL_TCK_R1 
                                  7        GND                     
                                  8        JTAG_DBP_TCK_PCH_R      
                                  9        FM_BMC_EN_DET           
                                  10       JTAG_BMC_PCH_TCK        
                                  12       FM_BMC_EN_DET           
                                  13       PD_JTAG_BMC_NTRST_N     
                                  14       P3V3_AUX                
U87              MOSFET_N_SMLF-BSS138K,BSS138K,A D        P1V05_PCH_AUX           
                                  G        FM_REMOTE_DEBUG_DET_R   
                                  S        FM_BMC_EN_DET           
U89              MOSFET_N_SMLF-BSS138K,BSS138K,A D        FM_PLD_HEARTBEAT_LVC3_D 
                                  G        FM_PLD_HEARTBEAT_LVC3   
                                  S        GND                     
U90              PI6CV304LE-PI6CV304LE,SMLF,IC,A 1        CLK_50M_RMII_R          
                                  2        CLK_50M_EN              
                                  3        CLK_50M_BMC_MAC_R       
                                  4        GND                     
                                  5        CLK_50M_NCSI_OCP_1      
                                  6        P3V3_AUX                
U94              ADM1086AKSZREEL7-ADM1086AKSZ-RA 1        FM_COMP_P3V3_AUX_ENIN   
                                  2        GND                     
                                  3        FM_COMP_P3V3_AUX_VIN    
                                  4        PWRGD_DSW_PWROK_R1      
                                  5        FM_COMP_P3V3_STBY_CEXT  
                                  6        P3V3_AUX                
U95              SN74LVC1G07DCKR-SN74LVC1G07DCKA 2        PWRGD_DSW_PWROK_R1      
                                  3        GND                     
                                  4        PWRGD_DSW_PWROK_R2      
                                  5        P3V3_AUX                
U96              TS3A24157RSER-TS3A24157RSER,SMA 1        JTAG_BMC_PLD_TDI        
                                  2        JTAG_BMC_DBP_TDI        
                                  3        JTAG_BMC_PLD_TDO        
                                  4        JTAG_BMC_DBP_TDO        
                                  5        GND                     
                                  6        JTAG_BMC_TDO            
                                  7        FM_JTAG_BMC_MUX_SEL     
                                  8        FM_JTAG_BMC_MUX_SEL     
                                  9        JTAG_BMC_TDI            
                                  10       P3V3_AUX                
U97              TS3A24157RSER-TS3A24157RSER,SMA 1        JTAG_BMC_PLD_TMS        
                                  2        JTAG_BMC_DBP_TMS        
                                  3        JTAG_BMC_PLD_TCK        
                                  4        JTAG_BMC_DBP_TCK        
                                  5        GND                     
                                  6        JTAG_BMC_TCK            
                                  7        FM_JTAG_BMC_MUX_SEL     
                                  8        FM_JTAG_BMC_MUX_SEL     
                                  9        JTAG_BMC_TMS            
                                  10       P3V3_AUX                
U98              PCA9306DCTR-PCA9306DCTR,SMLF,IA 1        GND                     
                                  2        P1V8_PCH_AUX            
                                  3        SMB_M2_P0_1V8AUX_SCL    
                                  4        SMB_M2_P0_1V8AUX_SDA    
                                  5        SMB_SENSOR_M2_P0_3V3AUX_SDA
                                  6        SMB_SENSOR_M2_P0_3V3AUX_SCL
                                  7        P3V3_AUX                
                                  8        SMB_PCIE_M2_EN          
U99              RT9818C44GV-RT9818C-44GV,SMLF,A 1        PWRGD_P5V               
                                  2        GND                     
                                  3        P5V                     
U101             SN74LVC1G17DCKR-SN74LVC1G17DCKA 2        IRQ_BMC_PCH_NMI_R       
                                  3        GND                     
                                  4        IRQ_BMC_PCH_NMI_R1      
                                  5        PGPPA_AUX               
U102             MAX9634FEUKT-MAX9634FEUK+T,SMLA 1        GND                     
                                  2        GND                     
                                  4        P12V_S3_AUX_CPU0_NVDIMM_ISENSE_
                                  5        P12V_S3_AUX_CPU0_NVDIMM_ISENS_1
U103             MAX9634FEUKT-MAX9634FEUK+T,SMLA 1        GND                     
                                  2        GND                     
                                  4        P12V_S3_AUX_CPU1_NVDIMM_ISENSE_
                                  5        P12V_S3_AUX_CPU1_NVDIMM_ISENS_1
U104             74LVC1G07GV-74LVC1G07GV,SMLF,IA 2        FM_SYS_THROTTLE_R_N     
                                  3        GND                     
                                  4        OCP_SFF_PWRBRK_BUFF_N   
                                  5        P3V3_AUX                
U105             ADS1015IDGSR-ADS1015IDGSR,SMLFA 1        VOL_SEN_ADDR            
                                  2        VOL_SEN_ALERT           
                                  3        GND                     
                                  4        P3V3_AUX_SENSE          
                                  5        P3V3_SENSE              
                                  6        P3V3_RTC_AUX_SENSE      
                                  7        P12V_AUX_SENSE          
                                  8        P3V3_AUX                
                                  9        SMB_SEN_3V3AUX_SDA      
                                  10       SMB_SEN_3V3AUX_SCL      
U107             MP5981GLUZ-MP5981GLU-Z,SMLF,ICA 1        P12V_REAR_CPU           
                                  2        P12V_REAR_CPU           
                                  3        PU_MP5981_0_D_OC        
                                  4        MP5981_0_ON_PD          
                                  5        PU_MP5981_0_GOK         
                                  6        GND                     
                                  7        GND                     
                                  8        PD_MP5981_0_MODE        
                                  9        P12V_AUX                
                                  10       P12V_AUX                
                                  11       P12V_AUX                
                                  12       P12V_AUX                
                                  13       P12V_AUX                
                                  14       P12V_AUX                
                                  15       P12V_AUX                
                                  16       P12V_AUX                
                                  17       GND                     
                                  19       MPS5981_SS              
                                  20       GND                     
                                  21       VDD3                    
                                  22       TP_MP5981_0_IMON        
                                  23       MP5981_0_CS             
                                  24       MP5981_0_CLREF          
                                  25       P12V_REAR_CPU           
                                  26       P12V_REAR_CPU           
                                  27       P12V_REAR_CPU           
                                  28       P12V_REAR_CPU           
                                  29       P12V_REAR_CPU           
                                  30       P12V_REAR_CPU           
                                  31       P12V_REAR_CPU           
                                  32       P12V_REAR_CPU           
                                  TH       GND                     
U117             TPS3897PDRYR-TPS3897PDRYR,SMLFA 1        FM_COMP_P3V3_AUX_ENIN   
                                  2        GND                     
                                  3        FM_COMP_P3V3_AUX_VIN    
                                  4        PWRGD_DSW_PWROK_R1      
                                  5        FM_COMP_P3V3_STBY_CEXT  
                                  6        P3V3_AUX                
U121             MAX11607EUAT-MAX11607EUA+T,SMLA 1        P3V3_AUX_SENSE          
                                  2        P3V3_SENSE              
                                  3        P3V3_RTC_AUX_SENSE      
                                  4        P12V_AUX_SENSE          
                                  5        SMB_SEN_3V3AUX_SCL      
                                  6        SMB_SEN_3V3AUX_SDA      
                                  7        GND                     
                                  8        P3V3_AUX                
U122             10M04SAU324I7G-10M04SAU324I7G,A A1       GND                     
                                  A2       FM_JTAG_BMC_PLD_MUX_SEL 
                                  A3       FM_JTAG_TCK_MUX_SEL     
                                  A4       FM_BMC_DBP_PRESENT_R_N  
                                  A5       FM_ESPI_PLD_R_EN        
                                  A7       FM_SPD_REMOTE_EN_R      
                                  A8       FM_PLD_CLKS_DEV_R_EN    
                                  A9       FM_PLD_CLK_25M_R_EN     
                                  A10      FM_PS_PWROK_DLY_SEL     
                                  A11      FM_PVCCIN_CPU0_R_EN     
                                  A12      FM_PVCCINFAON_CPU0_R_EN 
                                  A13      FM_PVCCFA_EHV_CPU0_R_EN 
                                  A14      FM_PVCCD_HV_CPU0_EN     
                                  A15      FM_PVCCFA_EHV_FIVRA_CPU0_R_EN
                                  A16      FM_PVNN_MAIN_CPU0_EN    
                                  A17      FM_ADR_MODE1_R          
                                  A18      GND                     
                                  B1       PWRGD_FAIL_CPU1_CD      
                                  B2       FM_FORCE_PWRON_LVC3     
                                  B6       GND                     
                                  B8       FM_PCHHOT_R_N           
                                  B9       USB_OC1_REAR_N          
                                  B10      GND                     
                                  B11      IRQ_PVCCD_CPU0_VRHOT_LVC3_N
                                  B12      IRQ_PVCCD_CPU1_VRHOT_LVC3_N
                                  B13      VOL_SEN_ALERT_R         
                                  B14      FM_RISER2_JTAG_SEL_PLD_N
                                  B15      GND                     
                                  B16      SMB_PCIE_3V3AUX_B_SCL   
                                  B17      SMB_PCIE_3V3AUX_B_SDA   
                                  B18      SGPIO_BMC_LD_N          
                                  C1       PWRGD_FAIL_CPU1_GH      
                                  C2       PWRGD_FAIL_CPU0_CD      
                                  C3       P3V3_AUX                
                                  C4       FM_PVPP_HBM_CPU0_EN     
                                  C5       FM_PVPP_HBM_CPU1_EN     
                                  C6       FM_P5V_EN               
                                  C7       FM_AUX_SW_EN            
                                  C8       FM_PCH_P1V8_AUX_EN      
                                  C9       FM_P1V05_PCH_AUX_EN     
                                  C10      FM_HBM2_HBM3_VPP_SEL    
                                  C11      FM_PVCCIN_CPU1_R_EN     
                                  C12      FM_PVCCINFAON_CPU1_R_EN 
                                  C13      FM_PVCCFA_EHV_CPU1_R_EN 
                                  C14      FM_PVCCD_HV_CPU1_EN     
                                  C15      FM_PVCCFA_EHV_FIVRA_CPU1_R_EN
                                  C16      FM_PVNN_MAIN_CPU1_EN    
                                  C17      RST_MB_STBY_R_N         
                                  D1       IRQ0_A57_R              
                                  D2       PWRGD_FAIL_CPU0_GH      
                                  D3       GND                     
                                  D4       PWRGD_FAIL_CPU0_AB      
                                  D5       FM_PLD_HEARTBEAT_LVC3   
                                  D6       FM_PLD_REV_N            
                                  D7       JTAG_DBP_BMC_PRDY_R_N   
                                  D8       JTAG_DBP_BMC_PREQ_R_N   
                                  D9       FM_BIOS_POST_CMPLT_BMC_N
                                  D10      FM_BMC_RSTBTN_OUT_N     
                                  D11      P3V3_AUX                
                                  D12      IRQ_PDB_R_N             
                                  D13      FM_BMC_READY_R_PLD_N    
                                  D14      FM_DIS_PS_PWROK_DLY     
                                  D15      FM_CPU1_PKGID2          
                                  D16      FM_CPU1_PKGID1          
                                  D17      FM_CPU1_PKGID0          
                                  D18      FM_CPU1_SKTOCC_LVT3_PLD_N
                                  E1       IRQ_BMC_CPU_NMI_R1      
                                  E2       FP_DPLD_ANAIN1          
                                  E3       GND                     
                                  E4       PWRGD_FAIL_CPU0_EF      
                                  E5       FM_DIMM_12V_CPS_SX_N    
                                  E6       GND                     
                                  E7       P3V3_AUX                
                                  E8       P3V3_AUX                
                                  E9       P3V3_AUX                
                                  E10      GND                     
                                  E11      P3V3_AUX                
                                  E12      P3V3_AUX                
                                  E13      GND                     
                                  E14      FM_PCH_CRASHLOG_TRIG_R_N
                                  E15      FM_RST_PERST_BIT2       
                                  E16      FM_RST_PERST_BIT1       
                                  E17      FM_RST_PERST_BIT0       
                                  E18      FM_THROTTLE_R_N         
                                  F2       ROT_P1_RST_IND_N_R      
                                  F3       P3V3_AUX_DPLD_ADC_VREF  
                                  F4       PVCCA_AUX_PLD           
                                  F5       FM_BIOS_DEBUG_EN_N      
                                  F6       PVCCA_AUX_PLD           
                                  F7       PD_MAIN_FPGA_F7         
                                  F8       GND                     
                                  F9       P3V3_AUX                
                                  F10      PCIE_M2_SSD0_PRSNT_N    
                                  F11      SMB_SML1_PMBUS_3V3AUX_PLD_SCL
                                  F12      SMB_SML1_PMBUS_3V3AUX_PLD_SDA
                                  F13      P3V3_AUX                
                                  F14      PVCCA_AUX_PLD           
                                  F15      FM_CPU0_PKGID0          
                                  F16      FM_CPU0_PKGID1          
                                  F17      GND                     
                                  F18      FM_CPU0_PKGID2          
                                  G1       FM_PSU_THROTTLE_N       
                                  G2       GND                     
                                  G3       IRQ_PCH_CPU_NMI_EVENT_N 
                                  G4       GND                     
                                  G5       P3V3_AUX                
                                  G6       PWRGD_FAIL_CPU1_AB      
                                  G7       VIRTUAL_RESEAT          
                                  G8       PU_MAIN_FPGA_STATUS_N   
                                  G9       PD_MAIN_FPGA_CONFIG_SEL 
                                  G10      FM_UV_ADR_TRIGGER_N     
                                  G11      FM_PCH_PRSNT_N          
                                  G12      FM_SLP_SUS_RSM_RST_N    
                                  G13      P3V3_AUX                
                                  G14      P3V3_AUX                
                                  G15      FM_CPU0_SKTOCC_LVT3_PLD_N
                                  G16      IRQ_CPU0_VRHOT_N        
                                  G17      IRQ_CPU1_VRHOT_N        
                                  G18      FM_SYS_THROTTLE_R_N     
                                  H2       VIRTUAL_RESEAT_FPGA_R_N 
                                  H3       JTAG_PLD_TDI_R          
                                  H4       JTAG_PLD_TDO_R          
                                  H5       P3V3_AUX                
                                  H6       PWRGD_FAIL_CPU1_EF      
                                  H7       JTAG_PLD_JTAGEN         
                                  H8       PU_MAIN_FPGA_CONFIG_DONE
                                  H9       PU_MAIN_FPGA_CONFIG_N   
                                  H10      P3V3_AUX                
                                  H11      PWRGD_PCH_PWROK_R       
                                  H12      PWRGD_SYS_PWROK_R       
                                  H13      P3V3_AUX                
                                  H14      GND                     
                                  H15      RST_PCIE_CPU0_DEV_PERST_N
                                  H16      RST_PCIE_CPU1_DEV_PERST_N
                                  H17      RST_PCIE_PCH_DEV_PERST_N
                                  H18      RST_PLTRST_PLD_B_N      
                                  J1       SMB_PLD_3V3AUX_SDA_R    
                                  J2       SMB_PLD_3V3AUX_SCL_R    
                                  J3       FM_OCP_SFF_PWR_GOOD_R   
                                  J4       FM_PCH_PLD_GLB_RST_WARN_N
                                  J5       P3V3_AUX                
                                  J6       FM_TPM_PRSNT_R_N        
                                  J7       JTAG_PLD_TMS_R          
                                  J8       JTAG_PLD_TCK_R          
                                  J9       P3V3_AUX                
                                  J10      GND                     
                                  J11      SGPIO_BMC_DIN_R         
                                  J12      SGPIO_BMC_CLK           
                                  J13      P3V3_AUX                
                                  J14      P3V3_AUX                
                                  J15      FM_CPU0_PROC_ID0        
                                  J16      FM_CPU0_PROC_ID1        
                                  J17      GND                     
                                  J18      FM_RISER1_JTAG_SEL_PLD_N
                                  K3       PU_RST_DEDI_BUSY_PLD_N  
                                  K4       FM_BMC_SUSACK_R_N       
                                  K5       P3V3_AUX                
                                  K6       GND                     
                                  K7       OCP_SFF_AUX_PWR_EN      
                                  K8       PWRGD_PVCCFA_EHV_CPU1   
                                  K9       GND                     
                                  K10      P3V3_AUX                
                                  K11      RST_PLTRST_PLD_N        
                                  K12      RST_RSMRST_PLD_R_N      
                                  K13      GND                     
                                  K14      P3V3_AUX                
                                  K15      FM_S3M_CPU0_CPLD_CONFIG_N
                                  K16      FM_S3M_CPU1_CPLD_CONFIG_N
                                  K17      FM_CPU1_PROC_ID0        
                                  K18      FM_CPU1_PROC_ID1        
                                  L1       FM_S3M_CPU0_CPLD_CRC_ERROR
                                  L2       FM_S3M_CPU1_CPLD_CRC_ERROR
                                  L3       CLK_25M_OSC_MAIN_FPGA   
                                  L4       GND                     
                                  L5       P3V3_AUX                
                                  L6       P3V3_AUX                
                                  L7       PWRGD_PVPP_HBM_CPU1     
                                  L8       PWRGD_PVCCFA_EHV_FIVRA_CPU1
                                  L9       P3V3_AUX                
                                  L10      PWRGD_DRAMPWRGD_CPU0_GH_R_LVC1
                                  L11      FM_ADR_ACK_R            
                                  L12      FM_ADR_MODE0_R          
                                  L13      P3V3_AUX                
                                  L14      P3V3_AUX                
                                  L15      FM_ADR_COMPLETE         
                                  L16      FM_ADR_TRIGGER_N        
                                  L17      FM_SLPS3_PLD_N          
                                  L18      FM_SLPS4_PLD_N          
                                  M1       PWRGD_P3V3_AUX_PLD      
                                  M2       PWRGD_PVCCD_HV_CPU0     
                                  M3       PWRGD_PVCCD_HV_CPU1     
                                  M4       PWRGD_PVCCFA_EHV_CPU0   
                                  M5       P3V3_AUX                
                                  M6       PVCCA_AUX_PLD           
                                  M7       IRQ_SML1_PMBUS_BMC_ALERT_N
                                  M8       H_CPU1_MON_FAIL_PLD_LVC1_N
                                  M9       RST_CPU1_LVC1_R_N       
                                  M10      PWRGD_DRAMPWRGD_CPU0_CD_R_LVC1
                                  M11      SGPIO_DEBUG_PLD_CLK     
                                  M12      SGPIO_DEBUG_PLD_DOUT    
                                  M13      P3V3_AUX                
                                  M14      GND                     
                                  M15      SGPIO_DEBUG_PLD_DIN     
                                  M16      SGPIO_DEBUG_PLD_LD_N    
                                  M17      SGPIO_BMC_DOUT          
                                  M18      RST_SGPIO_RESET_N_R     
                                  N1       PWRGD_PVCCFA_EHV_FIVRA_CPU0
                                  N2       GND                     
                                  N3       PWRGD_PVCCINFAON_CPU0   
                                  N4       PWRGD_P1V05_PCH_AUX     
                                  N5       GND                     
                                  N6       P3V3_AUX                
                                  N7       SMB_S3M_CPU1_LVC1_SCL   
                                  N8       SMB_S3M_CPU1_LVC1_SDA   
                                  N9       PVCCIO_PLDIO5           
                                  N10      GND                     
                                  N11      PWRGD_DRAMPWRGD_CPU0_EF_R_LVC1
                                  N12      GND                     
                                  N13      PD_MAIN_FPGA_N13        
                                  N14      PWRGD_PS_PWROK_PLD_R    
                                  N15      PWRGD_PLT_AUX_CPU0_LVT3_R
                                  N16      PWRGD_PLT_AUX_CPU1_LVT3_R
                                  N17      GND                     
                                  N18      FM_PS_EN_PLD_R          
                                  P1       PWRGD_PVCCIN_CPU0       
                                  P2       PWRGD_PVNN_MAIN_CPU1    
                                  P3       PWRGD_PVPP_HBM_CPU0     
                                  P4       PWRGD_P1V8_PCH_AUX_PLD  
                                  P5       H_CPU1_PROCHOT_LVC1_R_N 
                                  P6       H_CPU1_THERMTRIP_LVC1_N 
                                  P7       PVCCIO_PLDIO5           
                                  P8       PVCCIO_PLDIO5           
                                  P9       PVCCIO_PLDIO5           
                                  P10      PWRGD_DRAMPWRGD_CPU0_AB_R_LVC1
                                  P11      PVCCIO_PLDIO2           
                                  P12      PVCCIO_PLDIO2           
                                  P13      PVCCA_AUX_PLD           
                                  P14      IRQ_SGPIO_INTR_N_R      
                                  P15      IRQ_BMC_PCH_NMI_R       
                                  P16      IRQ_TPM_SPI_N           
                                  P17      IRQ_PCH_SCI_WHEA_R_N    
                                  P18      IRQ_PSYS_CRIT_N         
                                  R1       PWRGD_PVCCIN_CPU1       
                                  R2       PWRGD_PVCCINFAON_CPU1   
                                  R3       PWRGD_PVNN_MAIN_CPU0    
                                  R4       PWRGD_CPU1_LVC1_R       
                                  R5       H_CPU_NMI_LVC1_R_N      
                                  R6       H_CPU0_PROCHOT_LVC1_R_N 
                                  R7       GND                     
                                  R8       SMB_S3M_CPU0_LVC1_SCL   
                                  R9       SMB_S3M_CPU0_LVC1_SDA   
                                  R10      RST_CPU1_DRAM_GH_PLD_N  
                                  R11      RST_PLD_CPU0_DRAM_CD_N  
                                  R12      RST_CPU0_DRAM_GH_PLD_N  
                                  R13      RST_CPU0_DRAM_CD_PLD_N  
                                  R14      RST_CPU1_DRAM_CD_PLD_N  
                                  R15      FM_CPU_RMCA_CATERR_LVT3_R_N
                                  R16      FM_CPU_RMCA_CATERR_DLY_LVT3_R_N
                                  R17      FM_ME_AUTHN_FAIL        
                                  R18      FM_ME_BT_DONE           
                                  T1       IRQ_SML0_ALERT_R_N      
                                  T2       IRQ_SML1_PMBUS_PLD_ALERT_N
                                  T3       PWRGD_PVNN_PCH_AUX      
                                  T4       FM_THERMTRIP_DLY_LVC1_R_N
                                  T5       H_CPU_CATERR_LVC1_R_N   
                                  T6       H_CPU_ERR0_LVC1_N       
                                  T7       H_CPU_RMCA_LVC1_R_N     
                                  T8       H_CPU0_MEMHOT_IN_LVC1_R_N
                                  T9       H_CPU0_MEMHOT_OUT_LVC1_N
                                  T10      H_CPU0_THERMTRIP_LVC1_N 
                                  T11      RST_PLD_CPU0_DRAM_AB_N  
                                  T12      RST_PLD_CPU0_DRAM_EF_N  
                                  T13      RST_CPU1_DRAM_AB_PLD_N  
                                  T14      RST_CPU0_DRAM_EF_PLD_N  
                                  T15      RST_CPU1_DRAM_EF_PLD_N  
                                  T16      FM_PFR_DSW_PWROK_N      
                                  T17      RST_PFR_OVR_RTC_R       
                                  T18      RST_PFR_OVR_SRTC_R      
                                  U2       PWRGD_P3V3              
                                  U3       PWRGD_CPU0_LVC1_R       
                                  U4       GND                     
                                  U5       PWRGD_S0_PWROK_CPU1_LVC1_R
                                  U6       RST_CPU0_LVC1_R_N       
                                  U7       PWRGD_CPUPWRGD_LVC1     
                                  U10      GND                     
                                  U11      PWRGD_S0_PWROK_CPU0_LVC1_R
                                  U12      RST_CPU0_DRAM_AB_PLD_N  
                                  U13      PWRGD_DRAMPWRGD_CPU1_EF_R_LVC1
                                  U14      GND                     
                                  U15      PWRGD_DRAMPWRGD_CPU1_AB_R_LVC1
                                  U16      RST_PLD_CPU1_DRAM_CD_N  
                                  U17      PWRGD_DRAMPWRGD_CPU1_CD_R_LVC1
                                  U18      FM_PCH_BMC_THERMTRIP_N  
                                  V1       GND                     
                                  V2       H_CPU_ERR1_LVC1_N       
                                  V3       H_CPU_ERR2_LVC1_N       
                                  V4       H_CPU0_MEMTRIP_LVC1_N   
                                  V5       H_CPU0_MON_FAIL_PLD_LVC1_N
                                  V6       H_CPU1_MEMHOT_IN_LVC1_R_N
                                  V7       H_CPU1_MEMHOT_OUT_LVC1_N
                                  V8       H_CPU1_MEMTRIP_LVC1_N   
                                  V13      RST_PLD_CPU0_DRAM_GH_N  
                                  V14      RST_PLD_CPU1_DRAM_EF_N  
                                  V15      RST_PLD_CPU1_DRAM_AB_N  
                                  V16      RST_PLD_CPU1_DRAM_GH_N  
                                  V17      PWRGD_DRAMPWRGD_CPU1_GH_R_LVC1
                                  V18      GND                     
U123             TPS259520DSGR-TPS259520DSGR,SMA 1        P3V3_E1S_2_DVDT         
                                  2        FM_P3V3_E1S_2_EN        
                                  3        P3V3_AUX                
                                  4        P3V3_AUX                
                                  5        P3V3_E1S_2              
                                  6        P3V3_E1S_2_FLT_N        
                                  7        P3V3_E1S_2_ILM          
                                  8        GND                     
                                  TH       GND                     
U124             TPS259520DSGR-TPS259520DSGR,SMA 1        P3V3_E1S_1_DVDT         
                                  2        FM_P3V3_E1S_1_EN        
                                  3        P3V3_AUX                
                                  4        P3V3_AUX                
                                  5        P3V3_E1S_1              
                                  6        P3V3_E1S_1_FLT_N        
                                  7        P3V3_E1S_1_ILM          
                                  8        GND                     
                                  TH       GND                     
U125             TPS259520DSGR-TPS259520DSGR,SMA 1        P3V3_E1S_3_DVDT         
                                  2        FM_P3V3_E1S_3_EN        
                                  3        P3V3_AUX                
                                  4        P3V3_AUX                
                                  5        P3V3_E1S_3              
                                  6        P3V3_E1S_3_FLT_N        
                                  7        P3V3_E1S_3_ILM          
                                  8        GND                     
                                  TH       GND                     
U126             TPS259540DSGR-TPS259540DSGR,SMA 1        P12V_E1S_0_DVDT         
                                  2        FM_P12V_E1S_0_EN        
                                  3        P12V_FRONT_CPU          
                                  4        P12V_FRONT_CPU          
                                  5        P12V_E1S_0              
                                  6        P12V_E1S_0_FLT_N        
                                  7        P12V_E1S_0_ILM          
                                  8        GND                     
                                  TH       GND                     
U127             TPS259540DSGR-TPS259540DSGR,SMA 1        P12V_E1S_2_DVDT         
                                  2        FM_P12V_E1S_2_EN        
                                  3        P12V_FRONT_CPU          
                                  4        P12V_FRONT_CPU          
                                  5        P12V_E1S_2              
                                  6        P12V_E1S_2_FLT_N        
                                  7        P12V_E1S_2_ILM          
                                  8        GND                     
                                  TH       GND                     
U128             TPS259540DSGR-TPS259540DSGR,SMA 1        P12V_E1S_1_DVDT         
                                  2        FM_P12V_E1S_1_EN        
                                  3        P12V_FRONT_CPU          
                                  4        P12V_FRONT_CPU          
                                  5        P12V_E1S_1              
                                  6        P12V_E1S_1_FLT_N        
                                  7        P12V_E1S_1_ILM          
                                  8        GND                     
                                  TH       GND                     
U129             TPS259540DSGR-TPS259540DSGR,SMA 1        P12V_E1S_3_DVDT         
                                  2        FM_P12V_E1S_3_EN        
                                  3        P12V_FRONT_CPU          
                                  4        P12V_FRONT_CPU          
                                  5        P12V_E1S_3              
                                  6        P12V_E1S_3_FLT_N        
                                  7        P12V_E1S_3_ILM          
                                  8        GND                     
                                  TH       GND                     
U130             PCA9555PW_SMLF-PCA9555PW,IC,TMA 2        PCA9555_1_ADD1          
                                  3        PCA9555_1_ADD2          
                                  5        E1S_0_PWR_FAIL_N        
                                  6        E1S_1_BUF_EN            
                                  8        E1S_0_BUF_PRSNT_N       
                                  12       GND                     
                                  14       E1S_1_PWR_FAIL_N        
                                  15       E1S_1_BUF_EN            
                                  17       E1S_1_BUF_PRSNT_N       
                                  21       PCA9555_1_ADD0          
                                  22       SMB_PEHPCPU0_LVC3_R1_SCL
                                  23       SMB_PEHPCPU0_LVC3_R1_SDA
                                  24       P3V3_AUX                
U131             PCA9555PW_SMLF-PCA9555PW,IC,TMA 2        PCA9555_2_ADD1          
                                  3        PCA9555_2_ADD2          
                                  5        E1S_2_PWR_FAIL_N        
                                  6        E1S_2_BUF_EN            
                                  8        E1S_2_BUF_PRSNT_N       
                                  12       GND                     
                                  14       E1S_3_PWR_FAIL_N        
                                  15       E1S_3_BUF_EN            
                                  17       E1S_3_BUF_PRSNT_N       
                                  21       PCA9555_2_ADD0          
                                  22       SMB_PEHPCPU0_LVC3_R2_SCL
                                  23       SMB_PEHPCPU0_LVC3_R2_SDA
                                  24       P3V3_AUX                
U132             SN74LVC2G17DCKR-SN74LVC2G17DCKA 1        E1S_0_PRSNT_N           
                                  2        GND                     
                                  3        E1S_1_PRSNT_N           
                                  4        E1S_1_BUF_PRSNT_R_N     
                                  5        P3V3_AUX                
                                  6        E1S_0_BUF_PRSNT_R_N     
U133             SN74LVC2G17DCKR-SN74LVC2G17DCKA 1        E1S_2_PRSNT_N           
                                  2        GND                     
                                  3        E1S_3_PRSNT_N           
                                  4        E1S_3_BUF_PRSNT_R_N     
                                  5        P3V3_AUX                
                                  6        E1S_2_BUF_PRSNT_R_N     
U134             SN74LVC2G07DCKR_SMLF-SN74LVC2GA 1        RST_PCIE_E1S_PERST_N    
                                  2        GND                     
                                  3        RST_PCIE_E1S_PERST_N    
                                  4        RST_PCIE_BUF_E1S_1_PERST_N
                                  5        P3V3_AUX                
                                  6        RST_PCIE_BUF_E1S_0_PERST_N
U135             SN74LVC2G07DCKR_SMLF-SN74LVC2GA 1        RST_PCIE_E1S_PERST_N    
                                  2        GND                     
                                  3        RST_PCIE_E1S_PERST_N    
                                  4        RST_PCIE_BUF_E1S_3_PERST_N
                                  5        P3V3_AUX                
                                  6        RST_PCIE_BUF_E1S_2_PERST_N
U136             SN74LVC2G07DCKR_SMLF-SN74LVC2GA 1        RST_SMB_E1S_N           
                                  2        GND                     
                                  3        RST_SMB_E1S_N           
                                  4        RST_SMB_BUF_E1S_1_N     
                                  5        P3V3_AUX                
                                  6        RST_SMB_BUF_E1S_0_N     
U137             SN74LVC2G07DCKR_SMLF-SN74LVC2GA 1        RST_SMB_E1S_N           
                                  2        GND                     
                                  3        RST_SMB_E1S_N           
                                  4        RST_SMB_BUF_E1S_3_N     
                                  5        P3V3_AUX                
                                  6        RST_SMB_BUF_E1S_2_N     
U138             TPS259540DSGR-TPS259540DSGR,SMA 1        P12V_SCM_DVDT           
                                  2        P12V_SCM_EN_N           
                                  3        P12V_AUX                
                                  4        P12V_AUX                
                                  5        P12V_SCM                
                                  6        P12V_SCM_FLT_N          
                                  7        P12V_SCM_ILM            
                                  8        GND                     
                                  TH       GND                     
U141             PCA9546APWR-PCA9546APWR,SMLF,IA 1        PCA9546_PCIE3_ADDR0     
                                  2        PCA9546_PCIE3_ADDR1     
                                  3        PU_RST_SMB_PCIE3_N      
                                  4        SMB_PCIE_3V3AUX_SDA_R4  
                                  5        SMB_PCIE_3V3AUX_SCL_R4  
                                  6        SMB_PCIE_3V3AUX_SDA_R3  
                                  7        SMB_PCIE_3V3AUX_SCL_R3  
                                  8        GND                     
                                  13       PCA9546_PCIE3_ADDR2     
                                  14       SMB_PCIE3_3V3AUX_SCL    
                                  15       SMB_PCIE3_3V3AUX_SDA    
                                  16       P3V3_AUX                
X1               TP_TDR_4P_FTS_TH-TP_TDR_4P_DIPA 1        TDR_DIFF_85_TOP_DP      
                                  2        T_GND                   
                                  3        T_GND                   
                                  4        TDR_DIFF_85_TOP_DN      
X2               TP_TDR_4P_FTS_TH-TP_TDR_4P_DIPA 1        TDR_DIFF_85_IN1_DP      
                                  2        T_GND                   
                                  3        T_GND                   
                                  4        TDR_DIFF_85_IN1_DN      
X3               TP_TDR_4P_FTS_TH-TP_TDR_4P_DIPA 1        TDR_DIFF_85_IN2_DP      
                                  2        T_GND                   
                                  3        T_GND                   
                                  4        TDR_DIFF_85_IN2_DN      
X4               TP_TDR_4P_FTS_TH-TP_TDR_4P_DIPA 1        TDR_DIFF_85_IN3_DP      
                                  2        T_GND                   
                                  3        T_GND                   
                                  4        TDR_DIFF_85_IN3_DN      
X5               TP_TDR_4P_FTS_TH-TP_TDR_4P_DIPA 1        TDR_DIFF_85_IN4_DP      
                                  2        T_GND                   
                                  3        T_GND                   
                                  4        TDR_DIFF_85_IN4_DN      
X6               TP_TDR_4P_FTS_TH-TP_TDR_4P_DIPA 1        TDR_DIFF_85_BOT_DP      
                                  2        T_GND                   
                                  3        T_GND                   
                                  4        TDR_DIFF_85_BOT_DN      
X7               TP_TDR_4P_FTS_TH-TP_TDR_4P_DIPA 1        TDR_DIFF_85_TOP_DN      
                                  2        T_GND                   
                                  3        T_GND                   
                                  4        TDR_DIFF_85_TOP_DP      
X8               TP_TDR_4P_FTS_TH-TP_TDR_4P_DIPA 1        TDR_DIFF_85_IN1_DN      
                                  2        T_GND                   
                                  3        T_GND                   
                                  4        TDR_DIFF_85_IN1_DP      
X9               TP_TDR_4P_FTS_TH-TP_TDR_4P_DIPA 1        TDR_DIFF_85_IN2_DN      
                                  2        T_GND                   
                                  3        T_GND                   
                                  4        TDR_DIFF_85_IN2_DP      
X10              TP_TDR_4P_FTS_TH-TP_TDR_4P_DIPA 1        TDR_DIFF_85_IN3_DN      
                                  2        T_GND                   
                                  3        T_GND                   
                                  4        TDR_DIFF_85_IN3_DP      
X11              TP_TDR_4P_FTS_TH-TP_TDR_4P_DIPA 1        TDR_DIFF_85_IN4_DN      
                                  2        T_GND                   
                                  3        T_GND                   
                                  4        TDR_DIFF_85_IN4_DP      
X12              TP_TDR_4P_FTS_TH-TP_TDR_4P_DIPA 1        TDR_DIFF_85_BOT_DN      
                                  2        T_GND                   
                                  3        T_GND                   
                                  4        TDR_DIFF_85_BOT_DP      
X13              TP_TDR_4P_FTS_TH-TP_TDR_4P_DIPA 1        TDR_DIFF_100_TOP_DP     
                                  2        T_GND                   
                                  3        T_GND                   
                                  4        TDR_DIFF_100_TOP_DN     
X14              TP_TDR_4P_FTS_TH-TP_TDR_4P_DIPA 1        TDR_DIFF_100_IN1_DP     
                                  2        T_GND                   
                                  3        T_GND                   
                                  4        TDR_DIFF_100_IN1_DN     
X15              TP_TDR_4P_FTS_TH-TP_TDR_4P_DIPA 1        TDR_DIFF_100_IN2_DP     
                                  2        T_GND                   
                                  3        T_GND                   
                                  4        TDR_DIFF_100_IN2_DN     
X16              TP_TDR_4P_FTS_TH-TP_TDR_4P_DIPA 1        TDR_DIFF_100_IN3_DP     
                                  2        T_GND                   
                                  3        T_GND                   
                                  4        TDR_DIFF_100_IN3_DN     
X17              TP_TDR_4P_FTS_TH-TP_TDR_4P_DIPA 1        TDR_DIFF_100_IN4_DP     
                                  2        T_GND                   
                                  3        T_GND                   
                                  4        TDR_DIFF_100_IN4_DN     
X18              TP_TDR_4P_FTS_TH-TP_TDR_4P_DIPA 1        TDR_DIFF_100_BOT_DP     
                                  2        T_GND                   
                                  3        T_GND                   
                                  4        TDR_DIFF_100_BOT_DN     
X19              TP_TDR_4P_FTS_TH-TP_TDR_4P_DIPA 1        TDR_DIFF_100_TOP_DN     
                                  2        T_GND                   
                                  3        T_GND                   
                                  4        TDR_DIFF_100_TOP_DP     
X20              TP_TDR_4P_FTS_TH-TP_TDR_4P_DIPA 1        TDR_DIFF_100_IN1_DN     
                                  2        T_GND                   
                                  3        T_GND                   
                                  4        TDR_DIFF_100_IN1_DP     
X21              TP_TDR_4P_FTS_TH-TP_TDR_4P_DIPA 1        TDR_DIFF_100_IN2_DN     
                                  2        T_GND                   
                                  3        T_GND                   
                                  4        TDR_DIFF_100_IN2_DP     
X22              TP_TDR_4P_FTS_TH-TP_TDR_4P_DIPA 1        TDR_DIFF_100_IN3_DN     
                                  2        T_GND                   
                                  3        T_GND                   
                                  4        TDR_DIFF_100_IN3_DP     
X23              TP_TDR_4P_FTS_TH-TP_TDR_4P_DIPA 1        TDR_DIFF_100_IN4_DN     
                                  2        T_GND                   
                                  3        T_GND                   
                                  4        TDR_DIFF_100_IN4_DP     
X24              TP_TDR_4P_FTS_TH-TP_TDR_4P_DIPA 1        TDR_DIFF_100_BOT_DN     
                                  2        T_GND                   
                                  3        T_GND                   
                                  4        TDR_DIFF_100_BOT_DP     
Y1               Q_CRYSTAL_SMLF-32.768KHZ,IC,BGA 1        XTAL_PCH_RTC2_R         
                                  2        XTAL_PCH_RTC1           
Y2               Q_XTAL_4P_13_SMLF-25MHZ,IC,BG6A 1        XTAL_CLK_GEN1_25M_X1_R  
                                  2        GND                     
                                  3        XTAL_CLK_GEN1_25M_X2    
                                  4        GND                     
Y3               Q_XTAL_4P_13BI_24GND-25MHZ,SMLA 1        XTAL_PCH_25M_IN_R       
                                  2        GND                     
                                  3        XTAL_PCH_25M_OUT        
                                  4        GND                     
END BODY ORDERED NET LIST
